G04 ================== begin FILE IDENTIFICATION RECORD ==================*
G04 Layout Name:  9127_F0T_Expander_BD_F_v02_0110_1240.brd*
G04 Film Name:    gnd2*
G04 File Format:  Gerber RS274X*
G04 File Origin:  Cadence Allegro 17.2-S081*
G04 Origin Date:  Wed Jan 11 16:06:28 2023*
G04 *
G04 Layer:  VIA CLASS/GND2*
G04 Layer:  PIN/GND2*
G04 Layer:  ETCH/GND2*
G04 Layer:  DRAWING FORMAT/TITLE_BLOCK_A*
G04 Layer:  PIN/SPECIAL_DRILL*
G04 Layer:  MANUFACTURING/PHOTOPLOT_OUTLINE*
G04 Layer:  DRAWING FORMAT/TITLE_BLOCK*
G04 Layer:  DRAWING FORMAT/TITLE_DATA_GND2*
G04 *
G04 Offset:    (0.00 0.00)*
G04 Mirror:    No*
G04 Mode:      Negative*
G04 Rotation:  0*
G04 FullContactRelief:  No*
G04 UndefLineWidth:     6.00*
G04 ================== end FILE IDENTIFICATION RECORD ====================*
%FSLAX25Y25*MOIN*%
%IR0*IPPOS*OFA0.00000B0.00000*MIA0B0*SFA1.00000B1.00000*%
%ADD15C,.03*%
%ADD53C,.06*%
%ADD22C,.024*%
%ADD54C,.061*%
%ADD32C,.0322*%
%ADD45C,.071*%
%AMMACRO28*
4,1,36,0.0,.01,
-.001736,.009848,
-.00342,.009397,
-.005,.00866,
-.006428,.00766,
-.00766,.006428,
-.00866,.005,
-.009397,.00342,
-.009848,.001736,
-.01,0.0,
-.009848,-.001736,
-.009397,-.00342,
-.00866,-.005,
-.00766,-.006428,
-.006428,-.00766,
-.005,-.00866,
-.00342,-.009397,
-.001736,-.009848,
0.0,-.01,
.001736,-.009848,
.00342,-.009397,
.005,-.00866,
.006428,-.00766,
.00766,-.006428,
.00866,-.005,
.009397,-.00342,
.009848,-.001736,
.01,0.0,
.009848,.001736,
.009397,.00342,
.00866,.005,
.00766,.006428,
.006428,.00766,
.005,.00866,
.00342,.009397,
.001736,.009848,
0.0,.01,
0.0*
%
%ADD28MACRO28*%
%ADD27C,.026*%
%ADD51C,.082*%
%ADD43C,.028*%
%AMMACRO38*
4,1,20,-.0075,-.05555,
-.0075,-.06273,
-.013677,-.060878,
-.019439,-.057981,
-.024611,-.054127,
-.029034,-.049434,
-.032576,-.044045,
-.035127,-.038122,
-.036612,-.031846,
-.037,-.0265,
-.037,-.0075,
-.03,-.0075,
-.03,-.0265,
-.029544,-.03171,
-.028191,-.036762,
-.02598,-.041502,
-.022981,-.045786,
-.019282,-.049484,
-.014998,-.052484,
-.010258,-.054694,
-.0075,-.05555,
270.*
4,1,20,.0075,-.06273,
.0075,-.05555,
.01243,-.053806,
.016983,-.051232,
.02102,-.047906,
.024418,-.043931,
.027073,-.039425,
.028906,-.034527,
.029861,-.029385,
.03,-.0265,
.03,-.0075,
.037,-.0075,
.037,-.0265,
.036438,-.032925,
.034769,-.039154,
.032043,-.044999,
.028344,-.050282,
.023784,-.054842,
.018501,-.058541,
.012656,-.061266,
.0075,-.06273,
270.*
4,1,20,-.0075,.06273,
-.0075,.05555,
-.01243,.053806,
-.016983,.051232,
-.02102,.047906,
-.024418,.043931,
-.027073,.039425,
-.028906,.034527,
-.029861,.029385,
-.03,.0265,
-.03,.0075,
-.037,.0075,
-.037,.0265,
-.036438,.032925,
-.034769,.039154,
-.032043,.044999,
-.028344,.050282,
-.023784,.054842,
-.018501,.058541,
-.012656,.061266,
-.0075,.06273,
270.*
4,1,20,.0075,.05555,
.0075,.06273,
.013677,.060878,
.019439,.057981,
.024611,.054127,
.029034,.049434,
.032576,.044045,
.035127,.038122,
.036612,.031846,
.037,.0265,
.037,.0075,
.03,.0075,
.03,.0265,
.029544,.03171,
.028191,.036762,
.02598,.041502,
.022981,.045786,
.019282,.049484,
.014998,.052484,
.010258,.054694,
.0075,.05555,
270.*
%
%ADD38MACRO38*%
%AMMACRO30*
4,1,36,.0025,0.0,
.002462,.000434,
.002349,.000855,
.002165,.00125,
.001915,.001607,
.001607,.001915,
.00125,.002165,
.000855,.002349,
.000434,.002462,
0.0,.0025,
-.000434,.002462,
-.000855,.002349,
-.00125,.002165,
-.001607,.001915,
-.001915,.001607,
-.002165,.00125,
-.002349,.000855,
-.002462,.000434,
-.0025,0.0,
-.002462,-.000434,
-.002349,-.000855,
-.002165,-.00125,
-.001915,-.001607,
-.001607,-.001915,
-.00125,-.002165,
-.000855,-.002349,
-.000434,-.002462,
0.0,-.0025,
.000434,-.002462,
.000855,-.002349,
.00125,-.002165,
.001607,-.001915,
.001915,-.001607,
.002165,-.00125,
.002349,-.000855,
.002462,-.000434,
.0025,0.0,
315.*
%
%ADD30MACRO30*%
%AMMACRO14*
4,1,36,.0025,0.0,
.002462,.000434,
.002349,.000855,
.002165,.00125,
.001915,.001607,
.001607,.001915,
.00125,.002165,
.000855,.002349,
.000434,.002462,
0.0,.0025,
-.000434,.002462,
-.000855,.002349,
-.00125,.002165,
-.001607,.001915,
-.001915,.001607,
-.002165,.00125,
-.002349,.000855,
-.002462,.000434,
-.0025,0.0,
-.002462,-.000434,
-.002349,-.000855,
-.002165,-.00125,
-.001915,-.001607,
-.001607,-.001915,
-.00125,-.002165,
-.000855,-.002349,
-.000434,-.002462,
0.0,-.0025,
.000434,-.002462,
.000855,-.002349,
.00125,-.002165,
.001607,-.001915,
.001915,-.001607,
.002165,-.00125,
.002349,-.000855,
.002462,-.000434,
.0025,0.0,
180.*
%
%ADD14MACRO14*%
%AMMACRO10*
4,1,36,.0025,0.0,
.002462,.000434,
.002349,.000855,
.002165,.00125,
.001915,.001607,
.001607,.001915,
.00125,.002165,
.000855,.002349,
.000434,.002462,
0.0,.0025,
-.000434,.002462,
-.000855,.002349,
-.00125,.002165,
-.001607,.001915,
-.001915,.001607,
-.002165,.00125,
-.002349,.000855,
-.002462,.000434,
-.0025,0.0,
-.002462,-.000434,
-.002349,-.000855,
-.002165,-.00125,
-.001915,-.001607,
-.001607,-.001915,
-.00125,-.002165,
-.000855,-.002349,
-.000434,-.002462,
0.0,-.0025,
.000434,-.002462,
.000855,-.002349,
.00125,-.002165,
.001607,-.001915,
.001915,-.001607,
.002165,-.00125,
.002349,-.000855,
.002462,-.000434,
.0025,0.0,
270.*
%
%ADD10MACRO10*%
%AMMACRO46*
4,1,36,-.0025,0.0,
-.002462,.000434,
-.002349,.000855,
-.002165,.00125,
-.001915,.001607,
-.001607,.001915,
-.00125,.002165,
-.000855,.002349,
-.000434,.002462,
0.0,.0025,
.000434,.002462,
.000855,.002349,
.00125,.002165,
.001607,.001915,
.001915,.001607,
.002165,.00125,
.002349,.000855,
.002462,.000434,
.0025,0.0,
.002462,-.000434,
.002349,-.000855,
.002165,-.00125,
.001915,-.001607,
.001607,-.001915,
.00125,-.002165,
.000855,-.002349,
.000434,-.002462,
0.0,-.0025,
-.000434,-.002462,
-.000855,-.002349,
-.00125,-.002165,
-.001607,-.001915,
-.001915,-.001607,
-.002165,-.00125,
-.002349,-.000855,
-.002462,-.000434,
-.0025,0.0,
180.*
%
%ADD46MACRO46*%
%AMMACRO36*
4,1,36,.003,0.0,
.002954,.000521,
.002819,.001026,
.002598,.0015,
.002298,.001928,
.001928,.002298,
.0015,.002598,
.001026,.002819,
.000521,.002954,
0.0,.003,
-.000521,.002954,
-.001026,.002819,
-.0015,.002598,
-.001928,.002298,
-.002298,.001928,
-.002598,.0015,
-.002819,.001026,
-.002954,.000521,
-.003,0.0,
-.002954,-.000521,
-.002819,-.001026,
-.002598,-.0015,
-.002298,-.001928,
-.001928,-.002298,
-.0015,-.002598,
-.001026,-.002819,
-.000521,-.002954,
0.0,-.003,
.000521,-.002954,
.001026,-.002819,
.0015,-.002598,
.001928,-.002298,
.002298,-.001928,
.002598,-.0015,
.002819,-.001026,
.002954,-.000521,
.003,0.0,
270.*
%
%ADD36MACRO36*%
%AMMACRO24*
4,1,36,.003,0.0,
.002954,.000521,
.002819,.001026,
.002598,.0015,
.002298,.001928,
.001928,.002298,
.0015,.002598,
.001026,.002819,
.000521,.002954,
0.0,.003,
-.000521,.002954,
-.001026,.002819,
-.0015,.002598,
-.001928,.002298,
-.002298,.001928,
-.002598,.0015,
-.002819,.001026,
-.002954,.000521,
-.003,0.0,
-.002954,-.000521,
-.002819,-.001026,
-.002598,-.0015,
-.002298,-.001928,
-.001928,-.002298,
-.0015,-.002598,
-.001026,-.002819,
-.000521,-.002954,
0.0,-.003,
.000521,-.002954,
.001026,-.002819,
.0015,-.002598,
.001928,-.002298,
.002298,-.001928,
.002598,-.0015,
.002819,-.001026,
.002954,-.000521,
.003,0.0,
180.*
%
%ADD24MACRO24*%
%ADD21C,.074*%
%AMMACRO42*
4,1,36,-.003,0.0,
-.002954,.000521,
-.002819,.001026,
-.002598,.0015,
-.002298,.001928,
-.001928,.002298,
-.0015,.002598,
-.001026,.002819,
-.000521,.002954,
0.0,.003,
.000521,.002954,
.001026,.002819,
.0015,.002598,
.001928,.002298,
.002298,.001928,
.002598,.0015,
.002819,.001026,
.002954,.000521,
.003,0.0,
.002954,-.000521,
.002819,-.001026,
.002598,-.0015,
.002298,-.001928,
.001928,-.002298,
.0015,-.002598,
.001026,-.002819,
.000521,-.002954,
0.0,-.003,
-.000521,-.002954,
-.001026,-.002819,
-.0015,-.002598,
-.001928,-.002298,
-.002298,-.001928,
-.002598,-.0015,
-.002819,-.001026,
-.002954,-.000521,
-.003,0.0,
180.*
%
%ADD42MACRO42*%
%ADD25C,.0435*%
%ADD34C,.0257*%
%ADD58C,.087*%
%ADD39C,.0277*%
%AMMACRO44*
4,1,18,.09673,.06845,
.107147,.050613,
.114308,.031238,
.117996,.010914,
.118098,-.009741,
.114613,-.030101,
.107644,-.049546,
.097406,-.067485,
.09673,-.06845,
.10175,-.07347,
.112962,-.054685,
.120742,-.034239,
.124853,-.012752,
.125171,.009122,
.121685,.030719,
.114502,.051383,
.10384,.070486,
.10175,.07347,
.09673,.06845,
90.*
4,1,18,.06845,-.09673,
.050613,-.107147,
.031238,-.114308,
.010914,-.117996,
-.009741,-.118098,
-.030101,-.114613,
-.049546,-.107644,
-.067485,-.097406,
-.06845,-.09673,
-.07347,-.10175,
-.054685,-.112962,
-.034239,-.120742,
-.012752,-.124853,
.009122,-.125171,
.030719,-.121685,
.051383,-.114502,
.070486,-.10384,
.07347,-.10175,
.06845,-.09673,
90.*
4,1,18,-.09673,-.06845,
-.107147,-.050613,
-.114308,-.031238,
-.117996,-.010914,
-.118098,.009741,
-.114613,.030101,
-.107644,.049546,
-.097406,.067485,
-.09673,.06845,
-.10175,.07347,
-.112962,.054685,
-.120742,.034239,
-.124853,.012752,
-.125171,-.009122,
-.121685,-.030719,
-.114502,-.051383,
-.10384,-.070486,
-.10175,-.07347,
-.09673,-.06845,
90.*
4,1,18,-.06845,.09673,
-.050613,.107147,
-.031238,.114308,
-.010914,.117996,
.009741,.118098,
.030101,.114613,
.049546,.107644,
.067485,.097406,
.06845,.09673,
.07347,.10175,
.054685,.112962,
.034239,.120742,
.012752,.124853,
-.009122,.125171,
-.030719,.121685,
-.051383,.114502,
-.070486,.10384,
-.07347,.10175,
-.06845,.09673,
90.*
%
%ADD44MACRO44*%
%AMMACRO11*
4,1,15,.06231,.03403,
.067273,.022693,
.070191,.010666,
.070977,-.001684,
.069606,-.013984,
.066121,-.025858,
.06231,-.03403,
.06745,-.03917,
.073227,-.026862,
.076779,-.013739,
.077998,-.000197,
.076848,.01335,
.073362,.026492,
.067647,.038828,
.06745,.03917,
.06231,.03403,
0.0*
4,1,15,.03403,-.06231,
.022693,-.067273,
.010666,-.070191,
-.001684,-.070977,
-.013984,-.069606,
-.025858,-.066121,
-.03403,-.06231,
-.03917,-.06745,
-.026862,-.073227,
-.013739,-.076779,
-.000197,-.077998,
.01335,-.076848,
.026492,-.073362,
.038828,-.067647,
.03917,-.06745,
.03403,-.06231,
0.0*
4,1,15,-.06231,-.03403,
-.067273,-.022693,
-.070191,-.010666,
-.070977,.001684,
-.069606,.013984,
-.066121,.025858,
-.06231,.03403,
-.06745,.03917,
-.073227,.026862,
-.076779,.013739,
-.077998,.000197,
-.076848,-.01335,
-.073362,-.026492,
-.067647,-.038828,
-.06745,-.03917,
-.06231,-.03403,
0.0*
4,1,15,-.03403,.06231,
-.022693,.067273,
-.010666,.070191,
.001684,.070977,
.013984,.069606,
.025858,.066121,
.03403,.06231,
.03917,.06745,
.026862,.073227,
.013739,.076779,
.000197,.077998,
-.01335,.076848,
-.026492,.073362,
-.038828,.067647,
-.03917,.06745,
-.03403,.06231,
0.0*
%
%ADD11MACRO11*%
%ADD19C,.099*%
%AMMACRO18*
4,1,18,.09673,.06845,
.107147,.050613,
.114308,.031238,
.117996,.010914,
.118098,-.009741,
.114613,-.030101,
.107644,-.049546,
.097406,-.067485,
.09673,-.06845,
.10175,-.07347,
.112962,-.054685,
.120742,-.034239,
.124853,-.012752,
.125171,.009122,
.121685,.030719,
.114502,.051383,
.10384,.070486,
.10175,.07347,
.09673,.06845,
0.0*
4,1,18,.06845,-.09673,
.050613,-.107147,
.031238,-.114308,
.010914,-.117996,
-.009741,-.118098,
-.030101,-.114613,
-.049546,-.107644,
-.067485,-.097406,
-.06845,-.09673,
-.07347,-.10175,
-.054685,-.112962,
-.034239,-.120742,
-.012752,-.124853,
.009122,-.125171,
.030719,-.121685,
.051383,-.114502,
.070486,-.10384,
.07347,-.10175,
.06845,-.09673,
0.0*
4,1,18,-.09673,-.06845,
-.107147,-.050613,
-.114308,-.031238,
-.117996,-.010914,
-.118098,.009741,
-.114613,.030101,
-.107644,.049546,
-.097406,.067485,
-.09673,.06845,
-.10175,.07347,
-.112962,.054685,
-.120742,.034239,
-.124853,.012752,
-.125171,-.009122,
-.121685,-.030719,
-.114502,-.051383,
-.10384,-.070486,
-.10175,-.07347,
-.09673,-.06845,
0.0*
4,1,18,-.06845,.09673,
-.050613,.107147,
-.031238,.114308,
-.010914,.117996,
.009741,.118098,
.030101,.114613,
.049546,.107644,
.067485,.097406,
.06845,.09673,
.07347,.10175,
.054685,.112962,
.034239,.120742,
.012752,.124853,
-.009122,.125171,
-.030719,.121685,
-.051383,.114502,
-.070486,.10384,
-.07347,.10175,
-.06845,.09673,
0.0*
%
%ADD18MACRO18*%
%ADD33C,.0299*%
%AMMACRO61*
4,1,19,-.0075,-.03785,
-.011528,-.036185,
-.015205,-.033846,
-.01842,-.030904,
-.021075,-.027448,
-.02309,-.023584,
-.024404,-.019428,
-.024975,-.015108,
-.025,-.014,
-.025,-.0075,
-.018,-.0075,
-.018,-.014,
-.017727,-.017125,
-.016915,-.020155,
-.015589,-.022998,
-.01379,-.025567,
-.011572,-.027785,
-.009002,-.029584,
-.0075,-.03036,
-.0075,-.03785,
180.*
4,1,19,.0075,-.03785,
.0075,-.03036,
.010227,-.02881,
.012643,-.02681,
.014676,-.024421,
.016262,-.021715,
.017355,-.018774,
.017921,-.015689,
.018,-.014,
.018,-.0075,
.025,-.0075,
.025,-.014,
.02462,-.018342,
.023492,-.022551,
.02165,-.026501,
.019151,-.030071,
.016069,-.033153,
.012499,-.035652,
.008549,-.037494,
.0075,-.03785,
180.*
4,1,19,-.025,.0075,
-.025,.014,
-.02462,.018342,
-.023492,.022551,
-.02165,.026501,
-.019151,.030071,
-.016069,.033153,
-.012499,.035652,
-.008549,.037494,
-.0075,.03785,
-.0075,.03036,
-.010227,.02881,
-.012643,.02681,
-.014676,.024421,
-.016262,.021715,
-.017355,.018774,
-.017921,.015689,
-.018,.014,
-.018,.0075,
-.025,.0075,
180.*
4,1,19,.018,.0075,
.018,.014,
.017727,.017125,
.016915,.020155,
.015589,.022998,
.01379,.025567,
.011572,.027785,
.009002,.029584,
.0075,.03036,
.0075,.03785,
.011528,.036185,
.015205,.033846,
.01842,.030904,
.021075,.027448,
.02309,.023584,
.024404,.019428,
.024975,.015108,
.025,.014,
.025,.0075,
.018,.0075,
180.*
%
%ADD61MACRO61*%
%AMMACRO37*
4,1,16,.02584,.01524,
.028094,.010521,
.029494,.005483,
.029998,.000278,
.029591,-.004935,
.028284,-.009999,
.026118,-.014758,
.02584,-.01524,
.03092,-.02032,
.033979,-.014642,
.036005,-.008519,
.036938,-.002138,
.036748,.004309,
.035441,.010625,
.033058,.016618,
.03092,.02032,
.02584,.01524,
0.0*
4,1,16,.01524,-.02584,
.010521,-.028094,
.005483,-.029494,
.000278,-.029998,
-.004935,-.029591,
-.009999,-.028284,
-.014758,-.026118,
-.01524,-.02584,
-.02032,-.03092,
-.014642,-.033979,
-.008519,-.036005,
-.002138,-.036938,
.004309,-.036748,
.010625,-.035441,
.016618,-.033058,
.02032,-.03092,
.01524,-.02584,
0.0*
4,1,16,-.02584,-.01524,
-.028094,-.010521,
-.029494,-.005483,
-.029998,-.000278,
-.029591,.004935,
-.028284,.009999,
-.026118,.014758,
-.02584,.01524,
-.03092,.02032,
-.033979,.014642,
-.036005,.008519,
-.036938,.002138,
-.036748,-.004309,
-.035441,-.010625,
-.033058,-.016618,
-.03092,-.02032,
-.02584,-.01524,
0.0*
4,1,16,-.01524,.02584,
-.010521,.028094,
-.005483,.029494,
-.000278,.029998,
.004935,.029591,
.009999,.028284,
.014758,.026118,
.01524,.02584,
.02032,.03092,
.014642,.033979,
.008519,.036005,
.002138,.036938,
-.004309,.036748,
-.010625,.035441,
-.016618,.033058,
-.02032,.03092,
-.01524,.02584,
0.0*
%
%ADD37MACRO37*%
%AMMACRO50*
4,1,15,.02142,.01082,
.022973,.006936,
.023829,.002841,
.02396,-.00134,
.023364,-.00548,
.022057,-.009454,
.02142,-.01082,
.02657,-.01597,
.02894,-.011114,
.03043,-.005919,
.030995,-.000545,
.030619,.004845,
.029313,.010088,
.027115,.015025,
.02657,.01597,
.02142,.01082,
90.*
4,1,15,.01082,-.02142,
.006936,-.022973,
.002841,-.023829,
-.00134,-.02396,
-.00548,-.023364,
-.009454,-.022057,
-.01082,-.02142,
-.01597,-.02657,
-.011114,-.02894,
-.005919,-.03043,
-.000545,-.030995,
.004845,-.030619,
.010088,-.029313,
.015025,-.027115,
.01597,-.02657,
.01082,-.02142,
90.*
4,1,15,-.02142,-.01082,
-.022973,-.006936,
-.023829,-.002841,
-.02396,.00134,
-.023364,.00548,
-.022057,.009454,
-.02142,.01082,
-.02657,.01597,
-.02894,.011114,
-.03043,.005919,
-.030995,.000545,
-.030619,-.004845,
-.029313,-.010088,
-.027115,-.015025,
-.02657,-.01597,
-.02142,-.01082,
90.*
4,1,15,-.01082,.02142,
-.006936,.022973,
-.002841,.023829,
.00134,.02396,
.00548,.023364,
.009454,.022057,
.01082,.02142,
.01597,.02657,
.011114,.02894,
.005919,.03043,
.000545,.030995,
-.004845,.030619,
-.010088,.029313,
-.015025,.027115,
-.01597,.02657,
-.01082,.02142,
90.*
%
%ADD50MACRO50*%
%AMMACRO48*
4,1,18,.07103,.05689,
.07983,.043691,
.086204,.029165,
.089959,.013753,
.09098,-.002077,
.089237,-.017844,
.084783,-.033069,
.077753,-.047289,
.07103,-.05689,
.07601,-.06186,
.085597,-.047721,
.092583,-.032132,
.096757,-.015567,
.09799,.001471,
.096246,.018464,
.091577,.034897,
.084126,.050269,
.07601,.06186,
.07103,.05689,
90.*
4,1,18,.05689,-.07103,
.043691,-.07983,
.029165,-.086204,
.013753,-.089959,
-.002077,-.09098,
-.017844,-.089237,
-.033069,-.084783,
-.047289,-.077753,
-.05689,-.07103,
-.06186,-.07601,
-.047721,-.085597,
-.032132,-.092583,
-.015567,-.096757,
.001471,-.09799,
.018464,-.096246,
.034897,-.091577,
.050269,-.084126,
.06186,-.07601,
.05689,-.07103,
90.*
4,1,18,-.07103,-.05689,
-.07983,-.043691,
-.086204,-.029165,
-.089959,-.013753,
-.09098,.002077,
-.089237,.017844,
-.084783,.033069,
-.077753,.047289,
-.07103,.05689,
-.07601,.06186,
-.085597,.047721,
-.092583,.032132,
-.096757,.015567,
-.09799,-.001471,
-.096246,-.018464,
-.091577,-.034897,
-.084126,-.050269,
-.07601,-.06186,
-.07103,-.05689,
90.*
4,1,18,-.05689,.07103,
-.043691,.07983,
-.029165,.086204,
-.013753,.089959,
.002077,.09098,
.017844,.089237,
.033069,.084783,
.047289,.077753,
.05689,.07103,
.06186,.07601,
.047721,.085597,
.032132,.092583,
.015567,.096757,
-.001471,.09799,
-.018464,.096246,
-.034897,.091577,
-.050269,.084126,
-.06186,.07601,
-.05689,.07103,
90.*
%
%ADD48MACRO48*%
%AMMACRO62*
4,1,19,-.0075,-.04535,
-.011528,-.043685,
-.015205,-.041346,
-.01842,-.038404,
-.021075,-.034948,
-.02309,-.031084,
-.024404,-.026928,
-.024975,-.022608,
-.025,-.0215,
-.025,-.0075,
-.018,-.0075,
-.018,-.0215,
-.017727,-.024625,
-.016915,-.027655,
-.015589,-.030498,
-.01379,-.033067,
-.011572,-.035285,
-.009002,-.037084,
-.0075,-.03786,
-.0075,-.04535,
180.*
4,1,19,.0075,-.04535,
.0075,-.03786,
.010227,-.03631,
.012643,-.03431,
.014676,-.031921,
.016262,-.029215,
.017355,-.026274,
.017921,-.023189,
.018,-.0215,
.018,-.0075,
.025,-.0075,
.025,-.0215,
.02462,-.025842,
.023492,-.030051,
.02165,-.034001,
.019151,-.037571,
.016069,-.040653,
.012499,-.043152,
.008549,-.044994,
.0075,-.04535,
180.*
4,1,19,-.025,.0075,
-.025,.0215,
-.02462,.025842,
-.023492,.030051,
-.02165,.034001,
-.019151,.037571,
-.016069,.040653,
-.012499,.043152,
-.008549,.044994,
-.0075,.04535,
-.0075,.03786,
-.010227,.03631,
-.012643,.03431,
-.014676,.031921,
-.016262,.029215,
-.017355,.026274,
-.017921,.023189,
-.018,.0215,
-.018,.0075,
-.025,.0075,
180.*
4,1,19,.018,.0075,
.018,.0215,
.017727,.024625,
.016915,.027655,
.015589,.030498,
.01379,.033067,
.011572,.035285,
.009002,.037084,
.0075,.03786,
.0075,.04535,
.011528,.043685,
.015205,.041346,
.01842,.038404,
.021075,.034948,
.02309,.031084,
.024404,.026928,
.024975,.022608,
.025,.0215,
.025,.0075,
.018,.0075,
180.*
%
%ADD62MACRO62*%
%AMMACRO55*
4,1,15,.02475,.01414,
.026829,.009627,
.028094,.004822,
.028504,-.000129,
.028049,-.005077,
.026741,-.009871,
.02475,-.01414,
.02984,-.01923,
.032726,-.013756,
.034617,-.007864,
.035457,-.001734,
.03522,.00445,
.033912,.010498,
.031574,.016227,
.02984,.01923,
.02475,.01414,
0.0*
4,1,15,.01414,-.02475,
.009627,-.026829,
.004822,-.028094,
-.000129,-.028504,
-.005077,-.028049,
-.009871,-.026741,
-.01414,-.02475,
-.01923,-.02984,
-.013756,-.032726,
-.007864,-.034617,
-.001734,-.035457,
.00445,-.03522,
.010498,-.033912,
.016227,-.031574,
.01923,-.02984,
.01414,-.02475,
0.0*
4,1,15,-.02475,-.01414,
-.026829,-.009627,
-.028094,-.004822,
-.028504,.000129,
-.028049,.005077,
-.026741,.009871,
-.02475,.01414,
-.02984,.01923,
-.032726,.013756,
-.034617,.007864,
-.035457,.001734,
-.03522,-.00445,
-.033912,-.010498,
-.031574,-.016227,
-.02984,-.01923,
-.02475,-.01414,
0.0*
4,1,15,-.01414,.02475,
-.009627,.026829,
-.004822,.028094,
.000129,.028504,
.005077,.028049,
.009871,.026741,
.01414,.02475,
.01923,.02984,
.013756,.032726,
.007864,.034617,
.001734,.035457,
-.00445,.03522,
-.010498,.033912,
-.016227,.031574,
-.01923,.02984,
-.01414,.02475,
0.0*
%
%ADD55MACRO55*%
%AMMACRO59*
4,1,15,.03682,.01914,
.039584,.012455,
.041146,.005393,
.041457,-.001834,
.040509,-.009005,
.03833,-.015903,
.03682,-.01914,
.04197,-.0243,
.045552,-.016643,
.04775,-.00848,
.048497,-.000059,
.047771,.008363,
.045593,.016531,
.042029,.024197,
.04197,.0243,
.03682,.01914,
90.*
4,1,15,.01914,-.03682,
.012455,-.039584,
.005393,-.041146,
-.001834,-.041457,
-.009005,-.040509,
-.015903,-.03833,
-.01914,-.03682,
-.0243,-.04197,
-.016643,-.045552,
-.00848,-.04775,
-.000059,-.048497,
.008363,-.047771,
.016531,-.045593,
.024197,-.042029,
.0243,-.04197,
.01914,-.03682,
90.*
4,1,15,-.03682,-.01914,
-.039584,-.012455,
-.041146,-.005393,
-.041457,.001834,
-.040509,.009005,
-.03833,.015903,
-.03682,.01914,
-.04197,.0243,
-.045552,.016643,
-.04775,.00848,
-.048497,.000059,
-.047771,-.008363,
-.045593,-.016531,
-.042029,-.024197,
-.04197,-.0243,
-.03682,-.01914,
90.*
4,1,15,-.01914,.03682,
-.012455,.039584,
-.005393,.041146,
.001834,.041457,
.009005,.040509,
.015903,.03833,
.01914,.03682,
.0243,.04197,
.016643,.045552,
.00848,.04775,
.000059,.048497,
-.008363,.047771,
-.016531,.045593,
-.024197,.042029,
-.0243,.04197,
-.01914,.03682,
90.*
%
%ADD59MACRO59*%
%AMMACRO60*
4,1,15,-.03682,.01914,
-.039584,.012455,
-.041146,.005393,
-.041457,-.001834,
-.040509,-.009005,
-.03833,-.015903,
-.03682,-.01914,
-.04197,-.0243,
-.045552,-.016643,
-.04775,-.00848,
-.048497,-.000059,
-.047771,.008363,
-.045593,.016531,
-.042029,.024197,
-.04197,.0243,
-.03682,.01914,
90.*
4,1,15,-.01914,-.03682,
-.012455,-.039584,
-.005393,-.041146,
.001834,-.041457,
.009005,-.040509,
.015903,-.03833,
.01914,-.03682,
.0243,-.04197,
.016643,-.045552,
.00848,-.04775,
.000059,-.048497,
-.008363,-.047771,
-.016531,-.045593,
-.024197,-.042029,
-.0243,-.04197,
-.01914,-.03682,
90.*
4,1,15,.03682,-.01914,
.039584,-.012455,
.041146,-.005393,
.041457,.001834,
.040509,.009005,
.03833,.015903,
.03682,.01914,
.04197,.0243,
.045552,.016643,
.04775,.00848,
.048497,.000059,
.047771,-.008363,
.045593,-.016531,
.042029,-.024197,
.04197,-.0243,
.03682,-.01914,
90.*
4,1,15,.01914,.03682,
.012455,.039584,
.005393,.041146,
-.001834,.041457,
-.009005,.040509,
-.015903,.03833,
-.01914,.03682,
-.0243,.04197,
-.016643,.045552,
-.00848,.04775,
-.000059,.048497,
.008363,.047771,
.016531,.045593,
.024197,.042029,
.0243,.04197,
.01914,.03682,
90.*
%
%ADD60MACRO60*%
%ADD63C,.142*%
%ADD13C,.125*%
%ADD29C,.208*%
%ADD47C,.164*%
%ADD17C,.155*%
%ADD40C,.256*%
%AMMACRO31*
4,1,36,0.0,.0085,
.001476,.008371,
.002907,.007987,
.00425,.007361,
.005464,.006511,
.006511,.005464,
.007361,.00425,
.007987,.002907,
.008371,.001476,
.0085,0.0,
.008371,-.001476,
.007987,-.002907,
.007361,-.00425,
.006511,-.005464,
.005464,-.006511,
.00425,-.007361,
.002907,-.007987,
.001476,-.008371,
0.0,-.0085,
-.001476,-.008371,
-.002907,-.007987,
-.00425,-.007361,
-.005464,-.006511,
-.006511,-.005464,
-.007361,-.00425,
-.007987,-.002907,
-.008371,-.001476,
-.0085,0.0,
-.008371,.001476,
-.007987,.002907,
-.007361,.00425,
-.006511,.005464,
-.005464,.006511,
-.00425,.007361,
-.002907,.007987,
-.001476,.008371,
0.0,.0085,
180.*
%
%ADD31MACRO31*%
%AMMACRO49*
4,1,36,0.0,.0185,
-.003212,.018219,
-.006327,.017384,
-.00925,.016021,
-.011892,.014172,
-.014172,.011892,
-.016021,.00925,
-.017384,.006327,
-.018219,.003212,
-.0185,0.0,
-.018219,-.003212,
-.017384,-.006327,
-.016021,-.00925,
-.014172,-.011892,
-.011892,-.014172,
-.00925,-.016021,
-.006327,-.017384,
-.003212,-.018219,
0.0,-.0185,
.003212,-.018219,
.006327,-.017384,
.00925,-.016021,
.011892,-.014172,
.014172,-.011892,
.016021,-.00925,
.017384,-.006327,
.018219,-.003212,
.0185,0.0,
.018219,.003212,
.017384,.006327,
.016021,.00925,
.014172,.011892,
.011892,.014172,
.00925,.016021,
.006327,.017384,
.003212,.018219,
0.0,.0185,
270.*
%
%ADD49MACRO49*%
%AMMACRO20*
4,1,20,-.0075,-.05555,
-.0075,-.06273,
-.013677,-.060878,
-.019439,-.057981,
-.024611,-.054127,
-.029034,-.049434,
-.032576,-.044045,
-.035127,-.038122,
-.036612,-.031846,
-.037,-.0265,
-.037,-.0075,
-.03,-.0075,
-.03,-.0265,
-.029544,-.03171,
-.028191,-.036762,
-.02598,-.041502,
-.022981,-.045786,
-.019282,-.049484,
-.014998,-.052484,
-.010258,-.054694,
-.0075,-.05555,
90.*
4,1,20,.0075,-.06273,
.0075,-.05555,
.01243,-.053806,
.016983,-.051232,
.02102,-.047906,
.024418,-.043931,
.027073,-.039425,
.028906,-.034527,
.029861,-.029385,
.03,-.0265,
.03,-.0075,
.037,-.0075,
.037,-.0265,
.036438,-.032925,
.034769,-.039154,
.032043,-.044999,
.028344,-.050282,
.023784,-.054842,
.018501,-.058541,
.012656,-.061266,
.0075,-.06273,
90.*
4,1,20,-.0075,.06273,
-.0075,.05555,
-.01243,.053806,
-.016983,.051232,
-.02102,.047906,
-.024418,.043931,
-.027073,.039425,
-.028906,.034527,
-.029861,.029385,
-.03,.0265,
-.03,.0075,
-.037,.0075,
-.037,.0265,
-.036438,.032925,
-.034769,.039154,
-.032043,.044999,
-.028344,.050282,
-.023784,.054842,
-.018501,.058541,
-.012656,.061266,
-.0075,.06273,
90.*
4,1,20,.0075,.05555,
.0075,.06273,
.013677,.060878,
.019439,.057981,
.024611,.054127,
.029034,.049434,
.032576,.044045,
.035127,.038122,
.036612,.031846,
.037,.0265,
.037,.0075,
.03,.0075,
.03,.0265,
.029544,.03171,
.028191,.036762,
.02598,.041502,
.022981,.045786,
.019282,.049484,
.014998,.052484,
.010258,.054694,
.0075,.05555,
90.*
%
%ADD20MACRO20*%
%AMMACRO16*
4,1,36,.0025,0.0,
.002462,.000434,
.002349,.000855,
.002165,.00125,
.001915,.001607,
.001607,.001915,
.00125,.002165,
.000855,.002349,
.000434,.002462,
0.0,.0025,
-.000434,.002462,
-.000855,.002349,
-.00125,.002165,
-.001607,.001915,
-.001915,.001607,
-.002165,.00125,
-.002349,.000855,
-.002462,.000434,
-.0025,0.0,
-.002462,-.000434,
-.002349,-.000855,
-.002165,-.00125,
-.001915,-.001607,
-.001607,-.001915,
-.00125,-.002165,
-.000855,-.002349,
-.000434,-.002462,
0.0,-.0025,
.000434,-.002462,
.000855,-.002349,
.00125,-.002165,
.001607,-.001915,
.001915,-.001607,
.002165,-.00125,
.002349,-.000855,
.002462,-.000434,
.0025,0.0,
90.*
%
%ADD16MACRO16*%
%AMMACRO35*
4,1,36,.003,0.0,
.002954,.000521,
.002819,.001026,
.002598,.0015,
.002298,.001928,
.001928,.002298,
.0015,.002598,
.001026,.002819,
.000521,.002954,
0.0,.003,
-.000521,.002954,
-.001026,.002819,
-.0015,.002598,
-.001928,.002298,
-.002298,.001928,
-.002598,.0015,
-.002819,.001026,
-.002954,.000521,
-.003,0.0,
-.002954,-.000521,
-.002819,-.001026,
-.002598,-.0015,
-.002298,-.001928,
-.001928,-.002298,
-.0015,-.002598,
-.001026,-.002819,
-.000521,-.002954,
0.0,-.003,
.000521,-.002954,
.001026,-.002819,
.0015,-.002598,
.001928,-.002298,
.002298,-.001928,
.002598,-.0015,
.002819,-.001026,
.002954,-.000521,
.003,0.0,
90.*
%
%ADD35MACRO35*%
%AMMACRO12*
4,1,36,.0025,0.0,
.002462,.000434,
.002349,.000855,
.002165,.00125,
.001915,.001607,
.001607,.001915,
.00125,.002165,
.000855,.002349,
.000434,.002462,
0.0,.0025,
-.000434,.002462,
-.000855,.002349,
-.00125,.002165,
-.001607,.001915,
-.001915,.001607,
-.002165,.00125,
-.002349,.000855,
-.002462,.000434,
-.0025,0.0,
-.002462,-.000434,
-.002349,-.000855,
-.002165,-.00125,
-.001915,-.001607,
-.001607,-.001915,
-.00125,-.002165,
-.000855,-.002349,
-.000434,-.002462,
0.0,-.0025,
.000434,-.002462,
.000855,-.002349,
.00125,-.002165,
.001607,-.001915,
.001915,-.001607,
.002165,-.00125,
.002349,-.000855,
.002462,-.000434,
.0025,0.0,
0.0*
%
%ADD12MACRO12*%
%AMMACRO52*
4,1,36,-.0025,0.0,
-.002462,.000434,
-.002349,.000855,
-.002165,.00125,
-.001915,.001607,
-.001607,.001915,
-.00125,.002165,
-.000855,.002349,
-.000434,.002462,
0.0,.0025,
.000434,.002462,
.000855,.002349,
.00125,.002165,
.001607,.001915,
.001915,.001607,
.002165,.00125,
.002349,.000855,
.002462,.000434,
.0025,0.0,
.002462,-.000434,
.002349,-.000855,
.002165,-.00125,
.001915,-.001607,
.001607,-.001915,
.00125,-.002165,
.000855,-.002349,
.000434,-.002462,
0.0,-.0025,
-.000434,-.002462,
-.000855,-.002349,
-.00125,-.002165,
-.001607,-.001915,
-.001915,-.001607,
-.002165,-.00125,
-.002349,-.000855,
-.002462,-.000434,
-.0025,0.0,
0.0*
%
%ADD52MACRO52*%
%AMMACRO26*
4,1,36,.003,0.0,
.002954,.000521,
.002819,.001026,
.002598,.0015,
.002298,.001928,
.001928,.002298,
.0015,.002598,
.001026,.002819,
.000521,.002954,
0.0,.003,
-.000521,.002954,
-.001026,.002819,
-.0015,.002598,
-.001928,.002298,
-.002298,.001928,
-.002598,.0015,
-.002819,.001026,
-.002954,.000521,
-.003,0.0,
-.002954,-.000521,
-.002819,-.001026,
-.002598,-.0015,
-.002298,-.001928,
-.001928,-.002298,
-.0015,-.002598,
-.001026,-.002819,
-.000521,-.002954,
0.0,-.003,
.000521,-.002954,
.001026,-.002819,
.0015,-.002598,
.001928,-.002298,
.002298,-.001928,
.002598,-.0015,
.002819,-.001026,
.002954,-.000521,
.003,0.0,
0.0*
%
%ADD26MACRO26*%
%AMMACRO23*
4,1,36,-.003,0.0,
-.002954,.000521,
-.002819,.001026,
-.002598,.0015,
-.002298,.001928,
-.001928,.002298,
-.0015,.002598,
-.001026,.002819,
-.000521,.002954,
0.0,.003,
.000521,.002954,
.001026,.002819,
.0015,.002598,
.001928,.002298,
.002298,.001928,
.002598,.0015,
.002819,.001026,
.002954,.000521,
.003,0.0,
.002954,-.000521,
.002819,-.001026,
.002598,-.0015,
.002298,-.001928,
.001928,-.002298,
.0015,-.002598,
.001026,-.002819,
.000521,-.002954,
0.0,-.003,
-.000521,-.002954,
-.001026,-.002819,
-.0015,-.002598,
-.001928,-.002298,
-.002298,-.001928,
-.002598,-.0015,
-.002819,-.001026,
-.002954,-.000521,
-.003,0.0,
0.0*
%
%ADD23MACRO23*%
%AMMACRO41*
4,1,16,.02584,.01524,
.028094,.010521,
.029494,.005483,
.029998,.000278,
.029591,-.004935,
.028284,-.009999,
.026118,-.014758,
.02584,-.01524,
.03092,-.02032,
.033979,-.014642,
.036005,-.008519,
.036938,-.002138,
.036748,.004309,
.035441,.010625,
.033058,.016618,
.03092,.02032,
.02584,.01524,
180.*
4,1,16,.01524,-.02584,
.010521,-.028094,
.005483,-.029494,
.000278,-.029998,
-.004935,-.029591,
-.009999,-.028284,
-.014758,-.026118,
-.01524,-.02584,
-.02032,-.03092,
-.014642,-.033979,
-.008519,-.036005,
-.002138,-.036938,
.004309,-.036748,
.010625,-.035441,
.016618,-.033058,
.02032,-.03092,
.01524,-.02584,
180.*
4,1,16,-.02584,-.01524,
-.028094,-.010521,
-.029494,-.005483,
-.029998,-.000278,
-.029591,.004935,
-.028284,.009999,
-.026118,.014758,
-.02584,.01524,
-.03092,.02032,
-.033979,.014642,
-.036005,.008519,
-.036938,.002138,
-.036748,-.004309,
-.035441,-.010625,
-.033058,-.016618,
-.03092,-.02032,
-.02584,-.01524,
180.*
4,1,16,-.01524,.02584,
-.010521,.028094,
-.005483,.029494,
-.000278,.029998,
.004935,.029591,
.009999,.028284,
.014758,.026118,
.01524,.02584,
.02032,.03092,
.014642,.033979,
.008519,.036005,
.002138,.036938,
-.004309,.036748,
-.010625,.035441,
-.016618,.033058,
-.02032,.03092,
-.01524,.02584,
180.*
%
%ADD41MACRO41*%
%AMMACRO56*
4,1,15,.03682,.01914,
.039584,.012455,
.041146,.005393,
.041457,-.001834,
.040509,-.009005,
.03833,-.015903,
.03682,-.01914,
.04197,-.0243,
.045552,-.016643,
.04775,-.00848,
.048497,-.000059,
.047771,.008363,
.045593,.016531,
.042029,.024197,
.04197,.0243,
.03682,.01914,
270.*
4,1,15,.01914,-.03682,
.012455,-.039584,
.005393,-.041146,
-.001834,-.041457,
-.009005,-.040509,
-.015903,-.03833,
-.01914,-.03682,
-.0243,-.04197,
-.016643,-.045552,
-.00848,-.04775,
-.000059,-.048497,
.008363,-.047771,
.016531,-.045593,
.024197,-.042029,
.0243,-.04197,
.01914,-.03682,
270.*
4,1,15,-.03682,-.01914,
-.039584,-.012455,
-.041146,-.005393,
-.041457,.001834,
-.040509,.009005,
-.03833,.015903,
-.03682,.01914,
-.04197,.0243,
-.045552,.016643,
-.04775,.00848,
-.048497,.000059,
-.047771,-.008363,
-.045593,-.016531,
-.042029,-.024197,
-.04197,-.0243,
-.03682,-.01914,
270.*
4,1,15,-.01914,.03682,
-.012455,.039584,
-.005393,.041146,
.001834,.041457,
.009005,.040509,
.015903,.03833,
.01914,.03682,
.0243,.04197,
.016643,.045552,
.00848,.04775,
.000059,.048497,
-.008363,.047771,
-.016531,.045593,
-.024197,.042029,
-.0243,.04197,
-.01914,.03682,
270.*
%
%ADD56MACRO56*%
%AMMACRO57*
4,1,15,-.03682,.01914,
-.039584,.012455,
-.041146,.005393,
-.041457,-.001834,
-.040509,-.009005,
-.03833,-.015903,
-.03682,-.01914,
-.04197,-.0243,
-.045552,-.016643,
-.04775,-.00848,
-.048497,-.000059,
-.047771,.008363,
-.045593,.016531,
-.042029,.024197,
-.04197,.0243,
-.03682,.01914,
270.*
4,1,15,-.01914,-.03682,
-.012455,-.039584,
-.005393,-.041146,
.001834,-.041457,
.009005,-.040509,
.015903,-.03833,
.01914,-.03682,
.0243,-.04197,
.016643,-.045552,
.00848,-.04775,
.000059,-.048497,
-.008363,-.047771,
-.016531,-.045593,
-.024197,-.042029,
-.0243,-.04197,
-.01914,-.03682,
270.*
4,1,15,.03682,-.01914,
.039584,-.012455,
.041146,-.005393,
.041457,.001834,
.040509,.009005,
.03833,.015903,
.03682,.01914,
.04197,.0243,
.045552,.016643,
.04775,.00848,
.048497,.000059,
.047771,-.008363,
.045593,-.016531,
.042029,-.024197,
.04197,-.0243,
.03682,-.01914,
270.*
4,1,15,.01914,.03682,
.012455,.039584,
.005393,.041146,
-.001834,.041457,
-.009005,.040509,
-.015903,.03833,
-.01914,.03682,
-.0243,.04197,
-.016643,.045552,
-.00848,.04775,
-.000059,.048497,
.008363,.047771,
.016531,.045593,
.024197,.042029,
.0243,.04197,
.01914,.03682,
270.*
%
%ADD57MACRO57*%
%ADD64C,.006*%
%ADD76C,.03006*%
%ADD82C,.02404*%
%ADD80C,.07005*%
%ADD73C,.08404*%
%ADD66C,.07306*%
%ADD79C,.09208*%
%ADD74C,.07606*%
%ADD72C,.08408*%
%ADD78C,.07608*%
%ADD71C,.08409*%
%ADD70O,.1621X.2251*%
%ADD69O,.03604X.07004*%
%ADD67O,.03006X.06406*%
%ADD81C,.16206*%
%ADD68O,.03606X.07006*%
%ADD77C,.17406*%
%ADD65C,.16506*%
%ADD75C,.21786*%
G75*
%LPD*%
G75*
G36*
G01X-1490433Y-1677216D02*
X4496476D01*
Y3837819D01*
X-1490433D01*
Y-1677216D01*
G37*
%LPC*%
G75*
G36*
G01X630370Y-100983D02*
G02X624496Y-95109I0J5874D01*
G01Y-32983D01*
G03X614622Y-23109I-9874J0D01*
G01X68874D01*
G03X59000Y-32983I0J-9874D01*
G01Y-95109D01*
G02X53126Y-100983I-5874J0D01*
G01X7874D01*
G02X2000Y-95109I0J5874D01*
G01Y-15748D01*
G02X7874Y-9874I5874J0D01*
G01X31358D01*
G03X41232Y0I0J9874D01*
G01Y34843D01*
G02X47106Y40717I5874J0D01*
G01X54980D01*
G02X60854Y34843I0J-5874D01*
G01Y0D01*
G03X70728Y-9874I9874J0D01*
G01X133720D01*
G03X143594Y0I0J9874D01*
G01Y34843D01*
G02X149468Y40717I5874J0D01*
G01X157343D01*
G02X163217Y34843I0J-5874D01*
G01Y0D01*
G03X173091Y-9874I9874J0D01*
G01X236083D01*
G03X245957Y0I0J9874D01*
G01Y34843D01*
G02X251831Y40717I5874J0D01*
G01X259705D01*
G02X265579Y34843I0J-5874D01*
G01Y0D01*
G03X275453Y-9874I9874J0D01*
G01X338445D01*
G03X348319Y0I0J9874D01*
G01Y34843D01*
G02X354193Y40717I5874J0D01*
G01X362067D01*
G02X367941Y34843I0J-5874D01*
G01Y0D01*
G03X377815Y-9874I9874J0D01*
G01X488445D01*
G03X498319Y0I0J9874D01*
G01Y34843D01*
G02X504193Y40717I5874J0D01*
G01X512067D01*
G02X517941Y34843I0J-5874D01*
G01Y0D01*
G03X527815Y-9874I9874J0D01*
G01X590807D01*
G03X600681Y0I0J9874D01*
G01Y34843D01*
G02X606555Y40717I5874J0D01*
G01X614429D01*
G02X620303Y34843I0J-5874D01*
G01Y0D01*
G03X630177Y-9874I9874J0D01*
G01X693169D01*
G03X703043Y0I0J9874D01*
G01Y34843D01*
G02X708917Y40717I5874J0D01*
G01X716791D01*
G02X722665Y34843I0J-5874D01*
G01Y0D01*
G03X732539Y-9874I9874J0D01*
G01X795531D01*
G03X805405Y0I0J9874D01*
G01Y34843D01*
G02X811279Y40717I5874J0D01*
G01X819154D01*
G02X825028Y34843I0J-5874D01*
G01Y0D01*
G03X834902Y-9874I9874J0D01*
G01X945531D01*
G03X955405Y0I0J9874D01*
G01Y34843D01*
G02X961279Y40717I5874J0D01*
G01X969154D01*
G02X975028Y34843I0J-5874D01*
G01Y0D01*
G03X984902Y-9874I9874J0D01*
G01X1047894D01*
G03X1057768Y0I0J9874D01*
G01Y34843D01*
G02X1063642Y40717I5874J0D01*
G01X1071516D01*
G02X1077390Y34843I0J-5874D01*
G01Y0D01*
G03X1087264Y-9874I9874J0D01*
G01X1150256D01*
G03X1160130Y0I0J9874D01*
G01Y34843D01*
G02X1166004Y40717I5874J0D01*
G01X1173878D01*
G02X1179752Y34843I0J-5874D01*
G01Y0D01*
G03X1189626Y-9874I9874J0D01*
G01X1252618D01*
G03X1262492Y0I0J9874D01*
G01Y34843D01*
G02X1268366Y40717I5874J0D01*
G01X1276240D01*
G02X1282114Y34843I0J-5874D01*
G01Y0D01*
G03X1291988Y-9874I9874J0D01*
G01X1402618D01*
G03X1412492Y0I0J9874D01*
G01Y34843D01*
G02X1418366Y40717I5874J0D01*
G01X1426240D01*
G02X1432114Y34843I0J-5874D01*
G01Y0D01*
G03X1441988Y-9874I9874J0D01*
G01X1504980D01*
G03X1514854Y0I0J9874D01*
G01Y34843D01*
G02X1520728Y40717I5874J0D01*
G01X1528602D01*
G02X1534476Y34843I0J-5874D01*
G01Y0D01*
G03X1544350Y-9874I9874J0D01*
G01X1607343D01*
G03X1617217Y0I0J9874D01*
G01Y34843D01*
G02X1623091Y40717I5874J0D01*
G01X1630965D01*
G02X1636839Y34843I0J-5874D01*
G01Y0D01*
G03X1646713Y-9874I9874J0D01*
G01X1709705D01*
G03X1719579Y0I0J9874D01*
G01Y34843D01*
G02X1725453Y40717I5874J0D01*
G01X1733327D01*
G02X1739201Y34843I0J-5874D01*
G01Y0D01*
G03X1749075Y-9874I9874J0D01*
G01X1833071D01*
G02X1838945Y-15748I0J-5874D01*
G01Y-95109D01*
G02X1833071Y-100983I-5874J0D01*
G01X630370D01*
G37*
G36*
G01X1833071Y1645992D02*
G02X1838945Y1640118I0J-5874D01*
G01Y970425D01*
G02X1837225Y966273I-5874J1D01*
G01X1826876Y955925D01*
G03X1823984Y948943I6982J-6982D01*
G01Y344836D01*
G03X1826876Y337855I9873J0D01*
G01X1837225Y327506D01*
G02X1838945Y323354I-4153J-4153D01*
G01Y7874D01*
G02X1833071Y2000I-5874J0D01*
G01X1756949D01*
G02X1751075Y7874I0J5874D01*
G01Y46654D01*
G03X1745138Y52591I-5937J0D01*
G01X1713642D01*
G03X1707705Y46654I0J-5937D01*
G01Y7874D01*
G02X1701831Y2000I-5874J0D01*
G01X1654587D01*
G02X1648713Y7874I0J5874D01*
G01Y46654D01*
G03X1642776Y52591I-5937J0D01*
G01X1611280D01*
G03X1605343Y46654I0J-5937D01*
G01Y7874D01*
G02X1599469Y2000I-5874J0D01*
G01X1552224D01*
G02X1546350Y7874I0J5874D01*
G01Y46654D01*
G03X1540413Y52591I-5937J0D01*
G01X1508917D01*
G03X1502980Y46654I0J-5937D01*
G01Y7874D01*
G02X1497106Y2000I-5874J0D01*
G01X1449862D01*
G02X1443988Y7874I0J5874D01*
G01Y46654D01*
G03X1438051Y52591I-5937J0D01*
G01X1406555D01*
G03X1400618Y46654I0J-5937D01*
G01Y7874D01*
G02X1394744Y2000I-5874J0D01*
G01X1299862D01*
G02X1293988Y7874I0J5874D01*
G01Y46654D01*
G03X1288051Y52591I-5937J0D01*
G01X1256555D01*
G03X1250618Y46654I0J-5937D01*
G01Y7874D01*
G02X1244744Y2000I-5874J0D01*
G01X1197500D01*
G02X1191626Y7874I0J5874D01*
G01Y46654D01*
G03X1185689Y52591I-5937J0D01*
G01X1154193D01*
G03X1148256Y46654I0J-5937D01*
G01Y7874D01*
G02X1142382Y2000I-5874J0D01*
G01X1095138D01*
G02X1089264Y7874I0J5874D01*
G01Y46654D01*
G03X1083327Y52591I-5937J0D01*
G01X1051831D01*
G03X1045894Y46654I0J-5937D01*
G01Y7874D01*
G02X1040020Y2000I-5874J0D01*
G01X992776D01*
G02X986902Y7874I0J5874D01*
G01Y46654D01*
G03X980965Y52591I-5937J0D01*
G01X949468D01*
G03X943531Y46654I0J-5937D01*
G01Y7874D01*
G02X937657Y2000I-5874J0D01*
G01X842776D01*
G02X836902Y7874I0J5874D01*
G01Y46654D01*
G03X830965Y52591I-5937J0D01*
G01X799468D01*
G03X793531Y46654I0J-5937D01*
G01Y7874D01*
G02X787657Y2000I-5874J0D01*
G01X740413D01*
G02X734539Y7874I0J5874D01*
G01Y46654D01*
G03X728602Y52591I-5937J0D01*
G01X697106D01*
G03X691169Y46654I0J-5937D01*
G01Y7874D01*
G02X685295Y2000I-5874J0D01*
G01X638051D01*
G02X632177Y7874I0J5874D01*
G01Y46654D01*
G03X626240Y52591I-5937J0D01*
G01X594744D01*
G03X588807Y46654I0J-5937D01*
G01Y7874D01*
G02X582933Y2000I-5874J0D01*
G01X535689D01*
G02X529815Y7874I0J5874D01*
G01Y46654D01*
G03X523878Y52591I-5937J0D01*
G01X492382D01*
G03X486445Y46654I0J-5937D01*
G01Y7874D01*
G02X480571Y2000I-5874J0D01*
G01X385689D01*
G02X379815Y7874I0J5874D01*
G01Y46654D01*
G03X373878Y52591I-5937J0D01*
G01X342382D01*
G03X336445Y46654I0J-5937D01*
G01Y7874D01*
G02X330571Y2000I-5874J0D01*
G01X283327D01*
G02X277453Y7874I0J5874D01*
G01Y46654D01*
G03X271516Y52591I-5937J0D01*
G01X240020D01*
G03X234083Y46654I0J-5937D01*
G01Y7874D01*
G02X228209Y2000I-5874J0D01*
G01X180965D01*
G02X175091Y7874I0J5874D01*
G01Y46654D01*
G03X169154Y52591I-5937J0D01*
G01X137657D01*
G03X131720Y46654I0J-5937D01*
G01Y7874D01*
G02X125846Y2000I-5874J0D01*
G01X78602D01*
G02X72728Y7874I0J5874D01*
G01Y46654D01*
G03X66791Y52591I-5937J0D01*
G01X35295D01*
G03X29358Y46654I0J-5937D01*
G01Y7874D01*
G02X23484Y2000I-5874J0D01*
G01X7874D01*
G02X2000Y7874I0J5874D01*
G01Y323354D01*
G02X3720Y327506I5873J-1D01*
G01X14068Y337855D01*
G03X16961Y344836I-6980J6983D01*
G01Y948943D01*
G03X14068Y955925I-9875J-1D01*
G01X3720Y966273D01*
G02X2000Y970425I4154J4153D01*
G01Y1640118D01*
G02X7874Y1645992I5874J0D01*
G01X789298D01*
G02X793649Y1644063I-1J-5873D01*
G03X800966Y1640819I7317J6631D01*
G01X1070058D01*
G03X1077374Y1644063I-1J9873D01*
G02X1081725Y1645992I4352J-3945D01*
G01X1833071D01*
G37*
G36*
G01Y1818880D02*
G02X1838945Y1813006I0J-5874D01*
G01Y1663740D01*
G02X1833071Y1657866I-5874J0D01*
G01X1763543D01*
G02X1757669Y1663740I0J5874D01*
G01Y1689331D01*
G03X1747795Y1699205I-9874J0D01*
G01X1461575D01*
G03X1451701Y1689331I0J-9874D01*
G01Y1663740D01*
G02X1445827Y1657866I-5874J0D01*
G01X1417087D01*
G02X1411213Y1663740I0J5874D01*
G01Y1689331D01*
G03X1401339Y1699205I-9874J0D01*
G01X1115118D01*
G03X1105244Y1689331I0J-9874D01*
G01Y1663740D01*
G02X1099370Y1657866I-5874J0D01*
G01X1090079D01*
G02X1084205Y1663740I0J5874D01*
G01Y1695110D01*
G03X1074331Y1704984I-9874J0D01*
G01X796693D01*
G03X786819Y1695110I0J-9874D01*
G01Y1663740D01*
G02X780945Y1657866I-5874J0D01*
G01X741575D01*
G02X735701Y1663740I0J5874D01*
G01Y1689331D01*
G03X725827Y1699205I-9874J0D01*
G01X439607D01*
G03X429733Y1689331I0J-9874D01*
G01Y1663740D01*
G02X423859Y1657866I-5874J0D01*
G01X395118D01*
G02X389244Y1663740I0J5874D01*
G01Y1689331D01*
G03X379370Y1699205I-9874J0D01*
G01X93150D01*
G03X83276Y1689331I0J-9874D01*
G01Y1663740D01*
G02X77402Y1657866I-5874J0D01*
G01X7874D01*
G02X2000Y1663740I0J5874D01*
G01Y1813006D01*
G02X7874Y1818880I5874J0D01*
G01X1833071D01*
G37*
%LPD*%
G75*
G36*
G01X607977Y1552080D02*
X555513D01*
G02X555210Y1552383I0J303D01*
G01Y1643194D01*
G02X555513Y1643498I303J1D01*
G01X608266D01*
G02X608570Y1643194I0J-304D01*
G01Y1552672D01*
X607977Y1552080D01*
G37*
G36*
G01X208954Y1643834D02*
G02X209256Y1644136I302J0D01*
G01X261611D01*
G02X261912Y1643834I-1J-302D01*
G01Y1642872D01*
Y1552470D01*
X261722Y1552280D01*
X208952D01*
Y1642872D01*
X208954D01*
Y1643834D01*
G37*
G36*
G01X1232576D02*
G02X1232878Y1644136I302J0D01*
G01X1285233D01*
G02X1285534Y1643834I-1J-302D01*
G01Y1643226D01*
Y1552461D01*
X1285353Y1552280D01*
X1232574D01*
Y1643226D01*
X1232576D01*
Y1643834D01*
G37*
G36*
G01X1579032D02*
G02X1579335Y1644136I303J-1D01*
G01X1631688D01*
G02X1631990Y1643834I0J-302D01*
G01Y1643174D01*
X1631992D01*
Y1552573D01*
X1631698Y1552280D01*
X1579032D01*
Y1643174D01*
Y1643834D01*
G37*
G36*
G01X177763Y1512216D02*
X180583D01*
G02X180786Y1512014I1J-202D01*
G01Y1511392D01*
G03X180836Y1511260I200J0D01*
G02Y1508348I-1664J-1456D01*
G03X180786Y1508216I150J-132D01*
G01Y1506273D01*
G03X180836Y1506141I200J0D01*
G02Y1503229I-1664J-1456D01*
G03X180786Y1503097I150J-132D01*
G01Y1502476D01*
G02X180583Y1502274I-203J1D01*
G01X177763D01*
G02X177560Y1502476I-1J202D01*
G01Y1503097D01*
G03X177510Y1503229I-200J0D01*
G02Y1506141I1664J1456D01*
G03X177560Y1506273I-150J132D01*
G01Y1508216D01*
G03X177510Y1508348I-200J0D01*
G02Y1511260I1664J1456D01*
G03X177560Y1511392I-150J132D01*
G01Y1512014D01*
G02X177763Y1512216I203J-1D01*
G37*
G36*
G01X350991D02*
X353811D01*
G02X354014Y1512014I1J-202D01*
G01Y1511392D01*
G03X354064Y1511260I200J0D01*
G02Y1508348I-1664J-1456D01*
G03X354014Y1508216I150J-132D01*
G01Y1506273D01*
G03X354064Y1506141I200J0D01*
G02Y1503229I-1664J-1456D01*
G03X354014Y1503097I150J-132D01*
G01Y1502476D01*
G02X353811Y1502274I-203J1D01*
G01X350991D01*
G02X350788Y1502476I-1J202D01*
G01Y1503097D01*
G03X350738Y1503229I-200J0D01*
G02Y1506141I1664J1456D01*
G03X350788Y1506273I-150J132D01*
G01Y1508216D01*
G03X350738Y1508348I-200J0D01*
G02Y1511260I1664J1456D01*
G03X350788Y1511392I-150J132D01*
G01Y1512014D01*
G02X350991Y1512216I203J-1D01*
G37*
G36*
G01X186425Y1516546D02*
X189245D01*
G02X189448Y1516344I1J-202D01*
G01Y1515722D01*
G03X189498Y1515590I200J0D01*
G02Y1512678I-1664J-1456D01*
G03X189448Y1512546I150J-132D01*
G01Y1510604D01*
G03X189498Y1510472I200J0D01*
G02Y1507560I-1664J-1456D01*
G03X189448Y1507428I150J-132D01*
G01Y1506806D01*
G02X189245Y1506604I-203J1D01*
G01X186425D01*
G02X186222Y1506806I-1J202D01*
G01Y1507428D01*
G03X186172Y1507560I-200J0D01*
G02Y1510472I1664J1456D01*
G03X186222Y1510604I-150J132D01*
G01Y1512546D01*
G03X186172Y1512678I-200J0D01*
G02Y1515590I1664J1456D01*
G03X186222Y1515722I-150J132D01*
G01Y1516344D01*
G02X186425Y1516546I203J-1D01*
G37*
G36*
G01X359653D02*
X362473D01*
G02X362676Y1516344I1J-202D01*
G01Y1515722D01*
G03X362726Y1515590I200J0D01*
G02Y1512678I-1664J-1456D01*
G03X362676Y1512546I150J-132D01*
G01Y1510604D01*
G03X362726Y1510472I200J0D01*
G02Y1507560I-1664J-1456D01*
G03X362676Y1507428I150J-132D01*
G01Y1506806D01*
G02X362473Y1506604I-203J1D01*
G01X359653D01*
G02X359450Y1506806I-1J202D01*
G01Y1507428D01*
G03X359400Y1507560I-200J0D01*
G02Y1510472I1664J1456D01*
G03X359450Y1510604I-150J132D01*
G01Y1512546D01*
G03X359400Y1512678I-200J0D01*
G02Y1515590I1664J1456D01*
G03X359450Y1515722I-150J132D01*
G01Y1516344D01*
G02X359653Y1516546I203J-1D01*
G37*
G36*
G01X177763Y1568516D02*
X180583D01*
G02X180786Y1568313I0J-203D01*
G01Y1567691D01*
G03X180836Y1567559I200J0D01*
G02Y1564647I-1664J-1456D01*
G03X180786Y1564515I150J-132D01*
G01Y1562573D01*
G03X180836Y1562441I200J0D01*
G02Y1559529I-1664J-1456D01*
G03X180786Y1559397I150J-132D01*
G01Y1558775D01*
G02X180583Y1558572I-203J0D01*
G01X177763D01*
G02X177560Y1558775I0J203D01*
G01Y1559397D01*
G03X177510Y1559529I-200J0D01*
G02Y1562441I1664J1456D01*
G03X177560Y1562573I-150J132D01*
G01Y1564515D01*
G03X177510Y1564647I-200J0D01*
G02Y1567559I1664J1456D01*
G03X177560Y1567691I-150J132D01*
G01Y1568313D01*
G02X177763Y1568516I203J0D01*
G37*
G36*
G01X350991D02*
X353811D01*
G02X354014Y1568313I0J-203D01*
G01Y1567691D01*
G03X354064Y1567559I200J0D01*
G02Y1564647I-1664J-1456D01*
G03X354014Y1564515I150J-132D01*
G01Y1562573D01*
G03X354064Y1562441I200J0D01*
G02Y1559529I-1664J-1456D01*
G03X354014Y1559397I150J-132D01*
G01Y1558775D01*
G02X353811Y1558572I-203J0D01*
G01X350991D01*
G02X350788Y1558775I0J203D01*
G01Y1559397D01*
G03X350738Y1559529I-200J0D01*
G02Y1562441I1664J1456D01*
G03X350788Y1562573I-150J132D01*
G01Y1564515D01*
G03X350738Y1564647I-200J0D01*
G02Y1567559I1664J1456D01*
G03X350788Y1567691I-150J132D01*
G01Y1568313D01*
G02X350991Y1568516I203J0D01*
G37*
G36*
G01X186425Y1572846D02*
X189245D01*
G02X189448Y1572644I1J-202D01*
G01Y1572022D01*
G03X189498Y1571890I200J0D01*
G02Y1568978I-1664J-1456D01*
G03X189448Y1568846I150J-132D01*
G01Y1566903D01*
G03X189498Y1566771I200J0D01*
G02Y1563859I-1664J-1456D01*
G03X189448Y1563727I150J-132D01*
G01Y1563106D01*
G02X189245Y1562904I-203J1D01*
G01X186425D01*
G02X186222Y1563106I-1J202D01*
G01Y1563727D01*
G03X186172Y1563859I-200J0D01*
G02Y1566771I1664J1456D01*
G03X186222Y1566903I-150J132D01*
G01Y1568846D01*
G03X186172Y1568978I-200J0D01*
G02Y1571890I1664J1456D01*
G03X186222Y1572022I-150J132D01*
G01Y1572644D01*
G02X186425Y1572846I203J-1D01*
G37*
G36*
G01X359653D02*
X362473D01*
G02X362676Y1572644I1J-202D01*
G01Y1572022D01*
G03X362726Y1571890I200J0D01*
G02Y1568978I-1664J-1456D01*
G03X362676Y1568846I150J-132D01*
G01Y1566903D01*
G03X362726Y1566771I200J0D01*
G02Y1563859I-1664J-1456D01*
G03X362676Y1563727I150J-132D01*
G01Y1563106D01*
G02X362473Y1562904I-203J1D01*
G01X359653D01*
G02X359450Y1563106I-1J202D01*
G01Y1563727D01*
G03X359400Y1563859I-200J0D01*
G02Y1566771I1664J1456D01*
G03X359450Y1566903I-150J132D01*
G01Y1568846D01*
G03X359400Y1568978I-200J0D01*
G02Y1571890I1664J1456D01*
G03X359450Y1572022I-150J132D01*
G01Y1572644D01*
G02X359653Y1572846I203J-1D01*
G37*
G36*
G01X177763Y1583870D02*
X180583D01*
G02X180786Y1583667I0J-203D01*
G01Y1583045D01*
G03X180836Y1582913I200J0D01*
G02Y1580001I-1664J-1456D01*
G03X180786Y1579869I150J-132D01*
G01Y1577927D01*
G03X180836Y1577795I200J0D01*
G02Y1574883I-1664J-1456D01*
G03X180786Y1574751I150J-132D01*
G01Y1574129D01*
G02X180583Y1573926I-203J0D01*
G01X177763D01*
G02X177560Y1574129I0J203D01*
G01Y1574751D01*
G03X177510Y1574883I-200J0D01*
G02Y1577795I1664J1456D01*
G03X177560Y1577927I-150J132D01*
G01Y1579869D01*
G03X177510Y1580001I-200J0D01*
G02Y1582913I1664J1456D01*
G03X177560Y1583045I-150J132D01*
G01Y1583667D01*
G02X177763Y1583870I203J0D01*
G37*
G36*
G01X404759Y1350874D02*
X408159D01*
G02Y1347270I0J-1802D01*
G01X404759D01*
G02Y1350874I0J1802D01*
G37*
G36*
G01X402489Y1419078D02*
X405889D01*
G02Y1415472I0J-1803D01*
G01X402489D01*
G02Y1419078I0J1803D01*
G37*
G36*
G01X1443660Y1308896D02*
X1440260D01*
G02Y1312500I0J1802D01*
G01X1443660D01*
G02Y1308896I0J-1802D01*
G37*
G36*
G01X970197Y665850D02*
X966797D01*
G02Y669456I0J1803D01*
G01X970197D01*
G02Y665850I0J-1803D01*
G37*
G36*
G01X501495Y772260D02*
X504895D01*
G02Y768654I0J-1803D01*
G01X501495D01*
G02Y772260I0J1803D01*
G37*
G36*
G01X909508Y623418D02*
X912908D01*
G02Y619814I0J-1802D01*
G01X909508D01*
G02Y623418I0J1802D01*
G37*
G36*
G01X900676Y623338D02*
X904076D01*
G02Y619734I0J-1802D01*
G01X900676D01*
G02Y623338I0J1802D01*
G37*
G36*
G01X526264Y665858D02*
X529664D01*
G02Y662254I0J-1802D01*
G01X526264D01*
G02Y665858I0J1802D01*
G37*
G36*
G01X534264Y663358D02*
X537664D01*
G02Y659754I0J-1802D01*
G01X534264D01*
G02Y663358I0J1802D01*
G37*
G36*
G01X538985Y734790D02*
X535585D01*
G02Y738396I0J1803D01*
G01X538985D01*
G02Y734790I0J-1803D01*
G37*
G36*
G01X530985Y739790D02*
X527585D01*
G02Y743396I0J1803D01*
G01X530985D01*
G02Y739790I0J-1803D01*
G37*
G36*
G01X517731Y742874D02*
X521131D01*
G02Y739268I0J-1803D01*
G01X517731D01*
G02Y742874I0J1803D01*
G37*
G36*
G01X511724Y739232D02*
X508324D01*
G02Y742838I0J1803D01*
G01X511724D01*
G02Y739232I0J-1803D01*
G37*
G36*
G01X415777Y306272D02*
X419177D01*
G02Y302668I0J-1802D01*
G01X415777D01*
G02Y306272I0J1802D01*
G37*
G36*
G01X423651Y309272D02*
X427051D01*
G02Y305668I0J-1802D01*
G01X423651D01*
G02Y309272I0J1802D01*
G37*
G36*
G01X431525Y306272D02*
X434925D01*
G02Y302668I0J-1802D01*
G01X431525D01*
G02Y306272I0J1802D01*
G37*
G36*
G01X434924Y368506D02*
X431524D01*
G02Y372112I0J1803D01*
G01X434924D01*
G02Y368506I0J-1803D01*
G37*
G36*
G01X933247Y1585829D02*
X940733Y1578343D01*
G03X940735Y1578341I142J140D01*
G03X940910Y1578270I174J178D01*
G01X956757D01*
G02X956899Y1578211I0J-200D01*
G01X960831Y1574278D01*
G02X960890Y1574136I-141J-142D01*
G01Y1543680D01*
G03X960963Y1543504I249J0D01*
G01X965002Y1539465D01*
G03X965004Y1539463I142J140D01*
G03X965179Y1539392I174J178D01*
G01X1020321D01*
G02X1020463Y1539333I0J-200D01*
G01X1032517Y1527279D01*
G02X1032576Y1527137I-141J-142D01*
G01Y1492489D01*
G02X1032517Y1492347I-200J0D01*
G01X1031783Y1491613D01*
G02X1031641Y1491554I-142J141D01*
G01X946768D01*
G02X946626Y1491613I0J200D01*
G01X944169Y1494071D01*
G03X944167Y1494073I-142J-140D01*
G03X943992Y1494144I-174J-178D01*
G01X933579D01*
G03X933404Y1494073I-1J-249D01*
G03X933402Y1494071I140J-142D01*
G01X917849Y1478518D01*
G03X917776Y1478342I176J-176D01*
G01Y1464605D01*
G02X917717Y1464463I-200J0D01*
G01X914897Y1461643D01*
G03X914895Y1461641I140J-142D01*
G03X914824Y1461466I178J-174D01*
G01Y1460513D01*
G02X914765Y1460371I-200J0D01*
G01X914235Y1459842D01*
G03X914162Y1459666I176J-176D01*
G01Y1446033D01*
G02X914104Y1445891I-200J-1D01*
G01X913370Y1445157D01*
G02X913228Y1445098I-142J141D01*
G01X900144D01*
G02X900002Y1445157I0J200D01*
G01X899268Y1445891D01*
G02X899210Y1446033I142J141D01*
G01Y1459640D01*
G03X899137Y1459816I-249J0D01*
G01X898531Y1460422D01*
G02X898472Y1460564I141J142D01*
G01Y1462024D01*
G03X898399Y1462200I-249J0D01*
G01X893401Y1467197D01*
G02X893342Y1467339I141J142D01*
G01Y1473096D01*
G03X893271Y1473271I-249J1D01*
G03X893269Y1473273I-142J-140D01*
G01X888245Y1478297D01*
G03X888069Y1478370I-176J-176D01*
G01X880504D01*
G03X880328Y1478297I0J-249D01*
G01X872973Y1470942D01*
G03X872900Y1470766I176J-176D01*
G01Y1460576D01*
G02X872841Y1460434I-200J0D01*
G01X872211Y1459804D01*
G03X872209Y1459802I140J-142D01*
G03X872138Y1459627I178J-174D01*
G01Y1446008D01*
G02X872079Y1445866I-200J0D01*
G01X871383Y1445170D01*
G02X871241Y1445112I-141J142D01*
G01X858287D01*
G02X858145Y1445171I0J200D01*
G01X857137Y1446178D01*
G02X857078Y1446320I141J142D01*
G01Y1459524D01*
G03X857007Y1459699I-249J1D01*
G03X857005Y1459701I-142J-140D01*
G01X852953Y1463753D01*
G03X852951Y1463755I-142J-140D01*
G03X852776Y1463826I-174J-178D01*
G01X828441D01*
G03X828266Y1463755I-1J-249D01*
G03X828264Y1463753I140J-142D01*
G01X827747Y1463236D01*
G03X827674Y1463060I176J-176D01*
G01Y1461432D01*
G02X827615Y1461290I-200J0D01*
G01X826986Y1460661D01*
G02X826844Y1460602I-142J141D01*
G01X825036D01*
G03X824860Y1460529I0J-249D01*
G01X821948Y1457617D01*
G02X821806Y1457558I-142J141D01*
G01X820451D01*
G03X820275Y1457485I0J-249D01*
G01X820069Y1457279D01*
G03X820067Y1457277I140J-142D01*
G03X819996Y1457102I178J-174D01*
G01Y1446047D01*
G02X819937Y1445905I-200J0D01*
G01X819241Y1445209D01*
G02X819099Y1445150I-142J141D01*
G01X805978D01*
G02X805836Y1445209I0J200D01*
G01X805061Y1445984D01*
G02X805002Y1446126I141J142D01*
G01Y1460243D01*
G02X805061Y1460385I200J0D01*
G01X805487Y1460810D01*
G03X805560Y1460986I-176J176D01*
G01Y1474724D01*
G02X805619Y1474866I200J0D01*
G01X805875Y1475122D01*
G03X805877Y1475124I-140J142D01*
G03X805948Y1475299I-178J174D01*
G01Y1524130D01*
G02X806007Y1524272I200J0D01*
G01X816121Y1534385D01*
G03X816123Y1534387I-140J142D01*
G03X816194Y1534562I-178J174D01*
G01Y1621268D01*
G02X816253Y1621410I200J0D01*
G01X822113Y1627269D01*
G02X822255Y1627328I142J-141D01*
G01X927980D01*
G02X928122Y1627269I0J-200D01*
G01X933115Y1622276D01*
G02X933174Y1622134I-141J-142D01*
G01Y1586005D01*
G03X933247Y1585829I249J0D01*
G37*
G36*
G01X1047661Y1451746D02*
X1045748Y1449833D01*
G02X1045606Y1449774I-142J141D01*
G01X955889D01*
G02X955747Y1449833I0J200D01*
G01X954749Y1450831D01*
G02X954690Y1450973I141J142D01*
G01Y1485726D01*
G02X954749Y1485868I200J0D01*
G01X956753Y1487871D01*
G02X956895Y1487930I142J-141D01*
G01X1046147D01*
G02X1046289Y1487871I0J-200D01*
G01X1047661Y1486500D01*
G02X1047720Y1486358I-141J-142D01*
G01Y1451888D01*
G02X1047661Y1451746I-200J0D01*
G37*
G36*
G01X952704Y1482405D02*
X953818Y1481291D01*
G03X953834Y1481276I178J174D01*
G01X954122Y1481036D01*
G02X954194Y1480882I-128J-154D01*
G01Y1451027D01*
G02X954135Y1450885I-200J0D01*
G01X953083Y1449833D01*
G02X952941Y1449774I-142J141D01*
G01X930177D01*
G02X930035Y1449833I0J200D01*
G01X928619Y1451249D01*
G02X928560Y1451391I141J142D01*
G01Y1481306D01*
G02X928619Y1481448I200J0D01*
G01X930003Y1482831D01*
G02X930145Y1482890I142J-141D01*
G01X952269D01*
G02X952435Y1482801I0J-200D01*
G01X952673Y1482443D01*
G03X952703Y1482406I207J137D01*
G01X952704Y1482405D01*
G37*
G36*
G01X26772Y1559218D02*
X20472D01*
G02Y1575428I0J8105D01*
G01X26772D01*
G02Y1559218I0J-8105D01*
G37*
G36*
G01X216125Y1441832D02*
X219525D01*
G02Y1438226I0J-1803D01*
G01X216125D01*
G02Y1441832I0J1803D01*
G37*
G36*
G01X413753Y1518690D02*
X417153D01*
G02Y1515084I0J-1803D01*
G01X413753D01*
G02Y1518690I0J1803D01*
G37*
G36*
G01X417334Y1475298D02*
X413934D01*
G02Y1478902I0J1802D01*
G01X417334D01*
G02Y1475298I0J-1802D01*
G37*
G36*
G01X919628Y334530D02*
X916228D01*
G02Y338136I0J1803D01*
G01X919628D01*
G02Y334530I0J-1803D01*
G37*
G36*
G01X905899Y304150D02*
X909299D01*
G02Y300544I0J-1803D01*
G01X905899D01*
G02Y304150I0J1803D01*
G37*
G36*
G01X1033891Y298096D02*
X1037291D01*
G02Y294490I0J-1803D01*
G01X1033891D01*
G02Y298096I0J1803D01*
G37*
G36*
G01X1318363Y312364D02*
X1321763D01*
G02Y308760I0J-1802D01*
G01X1318363D01*
G02Y312364I0J1802D01*
G37*
G36*
G01X1337508Y371598D02*
X1334108D01*
G02Y375204I0J1803D01*
G01X1337508D01*
G02Y371598I0J-1803D01*
G37*
G36*
G01X1326237Y309364D02*
X1329637D01*
G02Y305760I0J-1802D01*
G01X1326237D01*
G02Y309364I0J1802D01*
G37*
G36*
G01X1334111Y312364D02*
X1337511D01*
G02Y308760I0J-1802D01*
G01X1334111D01*
G02Y312364I0J1802D01*
G37*
G36*
G01X1518207Y1176748D02*
X1514467D01*
G02Y1179354I0J1303D01*
G01X1518207D01*
G02Y1176748I0J-1303D01*
G37*
G36*
G01Y1169268D02*
X1514467D01*
G02Y1171872I0J1302D01*
G01X1518207D01*
G02Y1169268I0J-1302D01*
G37*
G36*
G01X1513926Y907148D02*
X1510526D01*
G02Y910754I0J1803D01*
G01X1513926D01*
G02Y907148I0J-1803D01*
G37*
G36*
G01X1531299Y1174878D02*
X1527559D01*
G02Y1177482I0J1302D01*
G01X1531299D01*
G02Y1174878I0J-1302D01*
G37*
G36*
G01X146947Y1176748D02*
X143207D01*
G02Y1179354I0J1303D01*
G01X146947D01*
G02Y1176748I0J-1303D01*
G37*
G36*
G01Y1169268D02*
X143207D01*
G02Y1171872I0J1302D01*
G01X146947D01*
G02Y1169268I0J-1302D01*
G37*
G36*
G01X160039Y1174878D02*
X156299D01*
G02Y1177482I0J1302D01*
G01X160039D01*
G02Y1174878I0J-1302D01*
G37*
G36*
G01X604034Y1176748D02*
X600294D01*
G02Y1179354I0J1303D01*
G01X604034D01*
G02Y1176748I0J-1303D01*
G37*
G36*
G01Y1169268D02*
X600294D01*
G02Y1171872I0J1302D01*
G01X604034D01*
G02Y1169268I0J-1302D01*
G37*
G36*
G01X605733Y942940D02*
X609133D01*
G02Y939336I0J-1802D01*
G01X605733D01*
G02Y942940I0J1802D01*
G37*
G36*
G01X615256Y1176748D02*
X611516D01*
G02Y1179354I0J1303D01*
G01X615256D01*
G02Y1176748I0J-1303D01*
G37*
G36*
G01X1061120D02*
X1057380D01*
G02Y1179354I0J1303D01*
G01X1061120D01*
G02Y1176748I0J-1303D01*
G37*
G36*
G01Y1169268D02*
X1057380D01*
G02Y1171872I0J1302D01*
G01X1061120D01*
G02Y1169268I0J-1302D01*
G37*
G36*
G01X1769063Y921922D02*
X1765663D01*
G02Y925526I0J1802D01*
G01X1769063D01*
G02Y921922I0J-1802D01*
G37*
G36*
G01X1072342Y1176748D02*
X1068602D01*
G02Y1179354I0J1303D01*
G01X1072342D01*
G02Y1176748I0J-1303D01*
G37*
G36*
G01X647411Y379065D02*
X647412D01*
G02Y370659I0J-4203D01*
G01X647411D01*
G02Y379065I0J4203D01*
G37*
G36*
G01X111494Y1456412D02*
G02X111292Y1456210I-202J0D01*
G01X108472D01*
G02X108270Y1456413I1J203D01*
G01Y1457032D01*
G03X108220Y1457164I-200J0D01*
G02Y1460080I1661J1458D01*
G03X108270Y1460212I-150J132D01*
G01Y1462151D01*
G03X108220Y1462283I-200J0D01*
G02Y1465199I1661J1458D01*
G03X108270Y1465331I-150J132D01*
G01Y1465952D01*
G02X108472Y1466154I202J0D01*
G01X111292D01*
G02X111494Y1465951I-1J-203D01*
G01Y1465331D01*
G03X111544Y1465199I200J0D01*
G02Y1462283I-1661J-1458D01*
G03X111494Y1462151I150J-132D01*
G01Y1460212D01*
G03X111544Y1460080I200J0D01*
G02Y1457164I-1661J-1458D01*
G03X111494Y1457032I150J-132D01*
G01Y1456412D01*
G37*
G36*
G01X319368D02*
G02X319166Y1456210I-202J0D01*
G01X316346D01*
G02X316144Y1456413I1J203D01*
G01Y1457032D01*
G03X316094Y1457164I-200J0D01*
G02Y1460080I1661J1458D01*
G03X316144Y1460212I-150J132D01*
G01Y1462151D01*
G03X316094Y1462283I-200J0D01*
G02Y1465199I1661J1458D01*
G03X316144Y1465331I-150J132D01*
G01Y1465952D01*
G02X316346Y1466154I202J0D01*
G01X319166D01*
G02X319368Y1465951I-1J-203D01*
G01Y1465331D01*
G03X319418Y1465199I200J0D01*
G02Y1462283I-1661J-1458D01*
G03X319368Y1462151I150J-132D01*
G01Y1460212D01*
G03X319418Y1460080I200J0D01*
G02Y1457164I-1661J-1458D01*
G03X319368Y1457032I150J-132D01*
G01Y1456412D01*
G37*
G36*
G01X336690D02*
G02X336488Y1456210I-202J0D01*
G01X333668D01*
G02X333466Y1456413I1J203D01*
G01Y1457032D01*
G03X333416Y1457164I-200J0D01*
G02Y1460080I1661J1458D01*
G03X333466Y1460212I-150J132D01*
G01Y1462151D01*
G03X333416Y1462283I-200J0D01*
G02Y1465199I1661J1458D01*
G03X333466Y1465331I-150J132D01*
G01Y1465952D01*
G02X333668Y1466154I202J0D01*
G01X336488D01*
G02X336690Y1465951I-1J-203D01*
G01Y1465331D01*
G03X336740Y1465199I200J0D01*
G02Y1462283I-1661J-1458D01*
G03X336690Y1462151I150J-132D01*
G01Y1460212D01*
G03X336740Y1460080I200J0D01*
G02Y1457164I-1661J-1458D01*
G03X336690Y1457032I150J-132D01*
G01Y1456412D01*
G37*
G36*
G01X628157Y1466154D02*
X630977D01*
G02X631180Y1465951I0J-203D01*
G01Y1465329D01*
G03X631230Y1465197I200J0D01*
G02Y1462285I-1664J-1456D01*
G03X631180Y1462153I150J-132D01*
G01Y1460210D01*
G03X631230Y1460078I200J0D01*
G02Y1457166I-1664J-1456D01*
G03X631180Y1457034I150J-132D01*
G01Y1456413D01*
G02X630977Y1456210I-203J0D01*
G01X628157D01*
G02X627954Y1456413I0J203D01*
G01Y1457034D01*
G03X627904Y1457166I-200J0D01*
G02Y1460078I1664J1456D01*
G03X627954Y1460210I-150J132D01*
G01Y1462153D01*
G03X627904Y1462285I-200J0D01*
G02Y1465197I1664J1456D01*
G03X627954Y1465329I-150J132D01*
G01Y1465951D01*
G02X628157Y1466154I203J0D01*
G37*
G36*
G01X1133462Y1456412D02*
G02X1133260Y1456210I-202J0D01*
G01X1130440D01*
G02X1130238Y1456413I1J203D01*
G01Y1457032D01*
G03X1130188Y1457164I-200J0D01*
G02Y1460080I1661J1458D01*
G03X1130238Y1460212I-150J132D01*
G01Y1462151D01*
G03X1130188Y1462283I-200J0D01*
G02Y1465199I1661J1458D01*
G03X1130238Y1465331I-150J132D01*
G01Y1465952D01*
G02X1130440Y1466154I202J0D01*
G01X1133260D01*
G02X1133462Y1465951I-1J-203D01*
G01Y1465331D01*
G03X1133512Y1465199I200J0D01*
G02Y1462283I-1661J-1458D01*
G03X1133462Y1462151I150J-132D01*
G01Y1460212D01*
G03X1133512Y1460080I200J0D01*
G02Y1457164I-1661J-1458D01*
G03X1133462Y1457032I150J-132D01*
G01Y1456412D01*
G37*
G36*
G01X1147763Y1466154D02*
X1150583D01*
G02X1150786Y1465951I0J-203D01*
G01Y1465329D01*
G03X1150836Y1465197I200J0D01*
G02Y1462285I-1664J-1456D01*
G03X1150786Y1462153I150J-132D01*
G01Y1460210D01*
G03X1150836Y1460078I200J0D01*
G02Y1457166I-1664J-1456D01*
G03X1150786Y1457034I150J-132D01*
G01Y1456413D01*
G02X1150583Y1456210I-203J0D01*
G01X1147763D01*
G02X1147560Y1456413I0J203D01*
G01Y1457034D01*
G03X1147510Y1457166I-200J0D01*
G02Y1460078I1664J1456D01*
G03X1147560Y1460210I-150J132D01*
G01Y1462153D01*
G03X1147510Y1462285I-200J0D01*
G02Y1465197I1664J1456D01*
G03X1147560Y1465329I-150J132D01*
G01Y1465951D01*
G02X1147763Y1466154I203J0D01*
G37*
G36*
G01X1650125D02*
X1652945D01*
G02X1653148Y1465951I0J-203D01*
G01Y1465329D01*
G03X1653198Y1465197I200J0D01*
G02Y1462285I-1664J-1456D01*
G03X1653148Y1462153I150J-132D01*
G01Y1460210D01*
G03X1653198Y1460078I200J0D01*
G02Y1457166I-1664J-1456D01*
G03X1653148Y1457034I150J-132D01*
G01Y1456413D01*
G02X1652945Y1456210I-203J0D01*
G01X1650125D01*
G02X1649922Y1456413I0J203D01*
G01Y1457034D01*
G03X1649872Y1457166I-200J0D01*
G02Y1460078I1664J1456D01*
G03X1649922Y1460210I-150J132D01*
G01Y1462153D01*
G03X1649872Y1462285I-200J0D01*
G02Y1465197I1664J1456D01*
G03X1649922Y1465329I-150J132D01*
G01Y1465951D01*
G02X1650125Y1466154I203J0D01*
G37*
G36*
G01X1670470Y1456412D02*
G02X1670268Y1456210I-202J0D01*
G01X1667448D01*
G02X1667246Y1456413I1J203D01*
G01Y1457032D01*
G03X1667196Y1457164I-200J0D01*
G02Y1460080I1661J1458D01*
G03X1667246Y1460212I-150J132D01*
G01Y1462151D01*
G03X1667196Y1462283I-200J0D01*
G02Y1465199I1661J1458D01*
G03X1667246Y1465331I-150J132D01*
G01Y1465952D01*
G02X1667448Y1466154I202J0D01*
G01X1670268D01*
G02X1670470Y1465951I-1J-203D01*
G01Y1465331D01*
G03X1670520Y1465199I200J0D01*
G02Y1462283I-1661J-1458D01*
G03X1670470Y1462151I150J-132D01*
G01Y1460212D01*
G03X1670520Y1460080I200J0D01*
G02Y1457164I-1661J-1458D01*
G03X1670470Y1457032I150J-132D01*
G01Y1456412D01*
G37*
G36*
G01X117133Y1470484D02*
X119953D01*
G02X120156Y1470281I0J-203D01*
G01Y1469659D01*
G03X120206Y1469527I200J0D01*
G02Y1466615I-1664J-1456D01*
G03X120156Y1466483I150J-132D01*
G01Y1464541D01*
G03X120206Y1464409I200J0D01*
G02Y1461497I-1664J-1456D01*
G03X120156Y1461365I150J-132D01*
G01Y1460743D01*
G02X119953Y1460540I-203J0D01*
G01X117133D01*
G02X116930Y1460743I0J203D01*
G01Y1461365D01*
G03X116880Y1461497I-200J0D01*
G02Y1464409I1664J1456D01*
G03X116930Y1464541I-150J132D01*
G01Y1466483D01*
G03X116880Y1466615I-200J0D01*
G02Y1469527I1664J1456D01*
G03X116930Y1469659I-150J132D01*
G01Y1470281D01*
G02X117133Y1470484I203J0D01*
G37*
G36*
G01X310706Y1460742D02*
G02X310504Y1460540I-202J0D01*
G01X307684D01*
G02X307482Y1460743I1J203D01*
G01Y1461363D01*
G03X307432Y1461495I-200J0D01*
G02Y1464411I1661J1458D01*
G03X307482Y1464543I-150J132D01*
G01Y1466481D01*
G03X307432Y1466613I-200J0D01*
G02Y1469529I1661J1458D01*
G03X307482Y1469661I-150J132D01*
G01Y1470282D01*
G02X307684Y1470484I202J0D01*
G01X310504D01*
G02X310706Y1470281I-1J-203D01*
G01Y1469661D01*
G03X310756Y1469529I200J0D01*
G02Y1466613I-1661J-1458D01*
G03X310706Y1466481I150J-132D01*
G01Y1464543D01*
G03X310756Y1464411I200J0D01*
G02Y1461495I-1661J-1458D01*
G03X310706Y1461363I150J-132D01*
G01Y1460742D01*
G37*
G36*
G01X325007Y1470484D02*
X327827D01*
G02X328030Y1470281I0J-203D01*
G01Y1469659D01*
G03X328080Y1469527I200J0D01*
G02Y1466615I-1664J-1456D01*
G03X328030Y1466483I150J-132D01*
G01Y1464541D01*
G03X328080Y1464409I200J0D01*
G02Y1461497I-1664J-1456D01*
G03X328030Y1461365I150J-132D01*
G01Y1460743D01*
G02X327827Y1460540I-203J0D01*
G01X325007D01*
G02X324804Y1460743I0J203D01*
G01Y1461365D01*
G03X324754Y1461497I-200J0D01*
G02Y1464409I1664J1456D01*
G03X324804Y1464541I-150J132D01*
G01Y1466483D01*
G03X324754Y1466615I-200J0D01*
G02Y1469527I1664J1456D01*
G03X324804Y1469659I-150J132D01*
G01Y1470281D01*
G02X325007Y1470484I203J0D01*
G37*
G36*
G01X345352Y1460742D02*
G02X345150Y1460540I-202J0D01*
G01X342330D01*
G02X342128Y1460743I1J203D01*
G01Y1461363D01*
G03X342078Y1461495I-200J0D01*
G02Y1464411I1661J1458D01*
G03X342128Y1464543I-150J132D01*
G01Y1466481D01*
G03X342078Y1466613I-200J0D01*
G02Y1469529I1661J1458D01*
G03X342128Y1469661I-150J132D01*
G01Y1470282D01*
G02X342330Y1470484I202J0D01*
G01X345150D01*
G02X345352Y1470281I-1J-203D01*
G01Y1469661D01*
G03X345402Y1469529I200J0D01*
G02Y1466613I-1661J-1458D01*
G03X345352Y1466481I150J-132D01*
G01Y1464543D01*
G03X345402Y1464411I200J0D01*
G02Y1461495I-1661J-1458D01*
G03X345352Y1461363I150J-132D01*
G01Y1460742D01*
G37*
G36*
G01X639840D02*
G02X639638Y1460540I-202J0D01*
G01X636818D01*
G02X636616Y1460743I1J203D01*
G01Y1461363D01*
G03X636566Y1461495I-200J0D01*
G02Y1464411I1661J1458D01*
G03X636616Y1464543I-150J132D01*
G01Y1466481D01*
G03X636566Y1466613I-200J0D01*
G02Y1469529I1661J1458D01*
G03X636616Y1469661I-150J132D01*
G01Y1470282D01*
G02X636818Y1470484I202J0D01*
G01X639638D01*
G02X639840Y1470281I-1J-203D01*
G01Y1469661D01*
G03X639890Y1469529I200J0D01*
G02Y1466613I-1661J-1458D01*
G03X639840Y1466481I150J-132D01*
G01Y1464543D01*
G03X639890Y1464411I200J0D01*
G02Y1461495I-1661J-1458D01*
G03X639840Y1461363I150J-132D01*
G01Y1460742D01*
G37*
G36*
G01X1139101Y1470484D02*
X1141921D01*
G02X1142124Y1470281I0J-203D01*
G01Y1469659D01*
G03X1142174Y1469527I200J0D01*
G02Y1466615I-1664J-1456D01*
G03X1142124Y1466483I150J-132D01*
G01Y1464541D01*
G03X1142174Y1464409I200J0D01*
G02Y1461497I-1664J-1456D01*
G03X1142124Y1461365I150J-132D01*
G01Y1460743D01*
G02X1141921Y1460540I-203J0D01*
G01X1139101D01*
G02X1138898Y1460743I0J203D01*
G01Y1461365D01*
G03X1138848Y1461497I-200J0D01*
G02Y1464409I1664J1456D01*
G03X1138898Y1464541I-150J132D01*
G01Y1466483D01*
G03X1138848Y1466615I-200J0D01*
G02Y1469527I1664J1456D01*
G03X1138898Y1469659I-150J132D01*
G01Y1470281D01*
G02X1139101Y1470484I203J0D01*
G37*
G36*
G01X1159446Y1460742D02*
G02X1159244Y1460540I-202J0D01*
G01X1156424D01*
G02X1156222Y1460743I1J203D01*
G01Y1461363D01*
G03X1156172Y1461495I-200J0D01*
G02Y1464411I1661J1458D01*
G03X1156222Y1464543I-150J132D01*
G01Y1466481D01*
G03X1156172Y1466613I-200J0D01*
G02Y1469529I1661J1458D01*
G03X1156222Y1469661I-150J132D01*
G01Y1470282D01*
G02X1156424Y1470484I202J0D01*
G01X1159244D01*
G02X1159446Y1470281I-1J-203D01*
G01Y1469661D01*
G03X1159496Y1469529I200J0D01*
G02Y1466613I-1661J-1458D01*
G03X1159446Y1466481I150J-132D01*
G01Y1464543D01*
G03X1159496Y1464411I200J0D01*
G02Y1461495I-1661J-1458D01*
G03X1159446Y1461363I150J-132D01*
G01Y1460742D01*
G37*
G36*
G01X1661808D02*
G02X1661606Y1460540I-202J0D01*
G01X1658786D01*
G02X1658584Y1460743I1J203D01*
G01Y1461363D01*
G03X1658534Y1461495I-200J0D01*
G02Y1464411I1661J1458D01*
G03X1658584Y1464543I-150J132D01*
G01Y1466481D01*
G03X1658534Y1466613I-200J0D01*
G02Y1469529I1661J1458D01*
G03X1658584Y1469661I-150J132D01*
G01Y1470282D01*
G02X1658786Y1470484I202J0D01*
G01X1661606D01*
G02X1661808Y1470281I-1J-203D01*
G01Y1469661D01*
G03X1661858Y1469529I200J0D01*
G02Y1466613I-1661J-1458D01*
G03X1661808Y1466481I150J-132D01*
G01Y1464543D01*
G03X1661858Y1464411I200J0D01*
G02Y1461495I-1661J-1458D01*
G03X1661808Y1461363I150J-132D01*
G01Y1460742D01*
G37*
G36*
G01X1676109Y1470484D02*
X1678929D01*
G02X1679132Y1470281I0J-203D01*
G01Y1469659D01*
G03X1679182Y1469527I200J0D01*
G02Y1466615I-1664J-1456D01*
G03X1679132Y1466483I150J-132D01*
G01Y1464541D01*
G03X1679182Y1464409I200J0D01*
G02Y1461497I-1664J-1456D01*
G03X1679132Y1461365I150J-132D01*
G01Y1460743D01*
G02X1678929Y1460540I-203J0D01*
G01X1676109D01*
G02X1675906Y1460743I0J203D01*
G01Y1461365D01*
G03X1675856Y1461497I-200J0D01*
G02Y1464409I1664J1456D01*
G03X1675906Y1464541I-150J132D01*
G01Y1466483D01*
G03X1675856Y1466615I-200J0D01*
G02Y1469527I1664J1456D01*
G03X1675906Y1469659I-150J132D01*
G01Y1470281D01*
G02X1676109Y1470484I203J0D01*
G37*
G36*
G01X111494Y1471766D02*
G02X111292Y1471564I-202J0D01*
G01X108472D01*
G02X108270Y1471767I1J203D01*
G01Y1472387D01*
G03X108220Y1472519I-200J0D01*
G02Y1475435I1661J1458D01*
G03X108270Y1475567I-150J132D01*
G01Y1477505D01*
G03X108220Y1477637I-200J0D01*
G02Y1480553I1661J1458D01*
G03X108270Y1480685I-150J132D01*
G01Y1481306D01*
G02X108472Y1481508I202J0D01*
G01X111292D01*
G02X111494Y1481305I-1J-203D01*
G01Y1480685D01*
G03X111544Y1480553I200J0D01*
G02Y1477637I-1661J-1458D01*
G03X111494Y1477505I150J-132D01*
G01Y1475567D01*
G03X111544Y1475435I200J0D01*
G02Y1472519I-1661J-1458D01*
G03X111494Y1472387I150J-132D01*
G01Y1471766D01*
G37*
G36*
G01X319368D02*
G02X319166Y1471564I-202J0D01*
G01X316346D01*
G02X316144Y1471767I1J203D01*
G01Y1472387D01*
G03X316094Y1472519I-200J0D01*
G02Y1475435I1661J1458D01*
G03X316144Y1475567I-150J132D01*
G01Y1477505D01*
G03X316094Y1477637I-200J0D01*
G02Y1480553I1661J1458D01*
G03X316144Y1480685I-150J132D01*
G01Y1481306D01*
G02X316346Y1481508I202J0D01*
G01X319166D01*
G02X319368Y1481305I-1J-203D01*
G01Y1480685D01*
G03X319418Y1480553I200J0D01*
G02Y1477637I-1661J-1458D01*
G03X319368Y1477505I150J-132D01*
G01Y1475567D01*
G03X319418Y1475435I200J0D01*
G02Y1472519I-1661J-1458D01*
G03X319368Y1472387I150J-132D01*
G01Y1471766D01*
G37*
G36*
G01X336690D02*
G02X336488Y1471564I-202J0D01*
G01X333668D01*
G02X333466Y1471767I1J203D01*
G01Y1472387D01*
G03X333416Y1472519I-200J0D01*
G02Y1475435I1661J1458D01*
G03X333466Y1475567I-150J132D01*
G01Y1477505D01*
G03X333416Y1477637I-200J0D01*
G02Y1480553I1661J1458D01*
G03X333466Y1480685I-150J132D01*
G01Y1481306D01*
G02X333668Y1481508I202J0D01*
G01X336488D01*
G02X336690Y1481305I-1J-203D01*
G01Y1480685D01*
G03X336740Y1480553I200J0D01*
G02Y1477637I-1661J-1458D01*
G03X336690Y1477505I150J-132D01*
G01Y1475567D01*
G03X336740Y1475435I200J0D01*
G02Y1472519I-1661J-1458D01*
G03X336690Y1472387I150J-132D01*
G01Y1471766D01*
G37*
G36*
G01X628157Y1481508D02*
X630977D01*
G02X631180Y1481305I0J-203D01*
G01Y1480683D01*
G03X631230Y1480551I200J0D01*
G02Y1477639I-1664J-1456D01*
G03X631180Y1477507I150J-132D01*
G01Y1475565D01*
G03X631230Y1475433I200J0D01*
G02Y1472521I-1664J-1456D01*
G03X631180Y1472389I150J-132D01*
G01Y1471767D01*
G02X630977Y1471564I-203J0D01*
G01X628157D01*
G02X627954Y1471767I0J203D01*
G01Y1472389D01*
G03X627904Y1472521I-200J0D01*
G02Y1475433I1664J1456D01*
G03X627954Y1475565I-150J132D01*
G01Y1477507D01*
G03X627904Y1477639I-200J0D01*
G02Y1480551I1664J1456D01*
G03X627954Y1480683I-150J132D01*
G01Y1481305D01*
G02X628157Y1481508I203J0D01*
G37*
G36*
G01X1133462Y1471766D02*
G02X1133260Y1471564I-202J0D01*
G01X1130440D01*
G02X1130238Y1471767I1J203D01*
G01Y1472387D01*
G03X1130188Y1472519I-200J0D01*
G02Y1475435I1661J1458D01*
G03X1130238Y1475567I-150J132D01*
G01Y1477505D01*
G03X1130188Y1477637I-200J0D01*
G02Y1480553I1661J1458D01*
G03X1130238Y1480685I-150J132D01*
G01Y1481306D01*
G02X1130440Y1481508I202J0D01*
G01X1133260D01*
G02X1133462Y1481305I-1J-203D01*
G01Y1480685D01*
G03X1133512Y1480553I200J0D01*
G02Y1477637I-1661J-1458D01*
G03X1133462Y1477505I150J-132D01*
G01Y1475567D01*
G03X1133512Y1475435I200J0D01*
G02Y1472519I-1661J-1458D01*
G03X1133462Y1472387I150J-132D01*
G01Y1471766D01*
G37*
G36*
G01X1147763Y1481508D02*
X1150583D01*
G02X1150786Y1481305I0J-203D01*
G01Y1480683D01*
G03X1150836Y1480551I200J0D01*
G02Y1477639I-1664J-1456D01*
G03X1150786Y1477507I150J-132D01*
G01Y1475565D01*
G03X1150836Y1475433I200J0D01*
G02Y1472521I-1664J-1456D01*
G03X1150786Y1472389I150J-132D01*
G01Y1471767D01*
G02X1150583Y1471564I-203J0D01*
G01X1147763D01*
G02X1147560Y1471767I0J203D01*
G01Y1472389D01*
G03X1147510Y1472521I-200J0D01*
G02Y1475433I1664J1456D01*
G03X1147560Y1475565I-150J132D01*
G01Y1477507D01*
G03X1147510Y1477639I-200J0D01*
G02Y1480551I1664J1456D01*
G03X1147560Y1480683I-150J132D01*
G01Y1481305D01*
G02X1147763Y1481508I203J0D01*
G37*
G36*
G01X1650125D02*
X1652945D01*
G02X1653148Y1481305I0J-203D01*
G01Y1480683D01*
G03X1653198Y1480551I200J0D01*
G02Y1477639I-1664J-1456D01*
G03X1653148Y1477507I150J-132D01*
G01Y1475565D01*
G03X1653198Y1475433I200J0D01*
G02Y1472521I-1664J-1456D01*
G03X1653148Y1472389I150J-132D01*
G01Y1471767D01*
G02X1652945Y1471564I-203J0D01*
G01X1650125D01*
G02X1649922Y1471767I0J203D01*
G01Y1472389D01*
G03X1649872Y1472521I-200J0D01*
G02Y1475433I1664J1456D01*
G03X1649922Y1475565I-150J132D01*
G01Y1477507D01*
G03X1649872Y1477639I-200J0D01*
G02Y1480551I1664J1456D01*
G03X1649922Y1480683I-150J132D01*
G01Y1481305D01*
G02X1650125Y1481508I203J0D01*
G37*
G36*
G01X1670470Y1471766D02*
G02X1670268Y1471564I-202J0D01*
G01X1667448D01*
G02X1667246Y1471767I1J203D01*
G01Y1472387D01*
G03X1667196Y1472519I-200J0D01*
G02Y1475435I1661J1458D01*
G03X1667246Y1475567I-150J132D01*
G01Y1477505D01*
G03X1667196Y1477637I-200J0D01*
G02Y1480553I1661J1458D01*
G03X1667246Y1480685I-150J132D01*
G01Y1481306D01*
G02X1667448Y1481508I202J0D01*
G01X1670268D01*
G02X1670470Y1481305I-1J-203D01*
G01Y1480685D01*
G03X1670520Y1480553I200J0D01*
G02Y1477637I-1661J-1458D01*
G03X1670470Y1477505I150J-132D01*
G01Y1475567D01*
G03X1670520Y1475435I200J0D01*
G02Y1472519I-1661J-1458D01*
G03X1670470Y1472387I150J-132D01*
G01Y1471766D01*
G37*
G36*
G01X117133Y1485838D02*
X119953D01*
G02X120156Y1485635I0J-203D01*
G01Y1485014D01*
G03X120206Y1484882I200J0D01*
G02Y1481970I-1664J-1456D01*
G03X120156Y1481838I150J-132D01*
G01Y1479896D01*
G03X120206Y1479764I200J0D01*
G02Y1476852I-1664J-1456D01*
G03X120156Y1476720I150J-132D01*
G01Y1476097D01*
G02X119953Y1475894I-203J0D01*
G01X117133D01*
G02X116930Y1476097I0J203D01*
G01Y1476720D01*
G03X116880Y1476852I-200J0D01*
G02Y1479764I1664J1456D01*
G03X116930Y1479896I-150J132D01*
G01Y1481838D01*
G03X116880Y1481970I-200J0D01*
G02Y1484882I1664J1456D01*
G03X116930Y1485014I-150J132D01*
G01Y1485635D01*
G02X117133Y1485838I203J0D01*
G37*
G36*
G01X310706Y1476096D02*
G02X310504Y1475894I-202J0D01*
G01X307684D01*
G02X307482Y1476097I1J203D01*
G01Y1476718D01*
G03X307432Y1476850I-200J0D01*
G02Y1479766I1661J1458D01*
G03X307482Y1479898I-150J132D01*
G01Y1481836D01*
G03X307432Y1481968I-200J0D01*
G02Y1484884I1661J1458D01*
G03X307482Y1485016I-150J132D01*
G01Y1485636D01*
G02X307684Y1485838I202J0D01*
G01X310504D01*
G02X310706Y1485635I-1J-203D01*
G01Y1485016D01*
G03X310756Y1484884I200J0D01*
G02Y1481968I-1661J-1458D01*
G03X310706Y1481836I150J-132D01*
G01Y1479898D01*
G03X310756Y1479766I200J0D01*
G02Y1476850I-1661J-1458D01*
G03X310706Y1476718I150J-132D01*
G01Y1476096D01*
G37*
G36*
G01X325007Y1485838D02*
X327827D01*
G02X328030Y1485635I0J-203D01*
G01Y1485014D01*
G03X328080Y1484882I200J0D01*
G02Y1481970I-1664J-1456D01*
G03X328030Y1481838I150J-132D01*
G01Y1479896D01*
G03X328080Y1479764I200J0D01*
G02Y1476852I-1664J-1456D01*
G03X328030Y1476720I150J-132D01*
G01Y1476097D01*
G02X327827Y1475894I-203J0D01*
G01X325007D01*
G02X324804Y1476097I0J203D01*
G01Y1476720D01*
G03X324754Y1476852I-200J0D01*
G02Y1479764I1664J1456D01*
G03X324804Y1479896I-150J132D01*
G01Y1481838D01*
G03X324754Y1481970I-200J0D01*
G02Y1484882I1664J1456D01*
G03X324804Y1485014I-150J132D01*
G01Y1485635D01*
G02X325007Y1485838I203J0D01*
G37*
G36*
G01X345352Y1476096D02*
G02X345150Y1475894I-202J0D01*
G01X342330D01*
G02X342128Y1476097I1J203D01*
G01Y1476718D01*
G03X342078Y1476850I-200J0D01*
G02Y1479766I1661J1458D01*
G03X342128Y1479898I-150J132D01*
G01Y1481836D01*
G03X342078Y1481968I-200J0D01*
G02Y1484884I1661J1458D01*
G03X342128Y1485016I-150J132D01*
G01Y1485636D01*
G02X342330Y1485838I202J0D01*
G01X345150D01*
G02X345352Y1485635I-1J-203D01*
G01Y1485016D01*
G03X345402Y1484884I200J0D01*
G02Y1481968I-1661J-1458D01*
G03X345352Y1481836I150J-132D01*
G01Y1479898D01*
G03X345402Y1479766I200J0D01*
G02Y1476850I-1661J-1458D01*
G03X345352Y1476718I150J-132D01*
G01Y1476096D01*
G37*
G36*
G01X639840D02*
G02X639638Y1475894I-202J0D01*
G01X636818D01*
G02X636616Y1476097I1J203D01*
G01Y1476718D01*
G03X636566Y1476850I-200J0D01*
G02Y1479766I1661J1458D01*
G03X636616Y1479898I-150J132D01*
G01Y1481836D01*
G03X636566Y1481968I-200J0D01*
G02Y1484884I1661J1458D01*
G03X636616Y1485016I-150J132D01*
G01Y1485636D01*
G02X636818Y1485838I202J0D01*
G01X639638D01*
G02X639840Y1485635I-1J-203D01*
G01Y1485016D01*
G03X639890Y1484884I200J0D01*
G02Y1481968I-1661J-1458D01*
G03X639840Y1481836I150J-132D01*
G01Y1479898D01*
G03X639890Y1479766I200J0D01*
G02Y1476850I-1661J-1458D01*
G03X639840Y1476718I150J-132D01*
G01Y1476096D01*
G37*
G36*
G01X1139101Y1485838D02*
X1141921D01*
G02X1142124Y1485635I0J-203D01*
G01Y1485014D01*
G03X1142174Y1484882I200J0D01*
G02Y1481970I-1664J-1456D01*
G03X1142124Y1481838I150J-132D01*
G01Y1479896D01*
G03X1142174Y1479764I200J0D01*
G02Y1476852I-1664J-1456D01*
G03X1142124Y1476720I150J-132D01*
G01Y1476097D01*
G02X1141921Y1475894I-203J0D01*
G01X1139101D01*
G02X1138898Y1476097I0J203D01*
G01Y1476720D01*
G03X1138848Y1476852I-200J0D01*
G02Y1479764I1664J1456D01*
G03X1138898Y1479896I-150J132D01*
G01Y1481838D01*
G03X1138848Y1481970I-200J0D01*
G02Y1484882I1664J1456D01*
G03X1138898Y1485014I-150J132D01*
G01Y1485635D01*
G02X1139101Y1485838I203J0D01*
G37*
G36*
G01X1159446Y1476096D02*
G02X1159244Y1475894I-202J0D01*
G01X1156424D01*
G02X1156222Y1476097I1J203D01*
G01Y1476718D01*
G03X1156172Y1476850I-200J0D01*
G02Y1479766I1661J1458D01*
G03X1156222Y1479898I-150J132D01*
G01Y1481836D01*
G03X1156172Y1481968I-200J0D01*
G02Y1484884I1661J1458D01*
G03X1156222Y1485016I-150J132D01*
G01Y1485636D01*
G02X1156424Y1485838I202J0D01*
G01X1159244D01*
G02X1159446Y1485635I-1J-203D01*
G01Y1485016D01*
G03X1159496Y1484884I200J0D01*
G02Y1481968I-1661J-1458D01*
G03X1159446Y1481836I150J-132D01*
G01Y1479898D01*
G03X1159496Y1479766I200J0D01*
G02Y1476850I-1661J-1458D01*
G03X1159446Y1476718I150J-132D01*
G01Y1476096D01*
G37*
G36*
G01X1661808D02*
G02X1661606Y1475894I-202J0D01*
G01X1658786D01*
G02X1658584Y1476097I1J203D01*
G01Y1476718D01*
G03X1658534Y1476850I-200J0D01*
G02Y1479766I1661J1458D01*
G03X1658584Y1479898I-150J132D01*
G01Y1481836D01*
G03X1658534Y1481968I-200J0D01*
G02Y1484884I1661J1458D01*
G03X1658584Y1485016I-150J132D01*
G01Y1485636D01*
G02X1658786Y1485838I202J0D01*
G01X1661606D01*
G02X1661808Y1485635I-1J-203D01*
G01Y1485016D01*
G03X1661858Y1484884I200J0D01*
G02Y1481968I-1661J-1458D01*
G03X1661808Y1481836I150J-132D01*
G01Y1479898D01*
G03X1661858Y1479766I200J0D01*
G02Y1476850I-1661J-1458D01*
G03X1661808Y1476718I150J-132D01*
G01Y1476096D01*
G37*
G36*
G01X1676109Y1485838D02*
X1678929D01*
G02X1679132Y1485635I0J-203D01*
G01Y1485014D01*
G03X1679182Y1484882I200J0D01*
G02Y1481970I-1664J-1456D01*
G03X1679132Y1481838I150J-132D01*
G01Y1479896D01*
G03X1679182Y1479764I200J0D01*
G02Y1476852I-1664J-1456D01*
G03X1679132Y1476720I150J-132D01*
G01Y1476097D01*
G02X1678929Y1475894I-203J0D01*
G01X1676109D01*
G02X1675906Y1476097I0J203D01*
G01Y1476720D01*
G03X1675856Y1476852I-200J0D01*
G02Y1479764I1664J1456D01*
G03X1675906Y1479896I-150J132D01*
G01Y1481838D01*
G03X1675856Y1481970I-200J0D01*
G02Y1484882I1664J1456D01*
G03X1675906Y1485014I-150J132D01*
G01Y1485635D01*
G02X1676109Y1485838I203J0D01*
G37*
G36*
G01X111494Y1487120D02*
G02X111292Y1486918I-202J0D01*
G01X108472D01*
G02X108270Y1487121I1J203D01*
G01Y1487741D01*
G03X108220Y1487873I-200J0D01*
G02Y1490789I1661J1458D01*
G03X108270Y1490921I-150J132D01*
G01Y1492859D01*
G03X108220Y1492991I-200J0D01*
G02Y1495907I1661J1458D01*
G03X108270Y1496039I-150J132D01*
G01Y1496660D01*
G02X108472Y1496862I202J0D01*
G01X111292D01*
G02X111494Y1496659I-1J-203D01*
G01Y1496039D01*
G03X111544Y1495907I200J0D01*
G02Y1492991I-1661J-1458D01*
G03X111494Y1492859I150J-132D01*
G01Y1490921D01*
G03X111544Y1490789I200J0D01*
G02Y1487873I-1661J-1458D01*
G03X111494Y1487741I150J-132D01*
G01Y1487120D01*
G37*
G36*
G01X319368D02*
G02X319166Y1486918I-202J0D01*
G01X316346D01*
G02X316144Y1487121I1J203D01*
G01Y1487741D01*
G03X316094Y1487873I-200J0D01*
G02Y1490789I1661J1458D01*
G03X316144Y1490921I-150J132D01*
G01Y1492859D01*
G03X316094Y1492991I-200J0D01*
G02Y1495907I1661J1458D01*
G03X316144Y1496039I-150J132D01*
G01Y1496660D01*
G02X316346Y1496862I202J0D01*
G01X319166D01*
G02X319368Y1496659I-1J-203D01*
G01Y1496039D01*
G03X319418Y1495907I200J0D01*
G02Y1492991I-1661J-1458D01*
G03X319368Y1492859I150J-132D01*
G01Y1490921D01*
G03X319418Y1490789I200J0D01*
G02Y1487873I-1661J-1458D01*
G03X319368Y1487741I150J-132D01*
G01Y1487120D01*
G37*
G36*
G01X336690D02*
G02X336488Y1486918I-202J0D01*
G01X333668D01*
G02X333466Y1487121I1J203D01*
G01Y1487741D01*
G03X333416Y1487873I-200J0D01*
G02Y1490789I1661J1458D01*
G03X333466Y1490921I-150J132D01*
G01Y1492859D01*
G03X333416Y1492991I-200J0D01*
G02Y1495907I1661J1458D01*
G03X333466Y1496039I-150J132D01*
G01Y1496660D01*
G02X333668Y1496862I202J0D01*
G01X336488D01*
G02X336690Y1496659I-1J-203D01*
G01Y1496039D01*
G03X336740Y1495907I200J0D01*
G02Y1492991I-1661J-1458D01*
G03X336690Y1492859I150J-132D01*
G01Y1490921D01*
G03X336740Y1490789I200J0D01*
G02Y1487873I-1661J-1458D01*
G03X336690Y1487741I150J-132D01*
G01Y1487120D01*
G37*
G36*
G01X628157Y1496862D02*
X630977D01*
G02X631180Y1496659I0J-203D01*
G01Y1496037D01*
G03X631230Y1495905I200J0D01*
G02Y1492993I-1664J-1456D01*
G03X631180Y1492861I150J-132D01*
G01Y1490919D01*
G03X631230Y1490787I200J0D01*
G02Y1487875I-1664J-1456D01*
G03X631180Y1487743I150J-132D01*
G01Y1487121D01*
G02X630977Y1486918I-203J0D01*
G01X628157D01*
G02X627954Y1487121I0J203D01*
G01Y1487743D01*
G03X627904Y1487875I-200J0D01*
G02Y1490787I1664J1456D01*
G03X627954Y1490919I-150J132D01*
G01Y1492861D01*
G03X627904Y1492993I-200J0D01*
G02Y1495905I1664J1456D01*
G03X627954Y1496037I-150J132D01*
G01Y1496659D01*
G02X628157Y1496862I203J0D01*
G37*
G36*
G01X1133462Y1487120D02*
G02X1133260Y1486918I-202J0D01*
G01X1130440D01*
G02X1130238Y1487121I1J203D01*
G01Y1487741D01*
G03X1130188Y1487873I-200J0D01*
G02Y1490789I1661J1458D01*
G03X1130238Y1490921I-150J132D01*
G01Y1492859D01*
G03X1130188Y1492991I-200J0D01*
G02Y1495907I1661J1458D01*
G03X1130238Y1496039I-150J132D01*
G01Y1496660D01*
G02X1130440Y1496862I202J0D01*
G01X1133260D01*
G02X1133462Y1496659I-1J-203D01*
G01Y1496039D01*
G03X1133512Y1495907I200J0D01*
G02Y1492991I-1661J-1458D01*
G03X1133462Y1492859I150J-132D01*
G01Y1490921D01*
G03X1133512Y1490789I200J0D01*
G02Y1487873I-1661J-1458D01*
G03X1133462Y1487741I150J-132D01*
G01Y1487120D01*
G37*
G36*
G01X1147763Y1496862D02*
X1150583D01*
G02X1150786Y1496659I0J-203D01*
G01Y1496037D01*
G03X1150836Y1495905I200J0D01*
G02Y1492993I-1664J-1456D01*
G03X1150786Y1492861I150J-132D01*
G01Y1490919D01*
G03X1150836Y1490787I200J0D01*
G02Y1487875I-1664J-1456D01*
G03X1150786Y1487743I150J-132D01*
G01Y1487121D01*
G02X1150583Y1486918I-203J0D01*
G01X1147763D01*
G02X1147560Y1487121I0J203D01*
G01Y1487743D01*
G03X1147510Y1487875I-200J0D01*
G02Y1490787I1664J1456D01*
G03X1147560Y1490919I-150J132D01*
G01Y1492861D01*
G03X1147510Y1492993I-200J0D01*
G02Y1495905I1664J1456D01*
G03X1147560Y1496037I-150J132D01*
G01Y1496659D01*
G02X1147763Y1496862I203J0D01*
G37*
G36*
G01X1650125D02*
X1652945D01*
G02X1653148Y1496659I0J-203D01*
G01Y1496037D01*
G03X1653198Y1495905I200J0D01*
G02Y1492993I-1664J-1456D01*
G03X1653148Y1492861I150J-132D01*
G01Y1490919D01*
G03X1653198Y1490787I200J0D01*
G02Y1487875I-1664J-1456D01*
G03X1653148Y1487743I150J-132D01*
G01Y1487121D01*
G02X1652945Y1486918I-203J0D01*
G01X1650125D01*
G02X1649922Y1487121I0J203D01*
G01Y1487743D01*
G03X1649872Y1487875I-200J0D01*
G02Y1490787I1664J1456D01*
G03X1649922Y1490919I-150J132D01*
G01Y1492861D01*
G03X1649872Y1492993I-200J0D01*
G02Y1495905I1664J1456D01*
G03X1649922Y1496037I-150J132D01*
G01Y1496659D01*
G02X1650125Y1496862I203J0D01*
G37*
G36*
G01X1670470Y1487120D02*
G02X1670268Y1486918I-202J0D01*
G01X1667448D01*
G02X1667246Y1487121I1J203D01*
G01Y1487741D01*
G03X1667196Y1487873I-200J0D01*
G02Y1490789I1661J1458D01*
G03X1667246Y1490921I-150J132D01*
G01Y1492859D01*
G03X1667196Y1492991I-200J0D01*
G02Y1495907I1661J1458D01*
G03X1667246Y1496039I-150J132D01*
G01Y1496660D01*
G02X1667448Y1496862I202J0D01*
G01X1670268D01*
G02X1670470Y1496659I-1J-203D01*
G01Y1496039D01*
G03X1670520Y1495907I200J0D01*
G02Y1492991I-1661J-1458D01*
G03X1670470Y1492859I150J-132D01*
G01Y1490921D01*
G03X1670520Y1490789I200J0D01*
G02Y1487873I-1661J-1458D01*
G03X1670470Y1487741I150J-132D01*
G01Y1487120D01*
G37*
G36*
G01X117133Y1501192D02*
X119953D01*
G02X120156Y1500989I0J-203D01*
G01Y1500368D01*
G03X120206Y1500236I200J0D01*
G02Y1497324I-1664J-1456D01*
G03X120156Y1497192I150J-132D01*
G01Y1495250D01*
G03X120206Y1495118I200J0D01*
G02Y1492206I-1664J-1456D01*
G03X120156Y1492074I150J-132D01*
G01Y1491451D01*
G02X119953Y1491248I-203J0D01*
G01X117133D01*
G02X116930Y1491451I0J203D01*
G01Y1492074D01*
G03X116880Y1492206I-200J0D01*
G02Y1495118I1664J1456D01*
G03X116930Y1495250I-150J132D01*
G01Y1497192D01*
G03X116880Y1497324I-200J0D01*
G02Y1500236I1664J1456D01*
G03X116930Y1500368I-150J132D01*
G01Y1500989D01*
G02X117133Y1501192I203J0D01*
G37*
G36*
G01X310706Y1491450D02*
G02X310504Y1491248I-202J0D01*
G01X307684D01*
G02X307482Y1491451I1J203D01*
G01Y1492072D01*
G03X307432Y1492204I-200J0D01*
G02Y1495120I1661J1458D01*
G03X307482Y1495252I-150J132D01*
G01Y1497190D01*
G03X307432Y1497322I-200J0D01*
G02Y1500238I1661J1458D01*
G03X307482Y1500370I-150J132D01*
G01Y1500990D01*
G02X307684Y1501192I202J0D01*
G01X310504D01*
G02X310706Y1500989I-1J-203D01*
G01Y1500370D01*
G03X310756Y1500238I200J0D01*
G02Y1497322I-1661J-1458D01*
G03X310706Y1497190I150J-132D01*
G01Y1495252D01*
G03X310756Y1495120I200J0D01*
G02Y1492204I-1661J-1458D01*
G03X310706Y1492072I150J-132D01*
G01Y1491450D01*
G37*
G36*
G01X325007Y1501192D02*
X327827D01*
G02X328030Y1500989I0J-203D01*
G01Y1500368D01*
G03X328080Y1500236I200J0D01*
G02Y1497324I-1664J-1456D01*
G03X328030Y1497192I150J-132D01*
G01Y1495250D01*
G03X328080Y1495118I200J0D01*
G02Y1492206I-1664J-1456D01*
G03X328030Y1492074I150J-132D01*
G01Y1491451D01*
G02X327827Y1491248I-203J0D01*
G01X325007D01*
G02X324804Y1491451I0J203D01*
G01Y1492074D01*
G03X324754Y1492206I-200J0D01*
G02Y1495118I1664J1456D01*
G03X324804Y1495250I-150J132D01*
G01Y1497192D01*
G03X324754Y1497324I-200J0D01*
G02Y1500236I1664J1456D01*
G03X324804Y1500368I-150J132D01*
G01Y1500989D01*
G02X325007Y1501192I203J0D01*
G37*
G36*
G01X345352Y1491450D02*
G02X345150Y1491248I-202J0D01*
G01X342330D01*
G02X342128Y1491451I1J203D01*
G01Y1492072D01*
G03X342078Y1492204I-200J0D01*
G02Y1495120I1661J1458D01*
G03X342128Y1495252I-150J132D01*
G01Y1497190D01*
G03X342078Y1497322I-200J0D01*
G02Y1500238I1661J1458D01*
G03X342128Y1500370I-150J132D01*
G01Y1500990D01*
G02X342330Y1501192I202J0D01*
G01X345150D01*
G02X345352Y1500989I-1J-203D01*
G01Y1500370D01*
G03X345402Y1500238I200J0D01*
G02Y1497322I-1661J-1458D01*
G03X345352Y1497190I150J-132D01*
G01Y1495252D01*
G03X345402Y1495120I200J0D01*
G02Y1492204I-1661J-1458D01*
G03X345352Y1492072I150J-132D01*
G01Y1491450D01*
G37*
G36*
G01X639840D02*
G02X639638Y1491248I-202J0D01*
G01X636818D01*
G02X636616Y1491451I1J203D01*
G01Y1492072D01*
G03X636566Y1492204I-200J0D01*
G02Y1495120I1661J1458D01*
G03X636616Y1495252I-150J132D01*
G01Y1497190D01*
G03X636566Y1497322I-200J0D01*
G02Y1500238I1661J1458D01*
G03X636616Y1500370I-150J132D01*
G01Y1500990D01*
G02X636818Y1501192I202J0D01*
G01X639638D01*
G02X639840Y1500989I-1J-203D01*
G01Y1500370D01*
G03X639890Y1500238I200J0D01*
G02Y1497322I-1661J-1458D01*
G03X639840Y1497190I150J-132D01*
G01Y1495252D01*
G03X639890Y1495120I200J0D01*
G02Y1492204I-1661J-1458D01*
G03X639840Y1492072I150J-132D01*
G01Y1491450D01*
G37*
G36*
G01X1139101Y1501192D02*
X1141921D01*
G02X1142124Y1500989I0J-203D01*
G01Y1500368D01*
G03X1142174Y1500236I200J0D01*
G02Y1497324I-1664J-1456D01*
G03X1142124Y1497192I150J-132D01*
G01Y1495250D01*
G03X1142174Y1495118I200J0D01*
G02Y1492206I-1664J-1456D01*
G03X1142124Y1492074I150J-132D01*
G01Y1491451D01*
G02X1141921Y1491248I-203J0D01*
G01X1139101D01*
G02X1138898Y1491451I0J203D01*
G01Y1492074D01*
G03X1138848Y1492206I-200J0D01*
G02Y1495118I1664J1456D01*
G03X1138898Y1495250I-150J132D01*
G01Y1497192D01*
G03X1138848Y1497324I-200J0D01*
G02Y1500236I1664J1456D01*
G03X1138898Y1500368I-150J132D01*
G01Y1500989D01*
G02X1139101Y1501192I203J0D01*
G37*
G36*
G01X1159446Y1491450D02*
G02X1159244Y1491248I-202J0D01*
G01X1156424D01*
G02X1156222Y1491451I1J203D01*
G01Y1492072D01*
G03X1156172Y1492204I-200J0D01*
G02Y1495120I1661J1458D01*
G03X1156222Y1495252I-150J132D01*
G01Y1497190D01*
G03X1156172Y1497322I-200J0D01*
G02Y1500238I1661J1458D01*
G03X1156222Y1500370I-150J132D01*
G01Y1500990D01*
G02X1156424Y1501192I202J0D01*
G01X1159244D01*
G02X1159446Y1500989I-1J-203D01*
G01Y1500370D01*
G03X1159496Y1500238I200J0D01*
G02Y1497322I-1661J-1458D01*
G03X1159446Y1497190I150J-132D01*
G01Y1495252D01*
G03X1159496Y1495120I200J0D01*
G02Y1492204I-1661J-1458D01*
G03X1159446Y1492072I150J-132D01*
G01Y1491450D01*
G37*
G36*
G01X1661808D02*
G02X1661606Y1491248I-202J0D01*
G01X1658786D01*
G02X1658584Y1491451I1J203D01*
G01Y1492072D01*
G03X1658534Y1492204I-200J0D01*
G02Y1495120I1661J1458D01*
G03X1658584Y1495252I-150J132D01*
G01Y1497190D01*
G03X1658534Y1497322I-200J0D01*
G02Y1500238I1661J1458D01*
G03X1658584Y1500370I-150J132D01*
G01Y1500990D01*
G02X1658786Y1501192I202J0D01*
G01X1661606D01*
G02X1661808Y1500989I-1J-203D01*
G01Y1500370D01*
G03X1661858Y1500238I200J0D01*
G02Y1497322I-1661J-1458D01*
G03X1661808Y1497190I150J-132D01*
G01Y1495252D01*
G03X1661858Y1495120I200J0D01*
G02Y1492204I-1661J-1458D01*
G03X1661808Y1492072I150J-132D01*
G01Y1491450D01*
G37*
G36*
G01X1676109Y1501192D02*
X1678929D01*
G02X1679132Y1500989I0J-203D01*
G01Y1500368D01*
G03X1679182Y1500236I200J0D01*
G02Y1497324I-1664J-1456D01*
G03X1679132Y1497192I150J-132D01*
G01Y1495250D01*
G03X1679182Y1495118I200J0D01*
G02Y1492206I-1664J-1456D01*
G03X1679132Y1492074I150J-132D01*
G01Y1491451D01*
G02X1678929Y1491248I-203J0D01*
G01X1676109D01*
G02X1675906Y1491451I0J203D01*
G01Y1492074D01*
G03X1675856Y1492206I-200J0D01*
G02Y1495118I1664J1456D01*
G03X1675906Y1495250I-150J132D01*
G01Y1497192D01*
G03X1675856Y1497324I-200J0D01*
G02Y1500236I1664J1456D01*
G03X1675906Y1500368I-150J132D01*
G01Y1500989D01*
G02X1676109Y1501192I203J0D01*
G37*
G36*
G01X108472Y1512216D02*
X111292D01*
G02X111494Y1512014I0J-202D01*
G01Y1511394D01*
G03X111544Y1511262I200J0D01*
G02Y1508346I-1661J-1458D01*
G03X111494Y1508214I150J-132D01*
G01Y1506275D01*
G03X111544Y1506143I200J0D01*
G02Y1503227I-1661J-1458D01*
G03X111494Y1503095I150J-132D01*
G01Y1502476D01*
G02X111292Y1502274I-202J0D01*
G01X108472D01*
G02X108270Y1502476I0J202D01*
G01Y1503095D01*
G03X108220Y1503227I-200J0D01*
G02Y1506143I1661J1458D01*
G03X108270Y1506275I-150J132D01*
G01Y1508214D01*
G03X108220Y1508346I-200J0D01*
G02Y1511262I1661J1458D01*
G03X108270Y1511394I-150J132D01*
G01Y1512014D01*
G02X108472Y1512216I202J0D01*
G37*
G36*
G01X316346D02*
X319166D01*
G02X319368Y1512014I0J-202D01*
G01Y1511394D01*
G03X319418Y1511262I200J0D01*
G02Y1508346I-1661J-1458D01*
G03X319368Y1508214I150J-132D01*
G01Y1506275D01*
G03X319418Y1506143I200J0D01*
G02Y1503227I-1661J-1458D01*
G03X319368Y1503095I150J-132D01*
G01Y1502476D01*
G02X319166Y1502274I-202J0D01*
G01X316346D01*
G02X316144Y1502476I0J202D01*
G01Y1503095D01*
G03X316094Y1503227I-200J0D01*
G02Y1506143I1661J1458D01*
G03X316144Y1506275I-150J132D01*
G01Y1508214D01*
G03X316094Y1508346I-200J0D01*
G02Y1511262I1661J1458D01*
G03X316144Y1511394I-150J132D01*
G01Y1512014D01*
G02X316346Y1512216I202J0D01*
G37*
G36*
G01X333668D02*
X336488D01*
G02X336690Y1512014I0J-202D01*
G01Y1511394D01*
G03X336740Y1511262I200J0D01*
G02Y1508346I-1661J-1458D01*
G03X336690Y1508214I150J-132D01*
G01Y1506275D01*
G03X336740Y1506143I200J0D01*
G02Y1503227I-1661J-1458D01*
G03X336690Y1503095I150J-132D01*
G01Y1502476D01*
G02X336488Y1502274I-202J0D01*
G01X333668D01*
G02X333466Y1502476I0J202D01*
G01Y1503095D01*
G03X333416Y1503227I-200J0D01*
G02Y1506143I1661J1458D01*
G03X333466Y1506275I-150J132D01*
G01Y1508214D01*
G03X333416Y1508346I-200J0D01*
G02Y1511262I1661J1458D01*
G03X333466Y1511394I-150J132D01*
G01Y1512014D01*
G02X333668Y1512216I202J0D01*
G37*
G36*
G01X1130440D02*
X1133260D01*
G02X1133462Y1512014I0J-202D01*
G01Y1511394D01*
G03X1133512Y1511262I200J0D01*
G02Y1508346I-1661J-1458D01*
G03X1133462Y1508214I150J-132D01*
G01Y1506275D01*
G03X1133512Y1506143I200J0D01*
G02Y1503227I-1661J-1458D01*
G03X1133462Y1503095I150J-132D01*
G01Y1502476D01*
G02X1133260Y1502274I-202J0D01*
G01X1130440D01*
G02X1130238Y1502476I0J202D01*
G01Y1503095D01*
G03X1130188Y1503227I-200J0D01*
G02Y1506143I1661J1458D01*
G03X1130238Y1506275I-150J132D01*
G01Y1508214D01*
G03X1130188Y1508346I-200J0D01*
G02Y1511262I1661J1458D01*
G03X1130238Y1511394I-150J132D01*
G01Y1512014D01*
G02X1130440Y1512216I202J0D01*
G37*
G36*
G01X1667448D02*
X1670268D01*
G02X1670470Y1512014I0J-202D01*
G01Y1511394D01*
G03X1670520Y1511262I200J0D01*
G02Y1508346I-1661J-1458D01*
G03X1670470Y1508214I150J-132D01*
G01Y1506275D01*
G03X1670520Y1506143I200J0D01*
G02Y1503227I-1661J-1458D01*
G03X1670470Y1503095I150J-132D01*
G01Y1502476D01*
G02X1670268Y1502274I-202J0D01*
G01X1667448D01*
G02X1667246Y1502476I0J202D01*
G01Y1503095D01*
G03X1667196Y1503227I-200J0D01*
G02Y1506143I1661J1458D01*
G03X1667246Y1506275I-150J132D01*
G01Y1508214D01*
G03X1667196Y1508346I-200J0D01*
G02Y1511262I1661J1458D01*
G03X1667246Y1511394I-150J132D01*
G01Y1512014D01*
G02X1667448Y1512216I202J0D01*
G37*
G36*
G01X628156Y1502274D02*
G02X627954Y1502476I0J202D01*
G01Y1503097D01*
G03X627904Y1503229I-200J0D01*
G02Y1506141I1664J1456D01*
G03X627954Y1506273I-150J132D01*
G01Y1508216D01*
G03X627904Y1508348I-200J0D01*
G02Y1511260I1664J1456D01*
G03X627954Y1511392I-150J132D01*
G01Y1512014D01*
G02X628157Y1512216I203J-1D01*
G01X630978D01*
G02X631180Y1512014I0J-202D01*
G01Y1511392D01*
G03X631230Y1511260I200J0D01*
G02Y1508348I-1664J-1456D01*
G03X631180Y1508216I150J-132D01*
G01Y1506273D01*
G03X631230Y1506141I200J0D01*
G02Y1503229I-1664J-1456D01*
G03X631180Y1503097I150J-132D01*
G01Y1502476D01*
G02X630977Y1502274I-203J1D01*
G01X628156D01*
G37*
G36*
G01X1147762D02*
G02X1147560Y1502476I0J202D01*
G01Y1503097D01*
G03X1147510Y1503229I-200J0D01*
G02Y1506141I1664J1456D01*
G03X1147560Y1506273I-150J132D01*
G01Y1508216D01*
G03X1147510Y1508348I-200J0D01*
G02Y1511260I1664J1456D01*
G03X1147560Y1511392I-150J132D01*
G01Y1512014D01*
G02X1147763Y1512216I203J-1D01*
G01X1150584D01*
G02X1150786Y1512014I0J-202D01*
G01Y1511392D01*
G03X1150836Y1511260I200J0D01*
G02Y1508348I-1664J-1456D01*
G03X1150786Y1508216I150J-132D01*
G01Y1506273D01*
G03X1150836Y1506141I200J0D01*
G02Y1503229I-1664J-1456D01*
G03X1150786Y1503097I150J-132D01*
G01Y1502476D01*
G02X1150583Y1502274I-203J1D01*
G01X1147762D01*
G37*
G36*
G01X1650124D02*
G02X1649922Y1502476I0J202D01*
G01Y1503097D01*
G03X1649872Y1503229I-200J0D01*
G02Y1506141I1664J1456D01*
G03X1649922Y1506273I-150J132D01*
G01Y1508216D01*
G03X1649872Y1508348I-200J0D01*
G02Y1511260I1664J1456D01*
G03X1649922Y1511392I-150J132D01*
G01Y1512014D01*
G02X1650125Y1512216I203J-1D01*
G01X1652946D01*
G02X1653148Y1512014I0J-202D01*
G01Y1511392D01*
G03X1653198Y1511260I200J0D01*
G02Y1508348I-1664J-1456D01*
G03X1653148Y1508216I150J-132D01*
G01Y1506273D01*
G03X1653198Y1506141I200J0D01*
G02Y1503229I-1664J-1456D01*
G03X1653148Y1503097I150J-132D01*
G01Y1502476D01*
G02X1652945Y1502274I-203J1D01*
G01X1650124D01*
G37*
G36*
G01X307684Y1516546D02*
X310504D01*
G02X310706Y1516344I0J-202D01*
G01Y1515724D01*
G03X310756Y1515592I200J0D01*
G02Y1512676I-1661J-1458D01*
G03X310706Y1512544I150J-132D01*
G01Y1510606D01*
G03X310756Y1510474I200J0D01*
G02Y1507558I-1661J-1458D01*
G03X310706Y1507426I150J-132D01*
G01Y1506806D01*
G02X310504Y1506604I-202J0D01*
G01X307684D01*
G02X307482Y1506806I0J202D01*
G01Y1507426D01*
G03X307432Y1507558I-200J0D01*
G02Y1510474I1661J1458D01*
G03X307482Y1510606I-150J132D01*
G01Y1512544D01*
G03X307432Y1512676I-200J0D01*
G02Y1515592I1661J1458D01*
G03X307482Y1515724I-150J132D01*
G01Y1516344D01*
G02X307684Y1516546I202J0D01*
G37*
G36*
G01X342330D02*
X345150D01*
G02X345352Y1516344I0J-202D01*
G01Y1515724D01*
G03X345402Y1515592I200J0D01*
G02Y1512676I-1661J-1458D01*
G03X345352Y1512544I150J-132D01*
G01Y1510606D01*
G03X345402Y1510474I200J0D01*
G02Y1507558I-1661J-1458D01*
G03X345352Y1507426I150J-132D01*
G01Y1506806D01*
G02X345150Y1506604I-202J0D01*
G01X342330D01*
G02X342128Y1506806I0J202D01*
G01Y1507426D01*
G03X342078Y1507558I-200J0D01*
G02Y1510474I1661J1458D01*
G03X342128Y1510606I-150J132D01*
G01Y1512544D01*
G03X342078Y1512676I-200J0D01*
G02Y1515592I1661J1458D01*
G03X342128Y1515724I-150J132D01*
G01Y1516344D01*
G02X342330Y1516546I202J0D01*
G37*
G36*
G01X636818D02*
X639638D01*
G02X639840Y1516344I0J-202D01*
G01Y1515724D01*
G03X639890Y1515592I200J0D01*
G02Y1512676I-1661J-1458D01*
G03X639840Y1512544I150J-132D01*
G01Y1510606D01*
G03X639890Y1510474I200J0D01*
G02Y1507558I-1661J-1458D01*
G03X639840Y1507426I150J-132D01*
G01Y1506806D01*
G02X639638Y1506604I-202J0D01*
G01X636818D01*
G02X636616Y1506806I0J202D01*
G01Y1507426D01*
G03X636566Y1507558I-200J0D01*
G02Y1510474I1661J1458D01*
G03X636616Y1510606I-150J132D01*
G01Y1512544D01*
G03X636566Y1512676I-200J0D01*
G02Y1515592I1661J1458D01*
G03X636616Y1515724I-150J132D01*
G01Y1516344D01*
G02X636818Y1516546I202J0D01*
G37*
G36*
G01X1156424D02*
X1159244D01*
G02X1159446Y1516344I0J-202D01*
G01Y1515724D01*
G03X1159496Y1515592I200J0D01*
G02Y1512676I-1661J-1458D01*
G03X1159446Y1512544I150J-132D01*
G01Y1510606D01*
G03X1159496Y1510474I200J0D01*
G02Y1507558I-1661J-1458D01*
G03X1159446Y1507426I150J-132D01*
G01Y1506806D01*
G02X1159244Y1506604I-202J0D01*
G01X1156424D01*
G02X1156222Y1506806I0J202D01*
G01Y1507426D01*
G03X1156172Y1507558I-200J0D01*
G02Y1510474I1661J1458D01*
G03X1156222Y1510606I-150J132D01*
G01Y1512544D01*
G03X1156172Y1512676I-200J0D01*
G02Y1515592I1661J1458D01*
G03X1156222Y1515724I-150J132D01*
G01Y1516344D01*
G02X1156424Y1516546I202J0D01*
G37*
G36*
G01X1658786D02*
X1661606D01*
G02X1661808Y1516344I0J-202D01*
G01Y1515724D01*
G03X1661858Y1515592I200J0D01*
G02Y1512676I-1661J-1458D01*
G03X1661808Y1512544I150J-132D01*
G01Y1510606D01*
G03X1661858Y1510474I200J0D01*
G02Y1507558I-1661J-1458D01*
G03X1661808Y1507426I150J-132D01*
G01Y1506806D01*
G02X1661606Y1506604I-202J0D01*
G01X1658786D01*
G02X1658584Y1506806I0J202D01*
G01Y1507426D01*
G03X1658534Y1507558I-200J0D01*
G02Y1510474I1661J1458D01*
G03X1658584Y1510606I-150J132D01*
G01Y1512544D01*
G03X1658534Y1512676I-200J0D01*
G02Y1515592I1661J1458D01*
G03X1658584Y1515724I-150J132D01*
G01Y1516344D01*
G02X1658786Y1516546I202J0D01*
G37*
G36*
G01X117132Y1506604D02*
G02X116930Y1506806I0J202D01*
G01Y1507428D01*
G03X116880Y1507560I-200J0D01*
G02Y1510472I1664J1456D01*
G03X116930Y1510604I-150J132D01*
G01Y1512546D01*
G03X116880Y1512678I-200J0D01*
G02Y1515590I1664J1456D01*
G03X116930Y1515722I-150J132D01*
G01Y1516344D01*
G02X117133Y1516546I203J-1D01*
G01X119954D01*
G02X120156Y1516344I0J-202D01*
G01Y1515722D01*
G03X120206Y1515590I200J0D01*
G02Y1512678I-1664J-1456D01*
G03X120156Y1512546I150J-132D01*
G01Y1510604D01*
G03X120206Y1510472I200J0D01*
G02Y1507560I-1664J-1456D01*
G03X120156Y1507428I150J-132D01*
G01Y1506806D01*
G02X119953Y1506604I-203J1D01*
G01X117132D01*
G37*
G36*
G01X325006D02*
G02X324804Y1506806I0J202D01*
G01Y1507428D01*
G03X324754Y1507560I-200J0D01*
G02Y1510472I1664J1456D01*
G03X324804Y1510604I-150J132D01*
G01Y1512546D01*
G03X324754Y1512678I-200J0D01*
G02Y1515590I1664J1456D01*
G03X324804Y1515722I-150J132D01*
G01Y1516344D01*
G02X325007Y1516546I203J-1D01*
G01X327828D01*
G02X328030Y1516344I0J-202D01*
G01Y1515722D01*
G03X328080Y1515590I200J0D01*
G02Y1512678I-1664J-1456D01*
G03X328030Y1512546I150J-132D01*
G01Y1510604D01*
G03X328080Y1510472I200J0D01*
G02Y1507560I-1664J-1456D01*
G03X328030Y1507428I150J-132D01*
G01Y1506806D01*
G02X327827Y1506604I-203J1D01*
G01X325006D01*
G37*
G36*
G01X1139100D02*
G02X1138898Y1506806I0J202D01*
G01Y1507428D01*
G03X1138848Y1507560I-200J0D01*
G02Y1510472I1664J1456D01*
G03X1138898Y1510604I-150J132D01*
G01Y1512546D01*
G03X1138848Y1512678I-200J0D01*
G02Y1515590I1664J1456D01*
G03X1138898Y1515722I-150J132D01*
G01Y1516344D01*
G02X1139101Y1516546I203J-1D01*
G01X1141922D01*
G02X1142124Y1516344I0J-202D01*
G01Y1515722D01*
G03X1142174Y1515590I200J0D01*
G02Y1512678I-1664J-1456D01*
G03X1142124Y1512546I150J-132D01*
G01Y1510604D01*
G03X1142174Y1510472I200J0D01*
G02Y1507560I-1664J-1456D01*
G03X1142124Y1507428I150J-132D01*
G01Y1506806D01*
G02X1141921Y1506604I-203J1D01*
G01X1139100D01*
G37*
G36*
G01X1676108D02*
G02X1675906Y1506806I0J202D01*
G01Y1507428D01*
G03X1675856Y1507560I-200J0D01*
G02Y1510472I1664J1456D01*
G03X1675906Y1510604I-150J132D01*
G01Y1512546D01*
G03X1675856Y1512678I-200J0D01*
G02Y1515590I1664J1456D01*
G03X1675906Y1515722I-150J132D01*
G01Y1516344D01*
G02X1676109Y1516546I203J-1D01*
G01X1678930D01*
G02X1679132Y1516344I0J-202D01*
G01Y1515722D01*
G03X1679182Y1515590I200J0D01*
G02Y1512678I-1664J-1456D01*
G03X1679132Y1512546I150J-132D01*
G01Y1510604D01*
G03X1679182Y1510472I200J0D01*
G02Y1507560I-1664J-1456D01*
G03X1679132Y1507428I150J-132D01*
G01Y1506806D01*
G02X1678929Y1506604I-203J1D01*
G01X1676108D01*
G37*
G36*
G01X454929Y1568516D02*
X457749D01*
G02X457952Y1568313I0J-203D01*
G01Y1567691D01*
G03X458002Y1567559I200J0D01*
G02Y1564647I-1664J-1456D01*
G03X457952Y1564515I150J-132D01*
G01Y1562573D01*
G03X458002Y1562441I200J0D01*
G02Y1559529I-1664J-1456D01*
G03X457952Y1559397I150J-132D01*
G01Y1558775D01*
G02X457749Y1558572I-203J0D01*
G01X454929D01*
G02X454726Y1558775I0J203D01*
G01Y1559397D01*
G03X454676Y1559529I-200J0D01*
G02Y1562441I1664J1456D01*
G03X454726Y1562573I-150J132D01*
G01Y1564515D01*
G03X454676Y1564647I-200J0D01*
G02Y1567559I1664J1456D01*
G03X454726Y1567691I-150J132D01*
G01Y1568313D01*
G02X454929Y1568516I203J0D01*
G37*
G36*
G01X475274Y1558774D02*
G02X475072Y1558572I-202J0D01*
G01X472252D01*
G02X472050Y1558775I1J203D01*
G01Y1559395D01*
G03X472000Y1559527I-200J0D01*
G02Y1562443I1661J1458D01*
G03X472050Y1562575I-150J132D01*
G01Y1564513D01*
G03X472000Y1564645I-200J0D01*
G02Y1567561I1661J1458D01*
G03X472050Y1567693I-150J132D01*
G01Y1568314D01*
G02X472252Y1568516I202J0D01*
G01X475072D01*
G02X475274Y1568313I-1J-203D01*
G01Y1567693D01*
G03X475324Y1567561I200J0D01*
G02Y1564645I-1661J-1458D01*
G03X475274Y1564513I150J-132D01*
G01Y1562575D01*
G03X475324Y1562443I200J0D01*
G02Y1559527I-1661J-1458D01*
G03X475274Y1559395I150J-132D01*
G01Y1558774D01*
G37*
G36*
G01X489575Y1568516D02*
X492395D01*
G02X492598Y1568313I0J-203D01*
G01Y1567691D01*
G03X492648Y1567559I200J0D01*
G02Y1564647I-1664J-1456D01*
G03X492598Y1564515I150J-132D01*
G01Y1562573D01*
G03X492648Y1562441I200J0D01*
G02Y1559529I-1664J-1456D01*
G03X492598Y1559397I150J-132D01*
G01Y1558775D01*
G02X492395Y1558572I-203J0D01*
G01X489575D01*
G02X489372Y1558775I0J203D01*
G01Y1559397D01*
G03X489322Y1559529I-200J0D01*
G02Y1562441I1664J1456D01*
G03X489372Y1562573I-150J132D01*
G01Y1564515D01*
G03X489322Y1564647I-200J0D01*
G02Y1567559I1664J1456D01*
G03X489372Y1567691I-150J132D01*
G01Y1568313D01*
G02X489575Y1568516I203J0D01*
G37*
G36*
G01X506897D02*
X509717D01*
G02X509920Y1568313I0J-203D01*
G01Y1567691D01*
G03X509970Y1567559I200J0D01*
G02Y1564647I-1664J-1456D01*
G03X509920Y1564515I150J-132D01*
G01Y1562573D01*
G03X509970Y1562441I200J0D01*
G02Y1559529I-1664J-1456D01*
G03X509920Y1559397I150J-132D01*
G01Y1558775D01*
G02X509717Y1558572I-203J0D01*
G01X506897D01*
G02X506694Y1558775I0J203D01*
G01Y1559397D01*
G03X506644Y1559529I-200J0D01*
G02Y1562441I1664J1456D01*
G03X506694Y1562573I-150J132D01*
G01Y1564515D01*
G03X506644Y1564647I-200J0D01*
G02Y1567559I1664J1456D01*
G03X506694Y1567691I-150J132D01*
G01Y1568313D01*
G02X506897Y1568516I203J0D01*
G37*
G36*
G01X1497242Y1558774D02*
G02X1497040Y1558572I-202J0D01*
G01X1494220D01*
G02X1494018Y1558775I1J203D01*
G01Y1559395D01*
G03X1493968Y1559527I-200J0D01*
G02Y1562443I1661J1458D01*
G03X1494018Y1562575I-150J132D01*
G01Y1564513D01*
G03X1493968Y1564645I-200J0D01*
G02Y1567561I1661J1458D01*
G03X1494018Y1567693I-150J132D01*
G01Y1568314D01*
G02X1494220Y1568516I202J0D01*
G01X1497040D01*
G02X1497242Y1568313I-1J-203D01*
G01Y1567693D01*
G03X1497292Y1567561I200J0D01*
G02Y1564645I-1661J-1458D01*
G03X1497242Y1564513I150J-132D01*
G01Y1562575D01*
G03X1497292Y1562443I200J0D01*
G02Y1559527I-1661J-1458D01*
G03X1497242Y1559395I150J-132D01*
G01Y1558774D01*
G37*
G36*
G01X1511543Y1568516D02*
X1514363D01*
G02X1514566Y1568313I0J-203D01*
G01Y1567691D01*
G03X1514616Y1567559I200J0D01*
G02Y1564647I-1664J-1456D01*
G03X1514566Y1564515I150J-132D01*
G01Y1562573D01*
G03X1514616Y1562441I200J0D01*
G02Y1559529I-1664J-1456D01*
G03X1514566Y1559397I150J-132D01*
G01Y1558775D01*
G02X1514363Y1558572I-203J0D01*
G01X1511543D01*
G02X1511340Y1558775I0J203D01*
G01Y1559397D01*
G03X1511290Y1559529I-200J0D01*
G02Y1562441I1664J1456D01*
G03X1511340Y1562573I-150J132D01*
G01Y1564515D01*
G03X1511290Y1564647I-200J0D01*
G02Y1567559I1664J1456D01*
G03X1511340Y1567691I-150J132D01*
G01Y1568313D01*
G02X1511543Y1568516I203J0D01*
G37*
G36*
G01X1528865D02*
X1531685D01*
G02X1531888Y1568313I0J-203D01*
G01Y1567691D01*
G03X1531938Y1567559I200J0D01*
G02Y1564647I-1664J-1456D01*
G03X1531888Y1564515I150J-132D01*
G01Y1562573D01*
G03X1531938Y1562441I200J0D01*
G02Y1559529I-1664J-1456D01*
G03X1531888Y1559397I150J-132D01*
G01Y1558775D01*
G02X1531685Y1558572I-203J0D01*
G01X1528865D01*
G02X1528662Y1558775I0J203D01*
G01Y1559397D01*
G03X1528612Y1559529I-200J0D01*
G02Y1562441I1664J1456D01*
G03X1528662Y1562573I-150J132D01*
G01Y1564515D01*
G03X1528612Y1564647I-200J0D01*
G02Y1567559I1664J1456D01*
G03X1528662Y1567691I-150J132D01*
G01Y1568313D01*
G02X1528865Y1568516I203J0D01*
G37*
G36*
G01X463590Y1572846D02*
X466410D01*
G02X466612Y1572644I0J-202D01*
G01Y1572024D01*
G03X466662Y1571892I200J0D01*
G02Y1568976I-1661J-1458D01*
G03X466612Y1568844I150J-132D01*
G01Y1566905D01*
G03X466662Y1566773I200J0D01*
G02Y1563857I-1661J-1458D01*
G03X466612Y1563725I150J-132D01*
G01Y1563106D01*
G02X466410Y1562904I-202J0D01*
G01X463590D01*
G02X463388Y1563106I0J202D01*
G01Y1563725D01*
G03X463338Y1563857I-200J0D01*
G02Y1566773I1661J1458D01*
G03X463388Y1566905I-150J132D01*
G01Y1568844D01*
G03X463338Y1568976I-200J0D01*
G02Y1571892I1661J1458D01*
G03X463388Y1572024I-150J132D01*
G01Y1572644D01*
G02X463590Y1572846I202J0D01*
G37*
G36*
G01X498236D02*
X501056D01*
G02X501258Y1572644I0J-202D01*
G01Y1572024D01*
G03X501308Y1571892I200J0D01*
G02Y1568976I-1661J-1458D01*
G03X501258Y1568844I150J-132D01*
G01Y1566905D01*
G03X501308Y1566773I200J0D01*
G02Y1563857I-1661J-1458D01*
G03X501258Y1563725I150J-132D01*
G01Y1563106D01*
G02X501056Y1562904I-202J0D01*
G01X498236D01*
G02X498034Y1563106I0J202D01*
G01Y1563725D01*
G03X497984Y1563857I-200J0D01*
G02Y1566773I1661J1458D01*
G03X498034Y1566905I-150J132D01*
G01Y1568844D01*
G03X497984Y1568976I-200J0D01*
G02Y1571892I1661J1458D01*
G03X498034Y1572024I-150J132D01*
G01Y1572644D01*
G02X498236Y1572846I202J0D01*
G37*
G36*
G01X1485558D02*
X1488378D01*
G02X1488580Y1572644I0J-202D01*
G01Y1572024D01*
G03X1488630Y1571892I200J0D01*
G02Y1568976I-1661J-1458D01*
G03X1488580Y1568844I150J-132D01*
G01Y1566905D01*
G03X1488630Y1566773I200J0D01*
G02Y1563857I-1661J-1458D01*
G03X1488580Y1563725I150J-132D01*
G01Y1563106D01*
G02X1488378Y1562904I-202J0D01*
G01X1485558D01*
G02X1485356Y1563106I0J202D01*
G01Y1563725D01*
G03X1485306Y1563857I-200J0D01*
G02Y1566773I1661J1458D01*
G03X1485356Y1566905I-150J132D01*
G01Y1568844D01*
G03X1485306Y1568976I-200J0D01*
G02Y1571892I1661J1458D01*
G03X1485356Y1572024I-150J132D01*
G01Y1572644D01*
G02X1485558Y1572846I202J0D01*
G37*
G36*
G01X1520204D02*
X1523024D01*
G02X1523226Y1572644I0J-202D01*
G01Y1572024D01*
G03X1523276Y1571892I200J0D01*
G02Y1568976I-1661J-1458D01*
G03X1523226Y1568844I150J-132D01*
G01Y1566905D01*
G03X1523276Y1566773I200J0D01*
G02Y1563857I-1661J-1458D01*
G03X1523226Y1563725I150J-132D01*
G01Y1563106D01*
G02X1523024Y1562904I-202J0D01*
G01X1520204D01*
G02X1520002Y1563106I0J202D01*
G01Y1563725D01*
G03X1519952Y1563857I-200J0D01*
G02Y1566773I1661J1458D01*
G03X1520002Y1566905I-150J132D01*
G01Y1568844D01*
G03X1519952Y1568976I-200J0D01*
G02Y1571892I1661J1458D01*
G03X1520002Y1572024I-150J132D01*
G01Y1572644D01*
G02X1520204Y1572846I202J0D01*
G37*
G36*
G01X480912Y1562904D02*
G02X480710Y1563106I0J202D01*
G01Y1563727D01*
G03X480660Y1563859I-200J0D01*
G02Y1566771I1664J1456D01*
G03X480710Y1566903I-150J132D01*
G01Y1568846D01*
G03X480660Y1568978I-200J0D01*
G02Y1571890I1664J1456D01*
G03X480710Y1572022I-150J132D01*
G01Y1572644D01*
G02X480913Y1572846I203J-1D01*
G01X483734D01*
G02X483936Y1572644I0J-202D01*
G01Y1572022D01*
G03X483986Y1571890I200J0D01*
G02Y1568978I-1664J-1456D01*
G03X483936Y1568846I150J-132D01*
G01Y1566903D01*
G03X483986Y1566771I200J0D01*
G02Y1563859I-1664J-1456D01*
G03X483936Y1563727I150J-132D01*
G01Y1563106D01*
G02X483733Y1562904I-203J1D01*
G01X480912D01*
G37*
G36*
G01X1502880D02*
G02X1502678Y1563106I0J202D01*
G01Y1563727D01*
G03X1502628Y1563859I-200J0D01*
G02Y1566771I1664J1456D01*
G03X1502678Y1566903I-150J132D01*
G01Y1568846D01*
G03X1502628Y1568978I-200J0D01*
G02Y1571890I1664J1456D01*
G03X1502678Y1572022I-150J132D01*
G01Y1572644D01*
G02X1502881Y1572846I203J-1D01*
G01X1505702D01*
G02X1505904Y1572644I0J-202D01*
G01Y1572022D01*
G03X1505954Y1571890I200J0D01*
G02Y1568978I-1664J-1456D01*
G03X1505904Y1568846I150J-132D01*
G01Y1566903D01*
G03X1505954Y1566771I200J0D01*
G02Y1563859I-1664J-1456D01*
G03X1505904Y1563727I150J-132D01*
G01Y1563106D01*
G02X1505701Y1562904I-203J1D01*
G01X1502880D01*
G37*
G36*
G01X1537526D02*
G02X1537324Y1563106I0J202D01*
G01Y1563727D01*
G03X1537274Y1563859I-200J0D01*
G02Y1566771I1664J1456D01*
G03X1537324Y1566903I-150J132D01*
G01Y1568846D01*
G03X1537274Y1568978I-200J0D01*
G02Y1571890I1664J1456D01*
G03X1537324Y1572022I-150J132D01*
G01Y1572644D01*
G02X1537527Y1572846I203J-1D01*
G01X1540348D01*
G02X1540550Y1572644I0J-202D01*
G01Y1572022D01*
G03X1540600Y1571890I200J0D01*
G02Y1568978I-1664J-1456D01*
G03X1540550Y1568846I150J-132D01*
G01Y1566903D01*
G03X1540600Y1566771I200J0D01*
G02Y1563859I-1664J-1456D01*
G03X1540550Y1563727I150J-132D01*
G01Y1563106D01*
G02X1540347Y1562904I-203J1D01*
G01X1537526D01*
G37*
G36*
G01X454929Y1583870D02*
X457749D01*
G02X457952Y1583667I0J-203D01*
G01Y1583045D01*
G03X458002Y1582913I200J0D01*
G02Y1580001I-1664J-1456D01*
G03X457952Y1579869I150J-132D01*
G01Y1577927D01*
G03X458002Y1577795I200J0D01*
G02Y1574883I-1664J-1456D01*
G03X457952Y1574751I150J-132D01*
G01Y1574129D01*
G02X457749Y1573926I-203J0D01*
G01X454929D01*
G02X454726Y1574129I0J203D01*
G01Y1574751D01*
G03X454676Y1574883I-200J0D01*
G02Y1577795I1664J1456D01*
G03X454726Y1577927I-150J132D01*
G01Y1579869D01*
G03X454676Y1580001I-200J0D01*
G02Y1582913I1664J1456D01*
G03X454726Y1583045I-150J132D01*
G01Y1583667D01*
G02X454929Y1583870I203J0D01*
G37*
G36*
G01X475274Y1574128D02*
G02X475072Y1573926I-202J0D01*
G01X472252D01*
G02X472050Y1574129I1J203D01*
G01Y1574749D01*
G03X472000Y1574881I-200J0D01*
G02Y1577797I1661J1458D01*
G03X472050Y1577929I-150J132D01*
G01Y1579867D01*
G03X472000Y1579999I-200J0D01*
G02Y1582915I1661J1458D01*
G03X472050Y1583047I-150J132D01*
G01Y1583668D01*
G02X472252Y1583870I202J0D01*
G01X475072D01*
G02X475274Y1583667I-1J-203D01*
G01Y1583047D01*
G03X475324Y1582915I200J0D01*
G02Y1579999I-1661J-1458D01*
G03X475274Y1579867I150J-132D01*
G01Y1577929D01*
G03X475324Y1577797I200J0D01*
G02Y1574881I-1661J-1458D01*
G03X475274Y1574749I150J-132D01*
G01Y1574128D01*
G37*
G36*
G01X489575Y1583870D02*
X492395D01*
G02X492598Y1583667I0J-203D01*
G01Y1583045D01*
G03X492648Y1582913I200J0D01*
G02Y1580001I-1664J-1456D01*
G03X492598Y1579869I150J-132D01*
G01Y1577927D01*
G03X492648Y1577795I200J0D01*
G02Y1574883I-1664J-1456D01*
G03X492598Y1574751I150J-132D01*
G01Y1574129D01*
G02X492395Y1573926I-203J0D01*
G01X489575D01*
G02X489372Y1574129I0J203D01*
G01Y1574751D01*
G03X489322Y1574883I-200J0D01*
G02Y1577795I1664J1456D01*
G03X489372Y1577927I-150J132D01*
G01Y1579869D01*
G03X489322Y1580001I-200J0D01*
G02Y1582913I1664J1456D01*
G03X489372Y1583045I-150J132D01*
G01Y1583667D01*
G02X489575Y1583870I203J0D01*
G37*
G36*
G01X506897D02*
X509717D01*
G02X509920Y1583667I0J-203D01*
G01Y1583045D01*
G03X509970Y1582913I200J0D01*
G02Y1580001I-1664J-1456D01*
G03X509920Y1579869I150J-132D01*
G01Y1577927D01*
G03X509970Y1577795I200J0D01*
G02Y1574883I-1664J-1456D01*
G03X509920Y1574751I150J-132D01*
G01Y1574129D01*
G02X509717Y1573926I-203J0D01*
G01X506897D01*
G02X506694Y1574129I0J203D01*
G01Y1574751D01*
G03X506644Y1574883I-200J0D01*
G02Y1577795I1664J1456D01*
G03X506694Y1577927I-150J132D01*
G01Y1579869D01*
G03X506644Y1580001I-200J0D01*
G02Y1582913I1664J1456D01*
G03X506694Y1583045I-150J132D01*
G01Y1583667D01*
G02X506897Y1583870I203J0D01*
G37*
G36*
G01X1497242Y1574128D02*
G02X1497040Y1573926I-202J0D01*
G01X1494220D01*
G02X1494018Y1574129I1J203D01*
G01Y1574749D01*
G03X1493968Y1574881I-200J0D01*
G02Y1577797I1661J1458D01*
G03X1494018Y1577929I-150J132D01*
G01Y1579867D01*
G03X1493968Y1579999I-200J0D01*
G02Y1582915I1661J1458D01*
G03X1494018Y1583047I-150J132D01*
G01Y1583668D01*
G02X1494220Y1583870I202J0D01*
G01X1497040D01*
G02X1497242Y1583667I-1J-203D01*
G01Y1583047D01*
G03X1497292Y1582915I200J0D01*
G02Y1579999I-1661J-1458D01*
G03X1497242Y1579867I150J-132D01*
G01Y1577929D01*
G03X1497292Y1577797I200J0D01*
G02Y1574881I-1661J-1458D01*
G03X1497242Y1574749I150J-132D01*
G01Y1574128D01*
G37*
G36*
G01X1511543Y1583870D02*
X1514363D01*
G02X1514566Y1583667I0J-203D01*
G01Y1583045D01*
G03X1514616Y1582913I200J0D01*
G02Y1580001I-1664J-1456D01*
G03X1514566Y1579869I150J-132D01*
G01Y1577927D01*
G03X1514616Y1577795I200J0D01*
G02Y1574883I-1664J-1456D01*
G03X1514566Y1574751I150J-132D01*
G01Y1574129D01*
G02X1514363Y1573926I-203J0D01*
G01X1511543D01*
G02X1511340Y1574129I0J203D01*
G01Y1574751D01*
G03X1511290Y1574883I-200J0D01*
G02Y1577795I1664J1456D01*
G03X1511340Y1577927I-150J132D01*
G01Y1579869D01*
G03X1511290Y1580001I-200J0D01*
G02Y1582913I1664J1456D01*
G03X1511340Y1583045I-150J132D01*
G01Y1583667D01*
G02X1511543Y1583870I203J0D01*
G37*
G36*
G01X1528865D02*
X1531685D01*
G02X1531888Y1583667I0J-203D01*
G01Y1583045D01*
G03X1531938Y1582913I200J0D01*
G02Y1580001I-1664J-1456D01*
G03X1531888Y1579869I150J-132D01*
G01Y1577927D01*
G03X1531938Y1577795I200J0D01*
G02Y1574883I-1664J-1456D01*
G03X1531888Y1574751I150J-132D01*
G01Y1574129D01*
G02X1531685Y1573926I-203J0D01*
G01X1528865D01*
G02X1528662Y1574129I0J203D01*
G01Y1574751D01*
G03X1528612Y1574883I-200J0D01*
G02Y1577795I1664J1456D01*
G03X1528662Y1577927I-150J132D01*
G01Y1579869D01*
G03X1528612Y1580001I-200J0D01*
G02Y1582913I1664J1456D01*
G03X1528662Y1583045I-150J132D01*
G01Y1583667D01*
G02X1528865Y1583870I203J0D01*
G37*
G36*
G01X463590Y1588200D02*
X466410D01*
G02X466612Y1587998I0J-202D01*
G01Y1587378D01*
G03X466662Y1587246I200J0D01*
G02Y1584330I-1661J-1458D01*
G03X466612Y1584198I150J-132D01*
G01Y1582260D01*
G03X466662Y1582128I200J0D01*
G02Y1579212I-1661J-1458D01*
G03X466612Y1579080I150J-132D01*
G01Y1578460D01*
G02X466410Y1578258I-202J0D01*
G01X463590D01*
G02X463388Y1578460I0J202D01*
G01Y1579080D01*
G03X463338Y1579212I-200J0D01*
G02Y1582128I1661J1458D01*
G03X463388Y1582260I-150J132D01*
G01Y1584198D01*
G03X463338Y1584330I-200J0D01*
G02Y1587246I1661J1458D01*
G03X463388Y1587378I-150J132D01*
G01Y1587998D01*
G02X463590Y1588200I202J0D01*
G37*
G36*
G01X498236D02*
X501056D01*
G02X501258Y1587998I0J-202D01*
G01Y1587378D01*
G03X501308Y1587246I200J0D01*
G02Y1584330I-1661J-1458D01*
G03X501258Y1584198I150J-132D01*
G01Y1582260D01*
G03X501308Y1582128I200J0D01*
G02Y1579212I-1661J-1458D01*
G03X501258Y1579080I150J-132D01*
G01Y1578460D01*
G02X501056Y1578258I-202J0D01*
G01X498236D01*
G02X498034Y1578460I0J202D01*
G01Y1579080D01*
G03X497984Y1579212I-200J0D01*
G02Y1582128I1661J1458D01*
G03X498034Y1582260I-150J132D01*
G01Y1584198D01*
G03X497984Y1584330I-200J0D01*
G02Y1587246I1661J1458D01*
G03X498034Y1587378I-150J132D01*
G01Y1587998D01*
G02X498236Y1588200I202J0D01*
G37*
G36*
G01X1485558D02*
X1488378D01*
G02X1488580Y1587998I0J-202D01*
G01Y1587378D01*
G03X1488630Y1587246I200J0D01*
G02Y1584330I-1661J-1458D01*
G03X1488580Y1584198I150J-132D01*
G01Y1582260D01*
G03X1488630Y1582128I200J0D01*
G02Y1579212I-1661J-1458D01*
G03X1488580Y1579080I150J-132D01*
G01Y1578460D01*
G02X1488378Y1578258I-202J0D01*
G01X1485558D01*
G02X1485356Y1578460I0J202D01*
G01Y1579080D01*
G03X1485306Y1579212I-200J0D01*
G02Y1582128I1661J1458D01*
G03X1485356Y1582260I-150J132D01*
G01Y1584198D01*
G03X1485306Y1584330I-200J0D01*
G02Y1587246I1661J1458D01*
G03X1485356Y1587378I-150J132D01*
G01Y1587998D01*
G02X1485558Y1588200I202J0D01*
G37*
G36*
G01X1520204D02*
X1523024D01*
G02X1523226Y1587998I0J-202D01*
G01Y1587378D01*
G03X1523276Y1587246I200J0D01*
G02Y1584330I-1661J-1458D01*
G03X1523226Y1584198I150J-132D01*
G01Y1582260D01*
G03X1523276Y1582128I200J0D01*
G02Y1579212I-1661J-1458D01*
G03X1523226Y1579080I150J-132D01*
G01Y1578460D01*
G02X1523024Y1578258I-202J0D01*
G01X1520204D01*
G02X1520002Y1578460I0J202D01*
G01Y1579080D01*
G03X1519952Y1579212I-200J0D01*
G02Y1582128I1661J1458D01*
G03X1520002Y1582260I-150J132D01*
G01Y1584198D01*
G03X1519952Y1584330I-200J0D01*
G02Y1587246I1661J1458D01*
G03X1520002Y1587378I-150J132D01*
G01Y1587998D01*
G02X1520204Y1588200I202J0D01*
G37*
G36*
G01X480912Y1578258D02*
G02X480710Y1578460I0J202D01*
G01Y1579082D01*
G03X480660Y1579214I-200J0D01*
G02Y1582126I1664J1456D01*
G03X480710Y1582258I-150J132D01*
G01Y1584200D01*
G03X480660Y1584332I-200J0D01*
G02Y1587244I1664J1456D01*
G03X480710Y1587376I-150J132D01*
G01Y1587998D01*
G02X480913Y1588200I203J-1D01*
G01X483734D01*
G02X483936Y1587998I0J-202D01*
G01Y1587376D01*
G03X483986Y1587244I200J0D01*
G02Y1584332I-1664J-1456D01*
G03X483936Y1584200I150J-132D01*
G01Y1582258D01*
G03X483986Y1582126I200J0D01*
G02Y1579214I-1664J-1456D01*
G03X483936Y1579082I150J-132D01*
G01Y1578460D01*
G02X483733Y1578258I-203J1D01*
G01X480912D01*
G37*
G36*
G01X1502880D02*
G02X1502678Y1578460I0J202D01*
G01Y1579082D01*
G03X1502628Y1579214I-200J0D01*
G02Y1582126I1664J1456D01*
G03X1502678Y1582258I-150J132D01*
G01Y1584200D01*
G03X1502628Y1584332I-200J0D01*
G02Y1587244I1664J1456D01*
G03X1502678Y1587376I-150J132D01*
G01Y1587998D01*
G02X1502881Y1588200I203J-1D01*
G01X1505702D01*
G02X1505904Y1587998I0J-202D01*
G01Y1587376D01*
G03X1505954Y1587244I200J0D01*
G02Y1584332I-1664J-1456D01*
G03X1505904Y1584200I150J-132D01*
G01Y1582258D01*
G03X1505954Y1582126I200J0D01*
G02Y1579214I-1664J-1456D01*
G03X1505904Y1579082I150J-132D01*
G01Y1578460D01*
G02X1505701Y1578258I-203J1D01*
G01X1502880D01*
G37*
G36*
G01X1537526D02*
G02X1537324Y1578460I0J202D01*
G01Y1579082D01*
G03X1537274Y1579214I-200J0D01*
G02Y1582126I1664J1456D01*
G03X1537324Y1582258I-150J132D01*
G01Y1584200D01*
G03X1537274Y1584332I-200J0D01*
G02Y1587244I1664J1456D01*
G03X1537324Y1587376I-150J132D01*
G01Y1587998D01*
G02X1537527Y1588200I203J-1D01*
G01X1540348D01*
G02X1540550Y1587998I0J-202D01*
G01Y1587376D01*
G03X1540600Y1587244I200J0D01*
G02Y1584332I-1664J-1456D01*
G03X1540550Y1584200I150J-132D01*
G01Y1582258D01*
G03X1540600Y1582126I200J0D01*
G02Y1579214I-1664J-1456D01*
G03X1540550Y1579082I150J-132D01*
G01Y1578460D01*
G02X1540347Y1578258I-203J1D01*
G01X1537526D01*
G37*
G36*
G01X454929Y1599224D02*
X457749D01*
G02X457952Y1599021I0J-203D01*
G01Y1598399D01*
G03X458002Y1598267I200J0D01*
G02Y1595355I-1664J-1456D01*
G03X457952Y1595223I150J-132D01*
G01Y1593281D01*
G03X458002Y1593149I200J0D01*
G02Y1590237I-1664J-1456D01*
G03X457952Y1590105I150J-132D01*
G01Y1589483D01*
G02X457749Y1589280I-203J0D01*
G01X454929D01*
G02X454726Y1589483I0J203D01*
G01Y1590105D01*
G03X454676Y1590237I-200J0D01*
G02Y1593149I1664J1456D01*
G03X454726Y1593281I-150J132D01*
G01Y1595223D01*
G03X454676Y1595355I-200J0D01*
G02Y1598267I1664J1456D01*
G03X454726Y1598399I-150J132D01*
G01Y1599021D01*
G02X454929Y1599224I203J0D01*
G37*
G36*
G01X475274Y1589482D02*
G02X475072Y1589280I-202J0D01*
G01X472252D01*
G02X472050Y1589483I1J203D01*
G01Y1590103D01*
G03X472000Y1590235I-200J0D01*
G02Y1593151I1661J1458D01*
G03X472050Y1593283I-150J132D01*
G01Y1595221D01*
G03X472000Y1595353I-200J0D01*
G02Y1598269I1661J1458D01*
G03X472050Y1598401I-150J132D01*
G01Y1599022D01*
G02X472252Y1599224I202J0D01*
G01X475072D01*
G02X475274Y1599021I-1J-203D01*
G01Y1598401D01*
G03X475324Y1598269I200J0D01*
G02Y1595353I-1661J-1458D01*
G03X475274Y1595221I150J-132D01*
G01Y1593283D01*
G03X475324Y1593151I200J0D01*
G02Y1590235I-1661J-1458D01*
G03X475274Y1590103I150J-132D01*
G01Y1589482D01*
G37*
G36*
G01X489575Y1599224D02*
X492395D01*
G02X492598Y1599021I0J-203D01*
G01Y1598399D01*
G03X492648Y1598267I200J0D01*
G02Y1595355I-1664J-1456D01*
G03X492598Y1595223I150J-132D01*
G01Y1593281D01*
G03X492648Y1593149I200J0D01*
G02Y1590237I-1664J-1456D01*
G03X492598Y1590105I150J-132D01*
G01Y1589483D01*
G02X492395Y1589280I-203J0D01*
G01X489575D01*
G02X489372Y1589483I0J203D01*
G01Y1590105D01*
G03X489322Y1590237I-200J0D01*
G02Y1593149I1664J1456D01*
G03X489372Y1593281I-150J132D01*
G01Y1595223D01*
G03X489322Y1595355I-200J0D01*
G02Y1598267I1664J1456D01*
G03X489372Y1598399I-150J132D01*
G01Y1599021D01*
G02X489575Y1599224I203J0D01*
G37*
G36*
G01X506897D02*
X509717D01*
G02X509920Y1599021I0J-203D01*
G01Y1598399D01*
G03X509970Y1598267I200J0D01*
G02Y1595355I-1664J-1456D01*
G03X509920Y1595223I150J-132D01*
G01Y1593281D01*
G03X509970Y1593149I200J0D01*
G02Y1590237I-1664J-1456D01*
G03X509920Y1590105I150J-132D01*
G01Y1589483D01*
G02X509717Y1589280I-203J0D01*
G01X506897D01*
G02X506694Y1589483I0J203D01*
G01Y1590105D01*
G03X506644Y1590237I-200J0D01*
G02Y1593149I1664J1456D01*
G03X506694Y1593281I-150J132D01*
G01Y1595223D01*
G03X506644Y1595355I-200J0D01*
G02Y1598267I1664J1456D01*
G03X506694Y1598399I-150J132D01*
G01Y1599021D01*
G02X506897Y1599224I203J0D01*
G37*
G36*
G01X1497242Y1589482D02*
G02X1497040Y1589280I-202J0D01*
G01X1494220D01*
G02X1494018Y1589483I1J203D01*
G01Y1590103D01*
G03X1493968Y1590235I-200J0D01*
G02Y1593151I1661J1458D01*
G03X1494018Y1593283I-150J132D01*
G01Y1595221D01*
G03X1493968Y1595353I-200J0D01*
G02Y1598269I1661J1458D01*
G03X1494018Y1598401I-150J132D01*
G01Y1599022D01*
G02X1494220Y1599224I202J0D01*
G01X1497040D01*
G02X1497242Y1599021I-1J-203D01*
G01Y1598401D01*
G03X1497292Y1598269I200J0D01*
G02Y1595353I-1661J-1458D01*
G03X1497242Y1595221I150J-132D01*
G01Y1593283D01*
G03X1497292Y1593151I200J0D01*
G02Y1590235I-1661J-1458D01*
G03X1497242Y1590103I150J-132D01*
G01Y1589482D01*
G37*
G36*
G01X1511543Y1599224D02*
X1514363D01*
G02X1514566Y1599021I0J-203D01*
G01Y1598399D01*
G03X1514616Y1598267I200J0D01*
G02Y1595355I-1664J-1456D01*
G03X1514566Y1595223I150J-132D01*
G01Y1593281D01*
G03X1514616Y1593149I200J0D01*
G02Y1590237I-1664J-1456D01*
G03X1514566Y1590105I150J-132D01*
G01Y1589483D01*
G02X1514363Y1589280I-203J0D01*
G01X1511543D01*
G02X1511340Y1589483I0J203D01*
G01Y1590105D01*
G03X1511290Y1590237I-200J0D01*
G02Y1593149I1664J1456D01*
G03X1511340Y1593281I-150J132D01*
G01Y1595223D01*
G03X1511290Y1595355I-200J0D01*
G02Y1598267I1664J1456D01*
G03X1511340Y1598399I-150J132D01*
G01Y1599021D01*
G02X1511543Y1599224I203J0D01*
G37*
G36*
G01X1528865D02*
X1531685D01*
G02X1531888Y1599021I0J-203D01*
G01Y1598399D01*
G03X1531938Y1598267I200J0D01*
G02Y1595355I-1664J-1456D01*
G03X1531888Y1595223I150J-132D01*
G01Y1593281D01*
G03X1531938Y1593149I200J0D01*
G02Y1590237I-1664J-1456D01*
G03X1531888Y1590105I150J-132D01*
G01Y1589483D01*
G02X1531685Y1589280I-203J0D01*
G01X1528865D01*
G02X1528662Y1589483I0J203D01*
G01Y1590105D01*
G03X1528612Y1590237I-200J0D01*
G02Y1593149I1664J1456D01*
G03X1528662Y1593281I-150J132D01*
G01Y1595223D01*
G03X1528612Y1595355I-200J0D01*
G02Y1598267I1664J1456D01*
G03X1528662Y1598399I-150J132D01*
G01Y1599021D01*
G02X1528865Y1599224I203J0D01*
G37*
G36*
G01X463590Y1603554D02*
X466410D01*
G02X466612Y1603352I0J-202D01*
G01Y1602732D01*
G03X466662Y1602600I200J0D01*
G02Y1599684I-1661J-1458D01*
G03X466612Y1599552I150J-132D01*
G01Y1597614D01*
G03X466662Y1597482I200J0D01*
G02Y1594566I-1661J-1458D01*
G03X466612Y1594434I150J-132D01*
G01Y1593814D01*
G02X466410Y1593612I-202J0D01*
G01X463590D01*
G02X463388Y1593814I0J202D01*
G01Y1594434D01*
G03X463338Y1594566I-200J0D01*
G02Y1597482I1661J1458D01*
G03X463388Y1597614I-150J132D01*
G01Y1599552D01*
G03X463338Y1599684I-200J0D01*
G02Y1602600I1661J1458D01*
G03X463388Y1602732I-150J132D01*
G01Y1603352D01*
G02X463590Y1603554I202J0D01*
G37*
G36*
G01X498236D02*
X501056D01*
G02X501258Y1603352I0J-202D01*
G01Y1602732D01*
G03X501308Y1602600I200J0D01*
G02Y1599684I-1661J-1458D01*
G03X501258Y1599552I150J-132D01*
G01Y1597614D01*
G03X501308Y1597482I200J0D01*
G02Y1594566I-1661J-1458D01*
G03X501258Y1594434I150J-132D01*
G01Y1593814D01*
G02X501056Y1593612I-202J0D01*
G01X498236D01*
G02X498034Y1593814I0J202D01*
G01Y1594434D01*
G03X497984Y1594566I-200J0D01*
G02Y1597482I1661J1458D01*
G03X498034Y1597614I-150J132D01*
G01Y1599552D01*
G03X497984Y1599684I-200J0D01*
G02Y1602600I1661J1458D01*
G03X498034Y1602732I-150J132D01*
G01Y1603352D01*
G02X498236Y1603554I202J0D01*
G37*
G36*
G01X1485558D02*
X1488378D01*
G02X1488580Y1603352I0J-202D01*
G01Y1602732D01*
G03X1488630Y1602600I200J0D01*
G02Y1599684I-1661J-1458D01*
G03X1488580Y1599552I150J-132D01*
G01Y1597614D01*
G03X1488630Y1597482I200J0D01*
G02Y1594566I-1661J-1458D01*
G03X1488580Y1594434I150J-132D01*
G01Y1593814D01*
G02X1488378Y1593612I-202J0D01*
G01X1485558D01*
G02X1485356Y1593814I0J202D01*
G01Y1594434D01*
G03X1485306Y1594566I-200J0D01*
G02Y1597482I1661J1458D01*
G03X1485356Y1597614I-150J132D01*
G01Y1599552D01*
G03X1485306Y1599684I-200J0D01*
G02Y1602600I1661J1458D01*
G03X1485356Y1602732I-150J132D01*
G01Y1603352D01*
G02X1485558Y1603554I202J0D01*
G37*
G36*
G01X1520204D02*
X1523024D01*
G02X1523226Y1603352I0J-202D01*
G01Y1602732D01*
G03X1523276Y1602600I200J0D01*
G02Y1599684I-1661J-1458D01*
G03X1523226Y1599552I150J-132D01*
G01Y1597614D01*
G03X1523276Y1597482I200J0D01*
G02Y1594566I-1661J-1458D01*
G03X1523226Y1594434I150J-132D01*
G01Y1593814D01*
G02X1523024Y1593612I-202J0D01*
G01X1520204D01*
G02X1520002Y1593814I0J202D01*
G01Y1594434D01*
G03X1519952Y1594566I-200J0D01*
G02Y1597482I1661J1458D01*
G03X1520002Y1597614I-150J132D01*
G01Y1599552D01*
G03X1519952Y1599684I-200J0D01*
G02Y1602600I1661J1458D01*
G03X1520002Y1602732I-150J132D01*
G01Y1603352D01*
G02X1520204Y1603554I202J0D01*
G37*
G36*
G01X480912Y1593612D02*
G02X480710Y1593814I0J202D01*
G01Y1594436D01*
G03X480660Y1594568I-200J0D01*
G02Y1597480I1664J1456D01*
G03X480710Y1597612I-150J132D01*
G01Y1599554D01*
G03X480660Y1599686I-200J0D01*
G02Y1602598I1664J1456D01*
G03X480710Y1602730I-150J132D01*
G01Y1603352D01*
G02X480913Y1603554I203J-1D01*
G01X483734D01*
G02X483936Y1603352I0J-202D01*
G01Y1602730D01*
G03X483986Y1602598I200J0D01*
G02Y1599686I-1664J-1456D01*
G03X483936Y1599554I150J-132D01*
G01Y1597612D01*
G03X483986Y1597480I200J0D01*
G02Y1594568I-1664J-1456D01*
G03X483936Y1594436I150J-132D01*
G01Y1593814D01*
G02X483733Y1593612I-203J1D01*
G01X480912D01*
G37*
G36*
G01X1502880D02*
G02X1502678Y1593814I0J202D01*
G01Y1594436D01*
G03X1502628Y1594568I-200J0D01*
G02Y1597480I1664J1456D01*
G03X1502678Y1597612I-150J132D01*
G01Y1599554D01*
G03X1502628Y1599686I-200J0D01*
G02Y1602598I1664J1456D01*
G03X1502678Y1602730I-150J132D01*
G01Y1603352D01*
G02X1502881Y1603554I203J-1D01*
G01X1505702D01*
G02X1505904Y1603352I0J-202D01*
G01Y1602730D01*
G03X1505954Y1602598I200J0D01*
G02Y1599686I-1664J-1456D01*
G03X1505904Y1599554I150J-132D01*
G01Y1597612D01*
G03X1505954Y1597480I200J0D01*
G02Y1594568I-1664J-1456D01*
G03X1505904Y1594436I150J-132D01*
G01Y1593814D01*
G02X1505701Y1593612I-203J1D01*
G01X1502880D01*
G37*
G36*
G01X1537526D02*
G02X1537324Y1593814I0J202D01*
G01Y1594436D01*
G03X1537274Y1594568I-200J0D01*
G02Y1597480I1664J1456D01*
G03X1537324Y1597612I-150J132D01*
G01Y1599554D01*
G03X1537274Y1599686I-200J0D01*
G02Y1602598I1664J1456D01*
G03X1537324Y1602730I-150J132D01*
G01Y1603352D01*
G02X1537527Y1603554I203J-1D01*
G01X1540348D01*
G02X1540550Y1603352I0J-202D01*
G01Y1602730D01*
G03X1540600Y1602598I200J0D01*
G02Y1599686I-1664J-1456D01*
G03X1540550Y1599554I150J-132D01*
G01Y1597612D01*
G03X1540600Y1597480I200J0D01*
G02Y1594568I-1664J-1456D01*
G03X1540550Y1594436I150J-132D01*
G01Y1593814D01*
G02X1540347Y1593612I-203J1D01*
G01X1537526D01*
G37*
G36*
G01X472252Y1614578D02*
X475072D01*
G02X475274Y1614376I0J-202D01*
G01Y1613756D01*
G03X475324Y1613624I200J0D01*
G02Y1610708I-1661J-1458D01*
G03X475274Y1610576I150J-132D01*
G01Y1608638D01*
G03X475324Y1608506I200J0D01*
G02Y1605590I-1661J-1458D01*
G03X475274Y1605458I150J-132D01*
G01Y1604838D01*
G02X475072Y1604636I-202J0D01*
G01X472252D01*
G02X472050Y1604838I0J202D01*
G01Y1605458D01*
G03X472000Y1605590I-200J0D01*
G02Y1608506I1661J1458D01*
G03X472050Y1608638I-150J132D01*
G01Y1610576D01*
G03X472000Y1610708I-200J0D01*
G02Y1613624I1661J1458D01*
G03X472050Y1613756I-150J132D01*
G01Y1614376D01*
G02X472252Y1614578I202J0D01*
G37*
G36*
G01X1494220D02*
X1497040D01*
G02X1497242Y1614376I0J-202D01*
G01Y1613756D01*
G03X1497292Y1613624I200J0D01*
G02Y1610708I-1661J-1458D01*
G03X1497242Y1610576I150J-132D01*
G01Y1608638D01*
G03X1497292Y1608506I200J0D01*
G02Y1605590I-1661J-1458D01*
G03X1497242Y1605458I150J-132D01*
G01Y1604838D01*
G02X1497040Y1604636I-202J0D01*
G01X1494220D01*
G02X1494018Y1604838I0J202D01*
G01Y1605458D01*
G03X1493968Y1605590I-200J0D01*
G02Y1608506I1661J1458D01*
G03X1494018Y1608638I-150J132D01*
G01Y1610576D01*
G03X1493968Y1610708I-200J0D01*
G02Y1613624I1661J1458D01*
G03X1494018Y1613756I-150J132D01*
G01Y1614376D01*
G02X1494220Y1614578I202J0D01*
G37*
G36*
G01X454928Y1604636D02*
G02X454726Y1604838I0J202D01*
G01Y1605460D01*
G03X454676Y1605592I-200J0D01*
G02Y1608504I1664J1456D01*
G03X454726Y1608636I-150J132D01*
G01Y1610578D01*
G03X454676Y1610710I-200J0D01*
G02Y1613622I1664J1456D01*
G03X454726Y1613754I-150J132D01*
G01Y1614376D01*
G02X454929Y1614578I203J-1D01*
G01X457750D01*
G02X457952Y1614376I0J-202D01*
G01Y1613754D01*
G03X458002Y1613622I200J0D01*
G02Y1610710I-1664J-1456D01*
G03X457952Y1610578I150J-132D01*
G01Y1608636D01*
G03X458002Y1608504I200J0D01*
G02Y1605592I-1664J-1456D01*
G03X457952Y1605460I150J-132D01*
G01Y1604838D01*
G02X457749Y1604636I-203J1D01*
G01X454928D01*
G37*
G36*
G01X489574D02*
G02X489372Y1604838I0J202D01*
G01Y1605460D01*
G03X489322Y1605592I-200J0D01*
G02Y1608504I1664J1456D01*
G03X489372Y1608636I-150J132D01*
G01Y1610578D01*
G03X489322Y1610710I-200J0D01*
G02Y1613622I1664J1456D01*
G03X489372Y1613754I-150J132D01*
G01Y1614376D01*
G02X489575Y1614578I203J-1D01*
G01X492396D01*
G02X492598Y1614376I0J-202D01*
G01Y1613754D01*
G03X492648Y1613622I200J0D01*
G02Y1610710I-1664J-1456D01*
G03X492598Y1610578I150J-132D01*
G01Y1608636D01*
G03X492648Y1608504I200J0D01*
G02Y1605592I-1664J-1456D01*
G03X492598Y1605460I150J-132D01*
G01Y1604838D01*
G02X492395Y1604636I-203J1D01*
G01X489574D01*
G37*
G36*
G01X506896D02*
G02X506694Y1604838I0J202D01*
G01Y1605460D01*
G03X506644Y1605592I-200J0D01*
G02Y1608504I1664J1456D01*
G03X506694Y1608636I-150J132D01*
G01Y1610578D01*
G03X506644Y1610710I-200J0D01*
G02Y1613622I1664J1456D01*
G03X506694Y1613754I-150J132D01*
G01Y1614376D01*
G02X506897Y1614578I203J-1D01*
G01X509718D01*
G02X509920Y1614376I0J-202D01*
G01Y1613754D01*
G03X509970Y1613622I200J0D01*
G02Y1610710I-1664J-1456D01*
G03X509920Y1610578I150J-132D01*
G01Y1608636D01*
G03X509970Y1608504I200J0D01*
G02Y1605592I-1664J-1456D01*
G03X509920Y1605460I150J-132D01*
G01Y1604838D01*
G02X509717Y1604636I-203J1D01*
G01X506896D01*
G37*
G36*
G01X1511542D02*
G02X1511340Y1604838I0J202D01*
G01Y1605460D01*
G03X1511290Y1605592I-200J0D01*
G02Y1608504I1664J1456D01*
G03X1511340Y1608636I-150J132D01*
G01Y1610578D01*
G03X1511290Y1610710I-200J0D01*
G02Y1613622I1664J1456D01*
G03X1511340Y1613754I-150J132D01*
G01Y1614376D01*
G02X1511543Y1614578I203J-1D01*
G01X1514364D01*
G02X1514566Y1614376I0J-202D01*
G01Y1613754D01*
G03X1514616Y1613622I200J0D01*
G02Y1610710I-1664J-1456D01*
G03X1514566Y1610578I150J-132D01*
G01Y1608636D01*
G03X1514616Y1608504I200J0D01*
G02Y1605592I-1664J-1456D01*
G03X1514566Y1605460I150J-132D01*
G01Y1604838D01*
G02X1514363Y1604636I-203J1D01*
G01X1511542D01*
G37*
G36*
G01X1528864D02*
G02X1528662Y1604838I0J202D01*
G01Y1605460D01*
G03X1528612Y1605592I-200J0D01*
G02Y1608504I1664J1456D01*
G03X1528662Y1608636I-150J132D01*
G01Y1610578D01*
G03X1528612Y1610710I-200J0D01*
G02Y1613622I1664J1456D01*
G03X1528662Y1613754I-150J132D01*
G01Y1614376D01*
G02X1528865Y1614578I203J-1D01*
G01X1531686D01*
G02X1531888Y1614376I0J-202D01*
G01Y1613754D01*
G03X1531938Y1613622I200J0D01*
G02Y1610710I-1664J-1456D01*
G03X1531888Y1610578I150J-132D01*
G01Y1608636D01*
G03X1531938Y1608504I200J0D01*
G02Y1605592I-1664J-1456D01*
G03X1531888Y1605460I150J-132D01*
G01Y1604838D01*
G02X1531685Y1604636I-203J1D01*
G01X1528864D01*
G37*
G36*
G01X463590Y1618908D02*
X466410D01*
G02X466612Y1618706I0J-202D01*
G01Y1618086D01*
G03X466662Y1617954I200J0D01*
G02Y1615038I-1661J-1458D01*
G03X466612Y1614906I150J-132D01*
G01Y1612968D01*
G03X466662Y1612836I200J0D01*
G02Y1609920I-1661J-1458D01*
G03X466612Y1609788I150J-132D01*
G01Y1609168D01*
G02X466410Y1608966I-202J0D01*
G01X463590D01*
G02X463388Y1609168I0J202D01*
G01Y1609788D01*
G03X463338Y1609920I-200J0D01*
G02Y1612836I1661J1458D01*
G03X463388Y1612968I-150J132D01*
G01Y1614906D01*
G03X463338Y1615038I-200J0D01*
G02Y1617954I1661J1458D01*
G03X463388Y1618086I-150J132D01*
G01Y1618706D01*
G02X463590Y1618908I202J0D01*
G37*
G36*
G01X498236D02*
X501056D01*
G02X501258Y1618706I0J-202D01*
G01Y1618086D01*
G03X501308Y1617954I200J0D01*
G02Y1615038I-1661J-1458D01*
G03X501258Y1614906I150J-132D01*
G01Y1612968D01*
G03X501308Y1612836I200J0D01*
G02Y1609920I-1661J-1458D01*
G03X501258Y1609788I150J-132D01*
G01Y1609168D01*
G02X501056Y1608966I-202J0D01*
G01X498236D01*
G02X498034Y1609168I0J202D01*
G01Y1609788D01*
G03X497984Y1609920I-200J0D01*
G02Y1612836I1661J1458D01*
G03X498034Y1612968I-150J132D01*
G01Y1614906D01*
G03X497984Y1615038I-200J0D01*
G02Y1617954I1661J1458D01*
G03X498034Y1618086I-150J132D01*
G01Y1618706D01*
G02X498236Y1618908I202J0D01*
G37*
G36*
G01X1485558D02*
X1488378D01*
G02X1488580Y1618706I0J-202D01*
G01Y1618086D01*
G03X1488630Y1617954I200J0D01*
G02Y1615038I-1661J-1458D01*
G03X1488580Y1614906I150J-132D01*
G01Y1612968D01*
G03X1488630Y1612836I200J0D01*
G02Y1609920I-1661J-1458D01*
G03X1488580Y1609788I150J-132D01*
G01Y1609168D01*
G02X1488378Y1608966I-202J0D01*
G01X1485558D01*
G02X1485356Y1609168I0J202D01*
G01Y1609788D01*
G03X1485306Y1609920I-200J0D01*
G02Y1612836I1661J1458D01*
G03X1485356Y1612968I-150J132D01*
G01Y1614906D01*
G03X1485306Y1615038I-200J0D01*
G02Y1617954I1661J1458D01*
G03X1485356Y1618086I-150J132D01*
G01Y1618706D01*
G02X1485558Y1618908I202J0D01*
G37*
G36*
G01X1520204D02*
X1523024D01*
G02X1523226Y1618706I0J-202D01*
G01Y1618086D01*
G03X1523276Y1617954I200J0D01*
G02Y1615038I-1661J-1458D01*
G03X1523226Y1614906I150J-132D01*
G01Y1612968D01*
G03X1523276Y1612836I200J0D01*
G02Y1609920I-1661J-1458D01*
G03X1523226Y1609788I150J-132D01*
G01Y1609168D01*
G02X1523024Y1608966I-202J0D01*
G01X1520204D01*
G02X1520002Y1609168I0J202D01*
G01Y1609788D01*
G03X1519952Y1609920I-200J0D01*
G02Y1612836I1661J1458D01*
G03X1520002Y1612968I-150J132D01*
G01Y1614906D01*
G03X1519952Y1615038I-200J0D01*
G02Y1617954I1661J1458D01*
G03X1520002Y1618086I-150J132D01*
G01Y1618706D01*
G02X1520204Y1618908I202J0D01*
G37*
G36*
G01X480912Y1608966D02*
G02X480710Y1609168I0J202D01*
G01Y1609790D01*
G03X480660Y1609922I-200J0D01*
G02Y1612834I1664J1456D01*
G03X480710Y1612966I-150J132D01*
G01Y1614908D01*
G03X480660Y1615040I-200J0D01*
G02Y1617952I1664J1456D01*
G03X480710Y1618084I-150J132D01*
G01Y1618706D01*
G02X480913Y1618908I203J-1D01*
G01X483734D01*
G02X483936Y1618706I0J-202D01*
G01Y1618084D01*
G03X483986Y1617952I200J0D01*
G02Y1615040I-1664J-1456D01*
G03X483936Y1614908I150J-132D01*
G01Y1612966D01*
G03X483986Y1612834I200J0D01*
G02Y1609922I-1664J-1456D01*
G03X483936Y1609790I150J-132D01*
G01Y1609168D01*
G02X483733Y1608966I-203J1D01*
G01X480912D01*
G37*
G36*
G01X1502880D02*
G02X1502678Y1609168I0J202D01*
G01Y1609790D01*
G03X1502628Y1609922I-200J0D01*
G02Y1612834I1664J1456D01*
G03X1502678Y1612966I-150J132D01*
G01Y1614908D01*
G03X1502628Y1615040I-200J0D01*
G02Y1617952I1664J1456D01*
G03X1502678Y1618084I-150J132D01*
G01Y1618706D01*
G02X1502881Y1618908I203J-1D01*
G01X1505702D01*
G02X1505904Y1618706I0J-202D01*
G01Y1618084D01*
G03X1505954Y1617952I200J0D01*
G02Y1615040I-1664J-1456D01*
G03X1505904Y1614908I150J-132D01*
G01Y1612966D01*
G03X1505954Y1612834I200J0D01*
G02Y1609922I-1664J-1456D01*
G03X1505904Y1609790I150J-132D01*
G01Y1609168D01*
G02X1505701Y1608966I-203J1D01*
G01X1502880D01*
G37*
G36*
G01X1537526D02*
G02X1537324Y1609168I0J202D01*
G01Y1609790D01*
G03X1537274Y1609922I-200J0D01*
G02Y1612834I1664J1456D01*
G03X1537324Y1612966I-150J132D01*
G01Y1614908D01*
G03X1537274Y1615040I-200J0D01*
G02Y1617952I1664J1456D01*
G03X1537324Y1618084I-150J132D01*
G01Y1618706D01*
G02X1537527Y1618908I203J-1D01*
G01X1540348D01*
G02X1540550Y1618706I0J-202D01*
G01Y1618084D01*
G03X1540600Y1617952I200J0D01*
G02Y1615040I-1664J-1456D01*
G03X1540550Y1614908I150J-132D01*
G01Y1612966D01*
G03X1540600Y1612834I200J0D01*
G02Y1609922I-1664J-1456D01*
G03X1540550Y1609790I150J-132D01*
G01Y1609168D01*
G02X1540347Y1608966I-203J1D01*
G01X1537526D01*
G37*
G36*
G01X125795Y1466154D02*
X128615D01*
G02X128818Y1465951I0J-203D01*
G01Y1465329D01*
G03X128868Y1465197I200J0D01*
G02Y1462285I-1664J-1456D01*
G03X128818Y1462153I150J-132D01*
G01Y1460210D01*
G03X128868Y1460078I200J0D01*
G02Y1457166I-1664J-1456D01*
G03X128818Y1457034I150J-132D01*
G01Y1456413D01*
G02X128615Y1456210I-203J0D01*
G01X125795D01*
G02X125592Y1456413I0J203D01*
G01Y1457034D01*
G03X125542Y1457166I-200J0D01*
G02Y1460078I1664J1456D01*
G03X125592Y1460210I-150J132D01*
G01Y1462153D01*
G03X125542Y1462285I-200J0D01*
G02Y1465197I1664J1456D01*
G03X125592Y1465329I-150J132D01*
G01Y1465951D01*
G02X125795Y1466154I203J0D01*
G37*
G36*
G01X143118D02*
X145938D01*
G02X146140Y1465951I-1J-203D01*
G01Y1465331D01*
G03X146190Y1465199I200J0D01*
G02Y1462283I-1661J-1458D01*
G03X146140Y1462151I150J-132D01*
G01Y1460212D01*
G03X146190Y1460080I200J0D01*
G02Y1457164I-1661J-1458D01*
G03X146140Y1457032I150J-132D01*
G01Y1456413D01*
G02X145938Y1456210I-202J-1D01*
G01X143118D01*
G02X142916Y1456413I1J203D01*
G01Y1457032D01*
G03X142866Y1457164I-200J0D01*
G02Y1460080I1661J1458D01*
G03X142916Y1460212I-150J132D01*
G01Y1462151D01*
G03X142866Y1462283I-200J0D01*
G02Y1465199I1661J1458D01*
G03X142916Y1465331I-150J132D01*
G01Y1465951D01*
G02X143118Y1466154I202J1D01*
G37*
G36*
G01X160440D02*
X163260D01*
G02X163462Y1465951I-1J-203D01*
G01Y1465331D01*
G03X163512Y1465199I200J0D01*
G02Y1462283I-1661J-1458D01*
G03X163462Y1462151I150J-132D01*
G01Y1460212D01*
G03X163512Y1460080I200J0D01*
G02Y1457164I-1661J-1458D01*
G03X163462Y1457032I150J-132D01*
G01Y1456413D01*
G02X163260Y1456210I-202J-1D01*
G01X160440D01*
G02X160238Y1456413I1J203D01*
G01Y1457032D01*
G03X160188Y1457164I-200J0D01*
G02Y1460080I1661J1458D01*
G03X160238Y1460212I-150J132D01*
G01Y1462151D01*
G03X160188Y1462283I-200J0D01*
G02Y1465199I1661J1458D01*
G03X160238Y1465331I-150J132D01*
G01Y1465951D01*
G02X160440Y1466154I202J1D01*
G37*
G36*
G01X177763D02*
X180583D01*
G02X180786Y1465951I0J-203D01*
G01Y1465329D01*
G03X180836Y1465197I200J0D01*
G02Y1462285I-1664J-1456D01*
G03X180786Y1462153I150J-132D01*
G01Y1460210D01*
G03X180836Y1460078I200J0D01*
G02Y1457166I-1664J-1456D01*
G03X180786Y1457034I150J-132D01*
G01Y1456413D01*
G02X180583Y1456210I-203J0D01*
G01X177763D01*
G02X177560Y1456413I0J203D01*
G01Y1457034D01*
G03X177510Y1457166I-200J0D01*
G02Y1460078I1664J1456D01*
G03X177560Y1460210I-150J132D01*
G01Y1462153D01*
G03X177510Y1462285I-200J0D01*
G02Y1465197I1664J1456D01*
G03X177560Y1465329I-150J132D01*
G01Y1465951D01*
G02X177763Y1466154I203J0D01*
G37*
G36*
G01X281700D02*
X284520D01*
G02X284722Y1465951I-1J-203D01*
G01Y1465331D01*
G03X284772Y1465199I200J0D01*
G02Y1462283I-1661J-1458D01*
G03X284722Y1462151I150J-132D01*
G01Y1460212D01*
G03X284772Y1460080I200J0D01*
G02Y1457164I-1661J-1458D01*
G03X284722Y1457032I150J-132D01*
G01Y1456413D01*
G02X284520Y1456210I-202J-1D01*
G01X281700D01*
G02X281498Y1456413I1J203D01*
G01Y1457032D01*
G03X281448Y1457164I-200J0D01*
G02Y1460080I1661J1458D01*
G03X281498Y1460212I-150J132D01*
G01Y1462151D01*
G03X281448Y1462283I-200J0D01*
G02Y1465199I1661J1458D01*
G03X281498Y1465331I-150J132D01*
G01Y1465951D01*
G02X281700Y1466154I202J1D01*
G37*
G36*
G01X299023D02*
X301843D01*
G02X302046Y1465951I0J-203D01*
G01Y1465329D01*
G03X302096Y1465197I200J0D01*
G02Y1462285I-1664J-1456D01*
G03X302046Y1462153I150J-132D01*
G01Y1460210D01*
G03X302096Y1460078I200J0D01*
G02Y1457166I-1664J-1456D01*
G03X302046Y1457034I150J-132D01*
G01Y1456413D01*
G02X301843Y1456210I-203J0D01*
G01X299023D01*
G02X298820Y1456413I0J203D01*
G01Y1457034D01*
G03X298770Y1457166I-200J0D01*
G02Y1460078I1664J1456D01*
G03X298820Y1460210I-150J132D01*
G01Y1462153D01*
G03X298770Y1462285I-200J0D01*
G02Y1465197I1664J1456D01*
G03X298820Y1465329I-150J132D01*
G01Y1465951D01*
G02X299023Y1466154I203J0D01*
G37*
G36*
G01X454929D02*
X457749D01*
G02X457952Y1465951I0J-203D01*
G01Y1465329D01*
G03X458002Y1465197I200J0D01*
G02Y1462285I-1664J-1456D01*
G03X457952Y1462153I150J-132D01*
G01Y1460210D01*
G03X458002Y1460078I200J0D01*
G02Y1457166I-1664J-1456D01*
G03X457952Y1457034I150J-132D01*
G01Y1456413D01*
G02X457749Y1456210I-203J0D01*
G01X454929D01*
G02X454726Y1456413I0J203D01*
G01Y1457034D01*
G03X454676Y1457166I-200J0D01*
G02Y1460078I1664J1456D01*
G03X454726Y1460210I-150J132D01*
G01Y1462153D01*
G03X454676Y1462285I-200J0D01*
G02Y1465197I1664J1456D01*
G03X454726Y1465329I-150J132D01*
G01Y1465951D01*
G02X454929Y1466154I203J0D01*
G37*
G36*
G01X472252D02*
X475072D01*
G02X475274Y1465951I-1J-203D01*
G01Y1465331D01*
G03X475324Y1465199I200J0D01*
G02Y1462283I-1661J-1458D01*
G03X475274Y1462151I150J-132D01*
G01Y1460212D01*
G03X475324Y1460080I200J0D01*
G02Y1457164I-1661J-1458D01*
G03X475274Y1457032I150J-132D01*
G01Y1456413D01*
G02X475072Y1456210I-202J-1D01*
G01X472252D01*
G02X472050Y1456413I1J203D01*
G01Y1457032D01*
G03X472000Y1457164I-200J0D01*
G02Y1460080I1661J1458D01*
G03X472050Y1460212I-150J132D01*
G01Y1462151D01*
G03X472000Y1462283I-200J0D01*
G02Y1465199I1661J1458D01*
G03X472050Y1465331I-150J132D01*
G01Y1465951D01*
G02X472252Y1466154I202J1D01*
G37*
G36*
G01X489575D02*
X492395D01*
G02X492598Y1465951I0J-203D01*
G01Y1465329D01*
G03X492648Y1465197I200J0D01*
G02Y1462285I-1664J-1456D01*
G03X492598Y1462153I150J-132D01*
G01Y1460210D01*
G03X492648Y1460078I200J0D01*
G02Y1457166I-1664J-1456D01*
G03X492598Y1457034I150J-132D01*
G01Y1456413D01*
G02X492395Y1456210I-203J0D01*
G01X489575D01*
G02X489372Y1456413I0J203D01*
G01Y1457034D01*
G03X489322Y1457166I-200J0D01*
G02Y1460078I1664J1456D01*
G03X489372Y1460210I-150J132D01*
G01Y1462153D01*
G03X489322Y1462285I-200J0D01*
G02Y1465197I1664J1456D01*
G03X489372Y1465329I-150J132D01*
G01Y1465951D01*
G02X489575Y1466154I203J0D01*
G37*
G36*
G01X506897D02*
X509717D01*
G02X509920Y1465951I0J-203D01*
G01Y1465329D01*
G03X509970Y1465197I200J0D01*
G02Y1462285I-1664J-1456D01*
G03X509920Y1462153I150J-132D01*
G01Y1460210D01*
G03X509970Y1460078I200J0D01*
G02Y1457166I-1664J-1456D01*
G03X509920Y1457034I150J-132D01*
G01Y1456413D01*
G02X509717Y1456210I-203J0D01*
G01X506897D01*
G02X506694Y1456413I0J203D01*
G01Y1457034D01*
G03X506644Y1457166I-200J0D01*
G02Y1460078I1664J1456D01*
G03X506694Y1460210I-150J132D01*
G01Y1462153D01*
G03X506644Y1462285I-200J0D01*
G02Y1465197I1664J1456D01*
G03X506694Y1465329I-150J132D01*
G01Y1465951D01*
G02X506897Y1466154I203J0D01*
G37*
G36*
G01X645480D02*
X648300D01*
G02X648502Y1465951I-1J-203D01*
G01Y1465331D01*
G03X648552Y1465199I200J0D01*
G02Y1462283I-1661J-1458D01*
G03X648502Y1462151I150J-132D01*
G01Y1460212D01*
G03X648552Y1460080I200J0D01*
G02Y1457164I-1661J-1458D01*
G03X648502Y1457032I150J-132D01*
G01Y1456413D01*
G02X648300Y1456210I-202J-1D01*
G01X645480D01*
G02X645278Y1456413I1J203D01*
G01Y1457032D01*
G03X645228Y1457164I-200J0D01*
G02Y1460080I1661J1458D01*
G03X645278Y1460212I-150J132D01*
G01Y1462151D01*
G03X645228Y1462283I-200J0D01*
G02Y1465199I1661J1458D01*
G03X645278Y1465331I-150J132D01*
G01Y1465951D01*
G02X645480Y1466154I202J1D01*
G37*
G36*
G01X662803D02*
X665623D01*
G02X665826Y1465951I0J-203D01*
G01Y1465329D01*
G03X665876Y1465197I200J0D01*
G02Y1462285I-1664J-1456D01*
G03X665826Y1462153I150J-132D01*
G01Y1460210D01*
G03X665876Y1460078I200J0D01*
G02Y1457166I-1664J-1456D01*
G03X665826Y1457034I150J-132D01*
G01Y1456413D01*
G02X665623Y1456210I-203J0D01*
G01X662803D01*
G02X662600Y1456413I0J203D01*
G01Y1457034D01*
G03X662550Y1457166I-200J0D01*
G02Y1460078I1664J1456D01*
G03X662600Y1460210I-150J132D01*
G01Y1462153D01*
G03X662550Y1462285I-200J0D01*
G02Y1465197I1664J1456D01*
G03X662600Y1465329I-150J132D01*
G01Y1465951D01*
G02X662803Y1466154I203J0D01*
G37*
G36*
G01X680125D02*
X682945D01*
G02X683148Y1465951I0J-203D01*
G01Y1465329D01*
G03X683198Y1465197I200J0D01*
G02Y1462285I-1664J-1456D01*
G03X683148Y1462153I150J-132D01*
G01Y1460210D01*
G03X683198Y1460078I200J0D01*
G02Y1457166I-1664J-1456D01*
G03X683148Y1457034I150J-132D01*
G01Y1456413D01*
G02X682945Y1456210I-203J0D01*
G01X680125D01*
G02X679922Y1456413I0J203D01*
G01Y1457034D01*
G03X679872Y1457166I-200J0D01*
G02Y1460078I1664J1456D01*
G03X679922Y1460210I-150J132D01*
G01Y1462153D01*
G03X679872Y1462285I-200J0D01*
G02Y1465197I1664J1456D01*
G03X679922Y1465329I-150J132D01*
G01Y1465951D01*
G02X680125Y1466154I203J0D01*
G37*
G36*
G01X1165086D02*
X1167906D01*
G02X1168108Y1465951I-1J-203D01*
G01Y1465331D01*
G03X1168158Y1465199I200J0D01*
G02Y1462283I-1661J-1458D01*
G03X1168108Y1462151I150J-132D01*
G01Y1460212D01*
G03X1168158Y1460080I200J0D01*
G02Y1457164I-1661J-1458D01*
G03X1168108Y1457032I150J-132D01*
G01Y1456413D01*
G02X1167906Y1456210I-202J-1D01*
G01X1165086D01*
G02X1164884Y1456413I1J203D01*
G01Y1457032D01*
G03X1164834Y1457164I-200J0D01*
G02Y1460080I1661J1458D01*
G03X1164884Y1460212I-150J132D01*
G01Y1462151D01*
G03X1164834Y1462283I-200J0D01*
G02Y1465199I1661J1458D01*
G03X1164884Y1465331I-150J132D01*
G01Y1465951D01*
G02X1165086Y1466154I202J1D01*
G37*
G36*
G01X1182408D02*
X1185228D01*
G02X1185430Y1465951I-1J-203D01*
G01Y1465331D01*
G03X1185480Y1465199I200J0D01*
G02Y1462283I-1661J-1458D01*
G03X1185430Y1462151I150J-132D01*
G01Y1460212D01*
G03X1185480Y1460080I200J0D01*
G02Y1457164I-1661J-1458D01*
G03X1185430Y1457032I150J-132D01*
G01Y1456413D01*
G02X1185228Y1456210I-202J-1D01*
G01X1182408D01*
G02X1182206Y1456413I1J203D01*
G01Y1457032D01*
G03X1182156Y1457164I-200J0D01*
G02Y1460080I1661J1458D01*
G03X1182206Y1460212I-150J132D01*
G01Y1462151D01*
G03X1182156Y1462283I-200J0D01*
G02Y1465199I1661J1458D01*
G03X1182206Y1465331I-150J132D01*
G01Y1465951D01*
G02X1182408Y1466154I202J1D01*
G37*
G36*
G01X1303669D02*
X1306489D01*
G02X1306692Y1465951I0J-203D01*
G01Y1465329D01*
G03X1306742Y1465197I200J0D01*
G02Y1462285I-1664J-1456D01*
G03X1306692Y1462153I150J-132D01*
G01Y1460210D01*
G03X1306742Y1460078I200J0D01*
G02Y1457166I-1664J-1456D01*
G03X1306692Y1457034I150J-132D01*
G01Y1456413D01*
G02X1306489Y1456210I-203J0D01*
G01X1303669D01*
G02X1303466Y1456413I0J203D01*
G01Y1457034D01*
G03X1303416Y1457166I-200J0D01*
G02Y1460078I1664J1456D01*
G03X1303466Y1460210I-150J132D01*
G01Y1462153D01*
G03X1303416Y1462285I-200J0D01*
G02Y1465197I1664J1456D01*
G03X1303466Y1465329I-150J132D01*
G01Y1465951D01*
G02X1303669Y1466154I203J0D01*
G37*
G36*
G01X1320992D02*
X1323812D01*
G02X1324014Y1465951I-1J-203D01*
G01Y1465331D01*
G03X1324064Y1465199I200J0D01*
G02Y1462283I-1661J-1458D01*
G03X1324014Y1462151I150J-132D01*
G01Y1460212D01*
G03X1324064Y1460080I200J0D01*
G02Y1457164I-1661J-1458D01*
G03X1324014Y1457032I150J-132D01*
G01Y1456413D01*
G02X1323812Y1456210I-202J-1D01*
G01X1320992D01*
G02X1320790Y1456413I1J203D01*
G01Y1457032D01*
G03X1320740Y1457164I-200J0D01*
G02Y1460080I1661J1458D01*
G03X1320790Y1460212I-150J132D01*
G01Y1462151D01*
G03X1320740Y1462283I-200J0D01*
G02Y1465199I1661J1458D01*
G03X1320790Y1465331I-150J132D01*
G01Y1465951D01*
G02X1320992Y1466154I202J1D01*
G37*
G36*
G01X1338315D02*
X1341135D01*
G02X1341338Y1465951I0J-203D01*
G01Y1465329D01*
G03X1341388Y1465197I200J0D01*
G02Y1462285I-1664J-1456D01*
G03X1341338Y1462153I150J-132D01*
G01Y1460210D01*
G03X1341388Y1460078I200J0D01*
G02Y1457166I-1664J-1456D01*
G03X1341338Y1457034I150J-132D01*
G01Y1456413D01*
G02X1341135Y1456210I-203J0D01*
G01X1338315D01*
G02X1338112Y1456413I0J203D01*
G01Y1457034D01*
G03X1338062Y1457166I-200J0D01*
G02Y1460078I1664J1456D01*
G03X1338112Y1460210I-150J132D01*
G01Y1462153D01*
G03X1338062Y1462285I-200J0D01*
G02Y1465197I1664J1456D01*
G03X1338112Y1465329I-150J132D01*
G01Y1465951D01*
G02X1338315Y1466154I203J0D01*
G37*
G36*
G01X1355637D02*
X1358457D01*
G02X1358660Y1465951I0J-203D01*
G01Y1465329D01*
G03X1358710Y1465197I200J0D01*
G02Y1462285I-1664J-1456D01*
G03X1358660Y1462153I150J-132D01*
G01Y1460210D01*
G03X1358710Y1460078I200J0D01*
G02Y1457166I-1664J-1456D01*
G03X1358660Y1457034I150J-132D01*
G01Y1456413D01*
G02X1358457Y1456210I-203J0D01*
G01X1355637D01*
G02X1355434Y1456413I0J203D01*
G01Y1457034D01*
G03X1355384Y1457166I-200J0D01*
G02Y1460078I1664J1456D01*
G03X1355434Y1460210I-150J132D01*
G01Y1462153D01*
G03X1355384Y1462285I-200J0D01*
G02Y1465197I1664J1456D01*
G03X1355434Y1465329I-150J132D01*
G01Y1465951D01*
G02X1355637Y1466154I203J0D01*
G37*
G36*
G01X1476897D02*
X1479717D01*
G02X1479920Y1465951I0J-203D01*
G01Y1465329D01*
G03X1479970Y1465197I200J0D01*
G02Y1462285I-1664J-1456D01*
G03X1479920Y1462153I150J-132D01*
G01Y1460210D01*
G03X1479970Y1460078I200J0D01*
G02Y1457166I-1664J-1456D01*
G03X1479920Y1457034I150J-132D01*
G01Y1456413D01*
G02X1479717Y1456210I-203J0D01*
G01X1476897D01*
G02X1476694Y1456413I0J203D01*
G01Y1457034D01*
G03X1476644Y1457166I-200J0D01*
G02Y1460078I1664J1456D01*
G03X1476694Y1460210I-150J132D01*
G01Y1462153D01*
G03X1476644Y1462285I-200J0D01*
G02Y1465197I1664J1456D01*
G03X1476694Y1465329I-150J132D01*
G01Y1465951D01*
G02X1476897Y1466154I203J0D01*
G37*
G36*
G01X1494220D02*
X1497040D01*
G02X1497242Y1465951I-1J-203D01*
G01Y1465331D01*
G03X1497292Y1465199I200J0D01*
G02Y1462283I-1661J-1458D01*
G03X1497242Y1462151I150J-132D01*
G01Y1460212D01*
G03X1497292Y1460080I200J0D01*
G02Y1457164I-1661J-1458D01*
G03X1497242Y1457032I150J-132D01*
G01Y1456413D01*
G02X1497040Y1456210I-202J-1D01*
G01X1494220D01*
G02X1494018Y1456413I1J203D01*
G01Y1457032D01*
G03X1493968Y1457164I-200J0D01*
G02Y1460080I1661J1458D01*
G03X1494018Y1460212I-150J132D01*
G01Y1462151D01*
G03X1493968Y1462283I-200J0D01*
G02Y1465199I1661J1458D01*
G03X1494018Y1465331I-150J132D01*
G01Y1465951D01*
G02X1494220Y1466154I202J1D01*
G37*
G36*
G01X1511543D02*
X1514363D01*
G02X1514566Y1465951I0J-203D01*
G01Y1465329D01*
G03X1514616Y1465197I200J0D01*
G02Y1462285I-1664J-1456D01*
G03X1514566Y1462153I150J-132D01*
G01Y1460210D01*
G03X1514616Y1460078I200J0D01*
G02Y1457166I-1664J-1456D01*
G03X1514566Y1457034I150J-132D01*
G01Y1456413D01*
G02X1514363Y1456210I-203J0D01*
G01X1511543D01*
G02X1511340Y1456413I0J203D01*
G01Y1457034D01*
G03X1511290Y1457166I-200J0D01*
G02Y1460078I1664J1456D01*
G03X1511340Y1460210I-150J132D01*
G01Y1462153D01*
G03X1511290Y1462285I-200J0D01*
G02Y1465197I1664J1456D01*
G03X1511340Y1465329I-150J132D01*
G01Y1465951D01*
G02X1511543Y1466154I203J0D01*
G37*
G36*
G01X1528865D02*
X1531685D01*
G02X1531888Y1465951I0J-203D01*
G01Y1465329D01*
G03X1531938Y1465197I200J0D01*
G02Y1462285I-1664J-1456D01*
G03X1531888Y1462153I150J-132D01*
G01Y1460210D01*
G03X1531938Y1460078I200J0D01*
G02Y1457166I-1664J-1456D01*
G03X1531888Y1457034I150J-132D01*
G01Y1456413D01*
G02X1531685Y1456210I-203J0D01*
G01X1528865D01*
G02X1528662Y1456413I0J203D01*
G01Y1457034D01*
G03X1528612Y1457166I-200J0D01*
G02Y1460078I1664J1456D01*
G03X1528662Y1460210I-150J132D01*
G01Y1462153D01*
G03X1528612Y1462285I-200J0D01*
G02Y1465197I1664J1456D01*
G03X1528662Y1465329I-150J132D01*
G01Y1465951D01*
G02X1528865Y1466154I203J0D01*
G37*
G36*
G01X1684771D02*
X1687591D01*
G02X1687794Y1465951I0J-203D01*
G01Y1465329D01*
G03X1687844Y1465197I200J0D01*
G02Y1462285I-1664J-1456D01*
G03X1687794Y1462153I150J-132D01*
G01Y1460210D01*
G03X1687844Y1460078I200J0D01*
G02Y1457166I-1664J-1456D01*
G03X1687794Y1457034I150J-132D01*
G01Y1456413D01*
G02X1687591Y1456210I-203J0D01*
G01X1684771D01*
G02X1684568Y1456413I0J203D01*
G01Y1457034D01*
G03X1684518Y1457166I-200J0D01*
G02Y1460078I1664J1456D01*
G03X1684568Y1460210I-150J132D01*
G01Y1462153D01*
G03X1684518Y1462285I-200J0D01*
G02Y1465197I1664J1456D01*
G03X1684568Y1465329I-150J132D01*
G01Y1465951D01*
G02X1684771Y1466154I203J0D01*
G37*
G36*
G01X1702093D02*
X1704913D01*
G02X1705116Y1465951I0J-203D01*
G01Y1465329D01*
G03X1705166Y1465197I200J0D01*
G02Y1462285I-1664J-1456D01*
G03X1705116Y1462153I150J-132D01*
G01Y1460210D01*
G03X1705166Y1460078I200J0D01*
G02Y1457166I-1664J-1456D01*
G03X1705116Y1457034I150J-132D01*
G01Y1456413D01*
G02X1704913Y1456210I-203J0D01*
G01X1702093D01*
G02X1701890Y1456413I0J203D01*
G01Y1457034D01*
G03X1701840Y1457166I-200J0D01*
G02Y1460078I1664J1456D01*
G03X1701890Y1460210I-150J132D01*
G01Y1462153D01*
G03X1701840Y1462285I-200J0D01*
G02Y1465197I1664J1456D01*
G03X1701890Y1465329I-150J132D01*
G01Y1465951D01*
G02X1702093Y1466154I203J0D01*
G37*
G36*
G01X134456Y1470484D02*
X137276D01*
G02X137478Y1470281I-1J-203D01*
G01Y1469661D01*
G03X137528Y1469529I200J0D01*
G02Y1466613I-1661J-1458D01*
G03X137478Y1466481I150J-132D01*
G01Y1464543D01*
G03X137528Y1464411I200J0D01*
G02Y1461495I-1661J-1458D01*
G03X137478Y1461363I150J-132D01*
G01Y1460743D01*
G02X137276Y1460540I-202J-1D01*
G01X134456D01*
G02X134254Y1460743I1J203D01*
G01Y1461363D01*
G03X134204Y1461495I-200J0D01*
G02Y1464411I1661J1458D01*
G03X134254Y1464543I-150J132D01*
G01Y1466481D01*
G03X134204Y1466613I-200J0D01*
G02Y1469529I1661J1458D01*
G03X134254Y1469661I-150J132D01*
G01Y1470281D01*
G02X134456Y1470484I202J1D01*
G37*
G36*
G01X151779D02*
X154599D01*
G02X154802Y1470281I0J-203D01*
G01Y1469659D01*
G03X154852Y1469527I200J0D01*
G02Y1466615I-1664J-1456D01*
G03X154802Y1466483I150J-132D01*
G01Y1464541D01*
G03X154852Y1464409I200J0D01*
G02Y1461497I-1664J-1456D01*
G03X154802Y1461365I150J-132D01*
G01Y1460743D01*
G02X154599Y1460540I-203J0D01*
G01X151779D01*
G02X151576Y1460743I0J203D01*
G01Y1461365D01*
G03X151526Y1461497I-200J0D01*
G02Y1464409I1664J1456D01*
G03X151576Y1464541I-150J132D01*
G01Y1466483D01*
G03X151526Y1466615I-200J0D01*
G02Y1469527I1664J1456D01*
G03X151576Y1469659I-150J132D01*
G01Y1470281D01*
G02X151779Y1470484I203J0D01*
G37*
G36*
G01X169102D02*
X171922D01*
G02X172124Y1470281I-1J-203D01*
G01Y1469661D01*
G03X172174Y1469529I200J0D01*
G02Y1466613I-1661J-1458D01*
G03X172124Y1466481I150J-132D01*
G01Y1464543D01*
G03X172174Y1464411I200J0D01*
G02Y1461495I-1661J-1458D01*
G03X172124Y1461363I150J-132D01*
G01Y1460743D01*
G02X171922Y1460540I-202J-1D01*
G01X169102D01*
G02X168900Y1460743I1J203D01*
G01Y1461363D01*
G03X168850Y1461495I-200J0D01*
G02Y1464411I1661J1458D01*
G03X168900Y1464543I-150J132D01*
G01Y1466481D01*
G03X168850Y1466613I-200J0D01*
G02Y1469529I1661J1458D01*
G03X168900Y1469661I-150J132D01*
G01Y1470281D01*
G02X169102Y1470484I202J1D01*
G37*
G36*
G01X186425D02*
X189245D01*
G02X189448Y1470281I0J-203D01*
G01Y1469659D01*
G03X189498Y1469527I200J0D01*
G02Y1466615I-1664J-1456D01*
G03X189448Y1466483I150J-132D01*
G01Y1464541D01*
G03X189498Y1464409I200J0D01*
G02Y1461497I-1664J-1456D01*
G03X189448Y1461365I150J-132D01*
G01Y1460743D01*
G02X189245Y1460540I-203J0D01*
G01X186425D01*
G02X186222Y1460743I0J203D01*
G01Y1461365D01*
G03X186172Y1461497I-200J0D01*
G02Y1464409I1664J1456D01*
G03X186222Y1464541I-150J132D01*
G01Y1466483D01*
G03X186172Y1466615I-200J0D01*
G02Y1469527I1664J1456D01*
G03X186222Y1469659I-150J132D01*
G01Y1470281D01*
G02X186425Y1470484I203J0D01*
G37*
G36*
G01X290361D02*
X293181D01*
G02X293384Y1470281I0J-203D01*
G01Y1469659D01*
G03X293434Y1469527I200J0D01*
G02Y1466615I-1664J-1456D01*
G03X293384Y1466483I150J-132D01*
G01Y1464541D01*
G03X293434Y1464409I200J0D01*
G02Y1461497I-1664J-1456D01*
G03X293384Y1461365I150J-132D01*
G01Y1460743D01*
G02X293181Y1460540I-203J0D01*
G01X290361D01*
G02X290158Y1460743I0J203D01*
G01Y1461365D01*
G03X290108Y1461497I-200J0D01*
G02Y1464409I1664J1456D01*
G03X290158Y1464541I-150J132D01*
G01Y1466483D01*
G03X290108Y1466615I-200J0D01*
G02Y1469527I1664J1456D01*
G03X290158Y1469659I-150J132D01*
G01Y1470281D01*
G02X290361Y1470484I203J0D01*
G37*
G36*
G01X463590D02*
X466410D01*
G02X466612Y1470281I-1J-203D01*
G01Y1469661D01*
G03X466662Y1469529I200J0D01*
G02Y1466613I-1661J-1458D01*
G03X466612Y1466481I150J-132D01*
G01Y1464543D01*
G03X466662Y1464411I200J0D01*
G02Y1461495I-1661J-1458D01*
G03X466612Y1461363I150J-132D01*
G01Y1460743D01*
G02X466410Y1460540I-202J-1D01*
G01X463590D01*
G02X463388Y1460743I1J203D01*
G01Y1461363D01*
G03X463338Y1461495I-200J0D01*
G02Y1464411I1661J1458D01*
G03X463388Y1464543I-150J132D01*
G01Y1466481D01*
G03X463338Y1466613I-200J0D01*
G02Y1469529I1661J1458D01*
G03X463388Y1469661I-150J132D01*
G01Y1470281D01*
G02X463590Y1470484I202J1D01*
G37*
G36*
G01X480913D02*
X483733D01*
G02X483936Y1470281I0J-203D01*
G01Y1469659D01*
G03X483986Y1469527I200J0D01*
G02Y1466615I-1664J-1456D01*
G03X483936Y1466483I150J-132D01*
G01Y1464541D01*
G03X483986Y1464409I200J0D01*
G02Y1461497I-1664J-1456D01*
G03X483936Y1461365I150J-132D01*
G01Y1460743D01*
G02X483733Y1460540I-203J0D01*
G01X480913D01*
G02X480710Y1460743I0J203D01*
G01Y1461365D01*
G03X480660Y1461497I-200J0D01*
G02Y1464409I1664J1456D01*
G03X480710Y1464541I-150J132D01*
G01Y1466483D01*
G03X480660Y1466615I-200J0D01*
G02Y1469527I1664J1456D01*
G03X480710Y1469659I-150J132D01*
G01Y1470281D01*
G02X480913Y1470484I203J0D01*
G37*
G36*
G01X498236D02*
X501056D01*
G02X501258Y1470281I-1J-203D01*
G01Y1469661D01*
G03X501308Y1469529I200J0D01*
G02Y1466613I-1661J-1458D01*
G03X501258Y1466481I150J-132D01*
G01Y1464543D01*
G03X501308Y1464411I200J0D01*
G02Y1461495I-1661J-1458D01*
G03X501258Y1461363I150J-132D01*
G01Y1460743D01*
G02X501056Y1460540I-202J-1D01*
G01X498236D01*
G02X498034Y1460743I1J203D01*
G01Y1461363D01*
G03X497984Y1461495I-200J0D01*
G02Y1464411I1661J1458D01*
G03X498034Y1464543I-150J132D01*
G01Y1466481D01*
G03X497984Y1466613I-200J0D01*
G02Y1469529I1661J1458D01*
G03X498034Y1469661I-150J132D01*
G01Y1470281D01*
G02X498236Y1470484I202J1D01*
G37*
G36*
G01X515559D02*
X518379D01*
G02X518582Y1470281I0J-203D01*
G01Y1469659D01*
G03X518632Y1469527I200J0D01*
G02Y1466615I-1664J-1456D01*
G03X518582Y1466483I150J-132D01*
G01Y1464541D01*
G03X518632Y1464409I200J0D01*
G02Y1461497I-1664J-1456D01*
G03X518582Y1461365I150J-132D01*
G01Y1460743D01*
G02X518379Y1460540I-203J0D01*
G01X515559D01*
G02X515356Y1460743I0J203D01*
G01Y1461365D01*
G03X515306Y1461497I-200J0D01*
G02Y1464409I1664J1456D01*
G03X515356Y1464541I-150J132D01*
G01Y1466483D01*
G03X515306Y1466615I-200J0D01*
G02Y1469527I1664J1456D01*
G03X515356Y1469659I-150J132D01*
G01Y1470281D01*
G02X515559Y1470484I203J0D01*
G37*
G36*
G01X654141D02*
X656961D01*
G02X657164Y1470281I0J-203D01*
G01Y1469659D01*
G03X657214Y1469527I200J0D01*
G02Y1466615I-1664J-1456D01*
G03X657164Y1466483I150J-132D01*
G01Y1464541D01*
G03X657214Y1464409I200J0D01*
G02Y1461497I-1664J-1456D01*
G03X657164Y1461365I150J-132D01*
G01Y1460743D01*
G02X656961Y1460540I-203J0D01*
G01X654141D01*
G02X653938Y1460743I0J203D01*
G01Y1461365D01*
G03X653888Y1461497I-200J0D01*
G02Y1464409I1664J1456D01*
G03X653938Y1464541I-150J132D01*
G01Y1466483D01*
G03X653888Y1466615I-200J0D01*
G02Y1469527I1664J1456D01*
G03X653938Y1469659I-150J132D01*
G01Y1470281D01*
G02X654141Y1470484I203J0D01*
G37*
G36*
G01X671464D02*
X674284D01*
G02X674486Y1470281I-1J-203D01*
G01Y1469661D01*
G03X674536Y1469529I200J0D01*
G02Y1466613I-1661J-1458D01*
G03X674486Y1466481I150J-132D01*
G01Y1464543D01*
G03X674536Y1464411I200J0D01*
G02Y1461495I-1661J-1458D01*
G03X674486Y1461363I150J-132D01*
G01Y1460743D01*
G02X674284Y1460540I-202J-1D01*
G01X671464D01*
G02X671262Y1460743I1J203D01*
G01Y1461363D01*
G03X671212Y1461495I-200J0D01*
G02Y1464411I1661J1458D01*
G03X671262Y1464543I-150J132D01*
G01Y1466481D01*
G03X671212Y1466613I-200J0D01*
G02Y1469529I1661J1458D01*
G03X671262Y1469661I-150J132D01*
G01Y1470281D01*
G02X671464Y1470484I202J1D01*
G37*
G36*
G01X688787D02*
X691607D01*
G02X691810Y1470281I0J-203D01*
G01Y1469659D01*
G03X691860Y1469527I200J0D01*
G02Y1466615I-1664J-1456D01*
G03X691810Y1466483I150J-132D01*
G01Y1464541D01*
G03X691860Y1464409I200J0D01*
G02Y1461497I-1664J-1456D01*
G03X691810Y1461365I150J-132D01*
G01Y1460743D01*
G02X691607Y1460540I-203J0D01*
G01X688787D01*
G02X688584Y1460743I0J203D01*
G01Y1461365D01*
G03X688534Y1461497I-200J0D01*
G02Y1464409I1664J1456D01*
G03X688584Y1464541I-150J132D01*
G01Y1466483D01*
G03X688534Y1466615I-200J0D01*
G02Y1469527I1664J1456D01*
G03X688584Y1469659I-150J132D01*
G01Y1470281D01*
G02X688787Y1470484I203J0D01*
G37*
G36*
G01X1173747D02*
X1176567D01*
G02X1176770Y1470281I0J-203D01*
G01Y1469659D01*
G03X1176820Y1469527I200J0D01*
G02Y1466615I-1664J-1456D01*
G03X1176770Y1466483I150J-132D01*
G01Y1464541D01*
G03X1176820Y1464409I200J0D01*
G02Y1461497I-1664J-1456D01*
G03X1176770Y1461365I150J-132D01*
G01Y1460743D01*
G02X1176567Y1460540I-203J0D01*
G01X1173747D01*
G02X1173544Y1460743I0J203D01*
G01Y1461365D01*
G03X1173494Y1461497I-200J0D01*
G02Y1464409I1664J1456D01*
G03X1173544Y1464541I-150J132D01*
G01Y1466483D01*
G03X1173494Y1466615I-200J0D01*
G02Y1469527I1664J1456D01*
G03X1173544Y1469659I-150J132D01*
G01Y1470281D01*
G02X1173747Y1470484I203J0D01*
G37*
G36*
G01X1191070D02*
X1193890D01*
G02X1194092Y1470281I-1J-203D01*
G01Y1469661D01*
G03X1194142Y1469529I200J0D01*
G02Y1466613I-1661J-1458D01*
G03X1194092Y1466481I150J-132D01*
G01Y1464543D01*
G03X1194142Y1464411I200J0D01*
G02Y1461495I-1661J-1458D01*
G03X1194092Y1461363I150J-132D01*
G01Y1460743D01*
G02X1193890Y1460540I-202J-1D01*
G01X1191070D01*
G02X1190868Y1460743I1J203D01*
G01Y1461363D01*
G03X1190818Y1461495I-200J0D01*
G02Y1464411I1661J1458D01*
G03X1190868Y1464543I-150J132D01*
G01Y1466481D01*
G03X1190818Y1466613I-200J0D01*
G02Y1469529I1661J1458D01*
G03X1190868Y1469661I-150J132D01*
G01Y1470281D01*
G02X1191070Y1470484I202J1D01*
G37*
G36*
G01X1312330D02*
X1315150D01*
G02X1315352Y1470281I-1J-203D01*
G01Y1469661D01*
G03X1315402Y1469529I200J0D01*
G02Y1466613I-1661J-1458D01*
G03X1315352Y1466481I150J-132D01*
G01Y1464543D01*
G03X1315402Y1464411I200J0D01*
G02Y1461495I-1661J-1458D01*
G03X1315352Y1461363I150J-132D01*
G01Y1460743D01*
G02X1315150Y1460540I-202J-1D01*
G01X1312330D01*
G02X1312128Y1460743I1J203D01*
G01Y1461363D01*
G03X1312078Y1461495I-200J0D01*
G02Y1464411I1661J1458D01*
G03X1312128Y1464543I-150J132D01*
G01Y1466481D01*
G03X1312078Y1466613I-200J0D01*
G02Y1469529I1661J1458D01*
G03X1312128Y1469661I-150J132D01*
G01Y1470281D01*
G02X1312330Y1470484I202J1D01*
G37*
G36*
G01X1329653D02*
X1332473D01*
G02X1332676Y1470281I0J-203D01*
G01Y1469659D01*
G03X1332726Y1469527I200J0D01*
G02Y1466615I-1664J-1456D01*
G03X1332676Y1466483I150J-132D01*
G01Y1464541D01*
G03X1332726Y1464409I200J0D01*
G02Y1461497I-1664J-1456D01*
G03X1332676Y1461365I150J-132D01*
G01Y1460743D01*
G02X1332473Y1460540I-203J0D01*
G01X1329653D01*
G02X1329450Y1460743I0J203D01*
G01Y1461365D01*
G03X1329400Y1461497I-200J0D01*
G02Y1464409I1664J1456D01*
G03X1329450Y1464541I-150J132D01*
G01Y1466483D01*
G03X1329400Y1466615I-200J0D01*
G02Y1469527I1664J1456D01*
G03X1329450Y1469659I-150J132D01*
G01Y1470281D01*
G02X1329653Y1470484I203J0D01*
G37*
G36*
G01X1346976D02*
X1349796D01*
G02X1349998Y1470281I-1J-203D01*
G01Y1469661D01*
G03X1350048Y1469529I200J0D01*
G02Y1466613I-1661J-1458D01*
G03X1349998Y1466481I150J-132D01*
G01Y1464543D01*
G03X1350048Y1464411I200J0D01*
G02Y1461495I-1661J-1458D01*
G03X1349998Y1461363I150J-132D01*
G01Y1460743D01*
G02X1349796Y1460540I-202J-1D01*
G01X1346976D01*
G02X1346774Y1460743I1J203D01*
G01Y1461363D01*
G03X1346724Y1461495I-200J0D01*
G02Y1464411I1661J1458D01*
G03X1346774Y1464543I-150J132D01*
G01Y1466481D01*
G03X1346724Y1466613I-200J0D01*
G02Y1469529I1661J1458D01*
G03X1346774Y1469661I-150J132D01*
G01Y1470281D01*
G02X1346976Y1470484I202J1D01*
G37*
G36*
G01X1364299D02*
X1367119D01*
G02X1367322Y1470281I0J-203D01*
G01Y1469659D01*
G03X1367372Y1469527I200J0D01*
G02Y1466615I-1664J-1456D01*
G03X1367322Y1466483I150J-132D01*
G01Y1464541D01*
G03X1367372Y1464409I200J0D01*
G02Y1461497I-1664J-1456D01*
G03X1367322Y1461365I150J-132D01*
G01Y1460743D01*
G02X1367119Y1460540I-203J0D01*
G01X1364299D01*
G02X1364096Y1460743I0J203D01*
G01Y1461365D01*
G03X1364046Y1461497I-200J0D01*
G02Y1464409I1664J1456D01*
G03X1364096Y1464541I-150J132D01*
G01Y1466483D01*
G03X1364046Y1466615I-200J0D01*
G02Y1469527I1664J1456D01*
G03X1364096Y1469659I-150J132D01*
G01Y1470281D01*
G02X1364299Y1470484I203J0D01*
G37*
G36*
G01X1485558D02*
X1488378D01*
G02X1488580Y1470281I-1J-203D01*
G01Y1469661D01*
G03X1488630Y1469529I200J0D01*
G02Y1466613I-1661J-1458D01*
G03X1488580Y1466481I150J-132D01*
G01Y1464543D01*
G03X1488630Y1464411I200J0D01*
G02Y1461495I-1661J-1458D01*
G03X1488580Y1461363I150J-132D01*
G01Y1460743D01*
G02X1488378Y1460540I-202J-1D01*
G01X1485558D01*
G02X1485356Y1460743I1J203D01*
G01Y1461363D01*
G03X1485306Y1461495I-200J0D01*
G02Y1464411I1661J1458D01*
G03X1485356Y1464543I-150J132D01*
G01Y1466481D01*
G03X1485306Y1466613I-200J0D01*
G02Y1469529I1661J1458D01*
G03X1485356Y1469661I-150J132D01*
G01Y1470281D01*
G02X1485558Y1470484I202J1D01*
G37*
G36*
G01X1502881D02*
X1505701D01*
G02X1505904Y1470281I0J-203D01*
G01Y1469659D01*
G03X1505954Y1469527I200J0D01*
G02Y1466615I-1664J-1456D01*
G03X1505904Y1466483I150J-132D01*
G01Y1464541D01*
G03X1505954Y1464409I200J0D01*
G02Y1461497I-1664J-1456D01*
G03X1505904Y1461365I150J-132D01*
G01Y1460743D01*
G02X1505701Y1460540I-203J0D01*
G01X1502881D01*
G02X1502678Y1460743I0J203D01*
G01Y1461365D01*
G03X1502628Y1461497I-200J0D01*
G02Y1464409I1664J1456D01*
G03X1502678Y1464541I-150J132D01*
G01Y1466483D01*
G03X1502628Y1466615I-200J0D01*
G02Y1469527I1664J1456D01*
G03X1502678Y1469659I-150J132D01*
G01Y1470281D01*
G02X1502881Y1470484I203J0D01*
G37*
G36*
G01X1520204D02*
X1523024D01*
G02X1523226Y1470281I-1J-203D01*
G01Y1469661D01*
G03X1523276Y1469529I200J0D01*
G02Y1466613I-1661J-1458D01*
G03X1523226Y1466481I150J-132D01*
G01Y1464543D01*
G03X1523276Y1464411I200J0D01*
G02Y1461495I-1661J-1458D01*
G03X1523226Y1461363I150J-132D01*
G01Y1460743D01*
G02X1523024Y1460540I-202J-1D01*
G01X1520204D01*
G02X1520002Y1460743I1J203D01*
G01Y1461363D01*
G03X1519952Y1461495I-200J0D01*
G02Y1464411I1661J1458D01*
G03X1520002Y1464543I-150J132D01*
G01Y1466481D01*
G03X1519952Y1466613I-200J0D01*
G02Y1469529I1661J1458D01*
G03X1520002Y1469661I-150J132D01*
G01Y1470281D01*
G02X1520204Y1470484I202J1D01*
G37*
G36*
G01X1537527D02*
X1540347D01*
G02X1540550Y1470281I0J-203D01*
G01Y1469659D01*
G03X1540600Y1469527I200J0D01*
G02Y1466615I-1664J-1456D01*
G03X1540550Y1466483I150J-132D01*
G01Y1464541D01*
G03X1540600Y1464409I200J0D01*
G02Y1461497I-1664J-1456D01*
G03X1540550Y1461365I150J-132D01*
G01Y1460743D01*
G02X1540347Y1460540I-203J0D01*
G01X1537527D01*
G02X1537324Y1460743I0J203D01*
G01Y1461365D01*
G03X1537274Y1461497I-200J0D01*
G02Y1464409I1664J1456D01*
G03X1537324Y1464541I-150J132D01*
G01Y1466483D01*
G03X1537274Y1466615I-200J0D01*
G02Y1469527I1664J1456D01*
G03X1537324Y1469659I-150J132D01*
G01Y1470281D01*
G02X1537527Y1470484I203J0D01*
G37*
G36*
G01X1693432D02*
X1696252D01*
G02X1696454Y1470281I-1J-203D01*
G01Y1469661D01*
G03X1696504Y1469529I200J0D01*
G02Y1466613I-1661J-1458D01*
G03X1696454Y1466481I150J-132D01*
G01Y1464543D01*
G03X1696504Y1464411I200J0D01*
G02Y1461495I-1661J-1458D01*
G03X1696454Y1461363I150J-132D01*
G01Y1460743D01*
G02X1696252Y1460540I-202J-1D01*
G01X1693432D01*
G02X1693230Y1460743I1J203D01*
G01Y1461363D01*
G03X1693180Y1461495I-200J0D01*
G02Y1464411I1661J1458D01*
G03X1693230Y1464543I-150J132D01*
G01Y1466481D01*
G03X1693180Y1466613I-200J0D01*
G02Y1469529I1661J1458D01*
G03X1693230Y1469661I-150J132D01*
G01Y1470281D01*
G02X1693432Y1470484I202J1D01*
G37*
G36*
G01X1710755D02*
X1713575D01*
G02X1713778Y1470281I0J-203D01*
G01Y1469659D01*
G03X1713828Y1469527I200J0D01*
G02Y1466615I-1664J-1456D01*
G03X1713778Y1466483I150J-132D01*
G01Y1464541D01*
G03X1713828Y1464409I200J0D01*
G02Y1461497I-1664J-1456D01*
G03X1713778Y1461365I150J-132D01*
G01Y1460743D01*
G02X1713575Y1460540I-203J0D01*
G01X1710755D01*
G02X1710552Y1460743I0J203D01*
G01Y1461365D01*
G03X1710502Y1461497I-200J0D01*
G02Y1464409I1664J1456D01*
G03X1710552Y1464541I-150J132D01*
G01Y1466483D01*
G03X1710502Y1466615I-200J0D01*
G02Y1469527I1664J1456D01*
G03X1710552Y1469659I-150J132D01*
G01Y1470281D01*
G02X1710755Y1470484I203J0D01*
G37*
G36*
G01X125795Y1481508D02*
X128615D01*
G02X128818Y1481305I0J-203D01*
G01Y1480683D01*
G03X128868Y1480551I200J0D01*
G02Y1477639I-1664J-1456D01*
G03X128818Y1477507I150J-132D01*
G01Y1475565D01*
G03X128868Y1475433I200J0D01*
G02Y1472521I-1664J-1456D01*
G03X128818Y1472389I150J-132D01*
G01Y1471767D01*
G02X128615Y1471564I-203J0D01*
G01X125795D01*
G02X125592Y1471767I0J203D01*
G01Y1472389D01*
G03X125542Y1472521I-200J0D01*
G02Y1475433I1664J1456D01*
G03X125592Y1475565I-150J132D01*
G01Y1477507D01*
G03X125542Y1477639I-200J0D01*
G02Y1480551I1664J1456D01*
G03X125592Y1480683I-150J132D01*
G01Y1481305D01*
G02X125795Y1481508I203J0D01*
G37*
G36*
G01X143118D02*
X145938D01*
G02X146140Y1481305I-1J-203D01*
G01Y1480685D01*
G03X146190Y1480553I200J0D01*
G02Y1477637I-1661J-1458D01*
G03X146140Y1477505I150J-132D01*
G01Y1475567D01*
G03X146190Y1475435I200J0D01*
G02Y1472519I-1661J-1458D01*
G03X146140Y1472387I150J-132D01*
G01Y1471767D01*
G02X145938Y1471564I-202J-1D01*
G01X143118D01*
G02X142916Y1471767I1J203D01*
G01Y1472387D01*
G03X142866Y1472519I-200J0D01*
G02Y1475435I1661J1458D01*
G03X142916Y1475567I-150J132D01*
G01Y1477505D01*
G03X142866Y1477637I-200J0D01*
G02Y1480553I1661J1458D01*
G03X142916Y1480685I-150J132D01*
G01Y1481305D01*
G02X143118Y1481508I202J1D01*
G37*
G36*
G01X160440D02*
X163260D01*
G02X163462Y1481305I-1J-203D01*
G01Y1480685D01*
G03X163512Y1480553I200J0D01*
G02Y1477637I-1661J-1458D01*
G03X163462Y1477505I150J-132D01*
G01Y1475567D01*
G03X163512Y1475435I200J0D01*
G02Y1472519I-1661J-1458D01*
G03X163462Y1472387I150J-132D01*
G01Y1471767D01*
G02X163260Y1471564I-202J-1D01*
G01X160440D01*
G02X160238Y1471767I1J203D01*
G01Y1472387D01*
G03X160188Y1472519I-200J0D01*
G02Y1475435I1661J1458D01*
G03X160238Y1475567I-150J132D01*
G01Y1477505D01*
G03X160188Y1477637I-200J0D01*
G02Y1480553I1661J1458D01*
G03X160238Y1480685I-150J132D01*
G01Y1481305D01*
G02X160440Y1481508I202J1D01*
G37*
G36*
G01X177763D02*
X180583D01*
G02X180786Y1481305I0J-203D01*
G01Y1480683D01*
G03X180836Y1480551I200J0D01*
G02Y1477639I-1664J-1456D01*
G03X180786Y1477507I150J-132D01*
G01Y1475565D01*
G03X180836Y1475433I200J0D01*
G02Y1472521I-1664J-1456D01*
G03X180786Y1472389I150J-132D01*
G01Y1471767D01*
G02X180583Y1471564I-203J0D01*
G01X177763D01*
G02X177560Y1471767I0J203D01*
G01Y1472389D01*
G03X177510Y1472521I-200J0D01*
G02Y1475433I1664J1456D01*
G03X177560Y1475565I-150J132D01*
G01Y1477507D01*
G03X177510Y1477639I-200J0D01*
G02Y1480551I1664J1456D01*
G03X177560Y1480683I-150J132D01*
G01Y1481305D01*
G02X177763Y1481508I203J0D01*
G37*
G36*
G01X281700D02*
X284520D01*
G02X284722Y1481305I-1J-203D01*
G01Y1480685D01*
G03X284772Y1480553I200J0D01*
G02Y1477637I-1661J-1458D01*
G03X284722Y1477505I150J-132D01*
G01Y1475567D01*
G03X284772Y1475435I200J0D01*
G02Y1472519I-1661J-1458D01*
G03X284722Y1472387I150J-132D01*
G01Y1471767D01*
G02X284520Y1471564I-202J-1D01*
G01X281700D01*
G02X281498Y1471767I1J203D01*
G01Y1472387D01*
G03X281448Y1472519I-200J0D01*
G02Y1475435I1661J1458D01*
G03X281498Y1475567I-150J132D01*
G01Y1477505D01*
G03X281448Y1477637I-200J0D01*
G02Y1480553I1661J1458D01*
G03X281498Y1480685I-150J132D01*
G01Y1481305D01*
G02X281700Y1481508I202J1D01*
G37*
G36*
G01X299023D02*
X301843D01*
G02X302046Y1481305I0J-203D01*
G01Y1480683D01*
G03X302096Y1480551I200J0D01*
G02Y1477639I-1664J-1456D01*
G03X302046Y1477507I150J-132D01*
G01Y1475565D01*
G03X302096Y1475433I200J0D01*
G02Y1472521I-1664J-1456D01*
G03X302046Y1472389I150J-132D01*
G01Y1471767D01*
G02X301843Y1471564I-203J0D01*
G01X299023D01*
G02X298820Y1471767I0J203D01*
G01Y1472389D01*
G03X298770Y1472521I-200J0D01*
G02Y1475433I1664J1456D01*
G03X298820Y1475565I-150J132D01*
G01Y1477507D01*
G03X298770Y1477639I-200J0D01*
G02Y1480551I1664J1456D01*
G03X298820Y1480683I-150J132D01*
G01Y1481305D01*
G02X299023Y1481508I203J0D01*
G37*
G36*
G01X454929D02*
X457749D01*
G02X457952Y1481305I0J-203D01*
G01Y1480683D01*
G03X458002Y1480551I200J0D01*
G02Y1477639I-1664J-1456D01*
G03X457952Y1477507I150J-132D01*
G01Y1475565D01*
G03X458002Y1475433I200J0D01*
G02Y1472521I-1664J-1456D01*
G03X457952Y1472389I150J-132D01*
G01Y1471767D01*
G02X457749Y1471564I-203J0D01*
G01X454929D01*
G02X454726Y1471767I0J203D01*
G01Y1472389D01*
G03X454676Y1472521I-200J0D01*
G02Y1475433I1664J1456D01*
G03X454726Y1475565I-150J132D01*
G01Y1477507D01*
G03X454676Y1477639I-200J0D01*
G02Y1480551I1664J1456D01*
G03X454726Y1480683I-150J132D01*
G01Y1481305D01*
G02X454929Y1481508I203J0D01*
G37*
G36*
G01X472252D02*
X475072D01*
G02X475274Y1481305I-1J-203D01*
G01Y1480685D01*
G03X475324Y1480553I200J0D01*
G02Y1477637I-1661J-1458D01*
G03X475274Y1477505I150J-132D01*
G01Y1475567D01*
G03X475324Y1475435I200J0D01*
G02Y1472519I-1661J-1458D01*
G03X475274Y1472387I150J-132D01*
G01Y1471767D01*
G02X475072Y1471564I-202J-1D01*
G01X472252D01*
G02X472050Y1471767I1J203D01*
G01Y1472387D01*
G03X472000Y1472519I-200J0D01*
G02Y1475435I1661J1458D01*
G03X472050Y1475567I-150J132D01*
G01Y1477505D01*
G03X472000Y1477637I-200J0D01*
G02Y1480553I1661J1458D01*
G03X472050Y1480685I-150J132D01*
G01Y1481305D01*
G02X472252Y1481508I202J1D01*
G37*
G36*
G01X489575D02*
X492395D01*
G02X492598Y1481305I0J-203D01*
G01Y1480683D01*
G03X492648Y1480551I200J0D01*
G02Y1477639I-1664J-1456D01*
G03X492598Y1477507I150J-132D01*
G01Y1475565D01*
G03X492648Y1475433I200J0D01*
G02Y1472521I-1664J-1456D01*
G03X492598Y1472389I150J-132D01*
G01Y1471767D01*
G02X492395Y1471564I-203J0D01*
G01X489575D01*
G02X489372Y1471767I0J203D01*
G01Y1472389D01*
G03X489322Y1472521I-200J0D01*
G02Y1475433I1664J1456D01*
G03X489372Y1475565I-150J132D01*
G01Y1477507D01*
G03X489322Y1477639I-200J0D01*
G02Y1480551I1664J1456D01*
G03X489372Y1480683I-150J132D01*
G01Y1481305D01*
G02X489575Y1481508I203J0D01*
G37*
G36*
G01X506897D02*
X509717D01*
G02X509920Y1481305I0J-203D01*
G01Y1480683D01*
G03X509970Y1480551I200J0D01*
G02Y1477639I-1664J-1456D01*
G03X509920Y1477507I150J-132D01*
G01Y1475565D01*
G03X509970Y1475433I200J0D01*
G02Y1472521I-1664J-1456D01*
G03X509920Y1472389I150J-132D01*
G01Y1471767D01*
G02X509717Y1471564I-203J0D01*
G01X506897D01*
G02X506694Y1471767I0J203D01*
G01Y1472389D01*
G03X506644Y1472521I-200J0D01*
G02Y1475433I1664J1456D01*
G03X506694Y1475565I-150J132D01*
G01Y1477507D01*
G03X506644Y1477639I-200J0D01*
G02Y1480551I1664J1456D01*
G03X506694Y1480683I-150J132D01*
G01Y1481305D01*
G02X506897Y1481508I203J0D01*
G37*
G36*
G01X645480D02*
X648300D01*
G02X648502Y1481305I-1J-203D01*
G01Y1480685D01*
G03X648552Y1480553I200J0D01*
G02Y1477637I-1661J-1458D01*
G03X648502Y1477505I150J-132D01*
G01Y1475567D01*
G03X648552Y1475435I200J0D01*
G02Y1472519I-1661J-1458D01*
G03X648502Y1472387I150J-132D01*
G01Y1471767D01*
G02X648300Y1471564I-202J-1D01*
G01X645480D01*
G02X645278Y1471767I1J203D01*
G01Y1472387D01*
G03X645228Y1472519I-200J0D01*
G02Y1475435I1661J1458D01*
G03X645278Y1475567I-150J132D01*
G01Y1477505D01*
G03X645228Y1477637I-200J0D01*
G02Y1480553I1661J1458D01*
G03X645278Y1480685I-150J132D01*
G01Y1481305D01*
G02X645480Y1481508I202J1D01*
G37*
G36*
G01X662803D02*
X665623D01*
G02X665826Y1481305I0J-203D01*
G01Y1480683D01*
G03X665876Y1480551I200J0D01*
G02Y1477639I-1664J-1456D01*
G03X665826Y1477507I150J-132D01*
G01Y1475565D01*
G03X665876Y1475433I200J0D01*
G02Y1472521I-1664J-1456D01*
G03X665826Y1472389I150J-132D01*
G01Y1471767D01*
G02X665623Y1471564I-203J0D01*
G01X662803D01*
G02X662600Y1471767I0J203D01*
G01Y1472389D01*
G03X662550Y1472521I-200J0D01*
G02Y1475433I1664J1456D01*
G03X662600Y1475565I-150J132D01*
G01Y1477507D01*
G03X662550Y1477639I-200J0D01*
G02Y1480551I1664J1456D01*
G03X662600Y1480683I-150J132D01*
G01Y1481305D01*
G02X662803Y1481508I203J0D01*
G37*
G36*
G01X680125D02*
X682945D01*
G02X683148Y1481305I0J-203D01*
G01Y1480683D01*
G03X683198Y1480551I200J0D01*
G02Y1477639I-1664J-1456D01*
G03X683148Y1477507I150J-132D01*
G01Y1475565D01*
G03X683198Y1475433I200J0D01*
G02Y1472521I-1664J-1456D01*
G03X683148Y1472389I150J-132D01*
G01Y1471767D01*
G02X682945Y1471564I-203J0D01*
G01X680125D01*
G02X679922Y1471767I0J203D01*
G01Y1472389D01*
G03X679872Y1472521I-200J0D01*
G02Y1475433I1664J1456D01*
G03X679922Y1475565I-150J132D01*
G01Y1477507D01*
G03X679872Y1477639I-200J0D01*
G02Y1480551I1664J1456D01*
G03X679922Y1480683I-150J132D01*
G01Y1481305D01*
G02X680125Y1481508I203J0D01*
G37*
G36*
G01X1165086D02*
X1167906D01*
G02X1168108Y1481305I-1J-203D01*
G01Y1480685D01*
G03X1168158Y1480553I200J0D01*
G02Y1477637I-1661J-1458D01*
G03X1168108Y1477505I150J-132D01*
G01Y1475567D01*
G03X1168158Y1475435I200J0D01*
G02Y1472519I-1661J-1458D01*
G03X1168108Y1472387I150J-132D01*
G01Y1471767D01*
G02X1167906Y1471564I-202J-1D01*
G01X1165086D01*
G02X1164884Y1471767I1J203D01*
G01Y1472387D01*
G03X1164834Y1472519I-200J0D01*
G02Y1475435I1661J1458D01*
G03X1164884Y1475567I-150J132D01*
G01Y1477505D01*
G03X1164834Y1477637I-200J0D01*
G02Y1480553I1661J1458D01*
G03X1164884Y1480685I-150J132D01*
G01Y1481305D01*
G02X1165086Y1481508I202J1D01*
G37*
G36*
G01X1182408D02*
X1185228D01*
G02X1185430Y1481305I-1J-203D01*
G01Y1480685D01*
G03X1185480Y1480553I200J0D01*
G02Y1477637I-1661J-1458D01*
G03X1185430Y1477505I150J-132D01*
G01Y1475567D01*
G03X1185480Y1475435I200J0D01*
G02Y1472519I-1661J-1458D01*
G03X1185430Y1472387I150J-132D01*
G01Y1471767D01*
G02X1185228Y1471564I-202J-1D01*
G01X1182408D01*
G02X1182206Y1471767I1J203D01*
G01Y1472387D01*
G03X1182156Y1472519I-200J0D01*
G02Y1475435I1661J1458D01*
G03X1182206Y1475567I-150J132D01*
G01Y1477505D01*
G03X1182156Y1477637I-200J0D01*
G02Y1480553I1661J1458D01*
G03X1182206Y1480685I-150J132D01*
G01Y1481305D01*
G02X1182408Y1481508I202J1D01*
G37*
G36*
G01X1303669D02*
X1306489D01*
G02X1306692Y1481305I0J-203D01*
G01Y1480683D01*
G03X1306742Y1480551I200J0D01*
G02Y1477639I-1664J-1456D01*
G03X1306692Y1477507I150J-132D01*
G01Y1475565D01*
G03X1306742Y1475433I200J0D01*
G02Y1472521I-1664J-1456D01*
G03X1306692Y1472389I150J-132D01*
G01Y1471767D01*
G02X1306489Y1471564I-203J0D01*
G01X1303669D01*
G02X1303466Y1471767I0J203D01*
G01Y1472389D01*
G03X1303416Y1472521I-200J0D01*
G02Y1475433I1664J1456D01*
G03X1303466Y1475565I-150J132D01*
G01Y1477507D01*
G03X1303416Y1477639I-200J0D01*
G02Y1480551I1664J1456D01*
G03X1303466Y1480683I-150J132D01*
G01Y1481305D01*
G02X1303669Y1481508I203J0D01*
G37*
G36*
G01X1320992D02*
X1323812D01*
G02X1324014Y1481305I-1J-203D01*
G01Y1480685D01*
G03X1324064Y1480553I200J0D01*
G02Y1477637I-1661J-1458D01*
G03X1324014Y1477505I150J-132D01*
G01Y1475567D01*
G03X1324064Y1475435I200J0D01*
G02Y1472519I-1661J-1458D01*
G03X1324014Y1472387I150J-132D01*
G01Y1471767D01*
G02X1323812Y1471564I-202J-1D01*
G01X1320992D01*
G02X1320790Y1471767I1J203D01*
G01Y1472387D01*
G03X1320740Y1472519I-200J0D01*
G02Y1475435I1661J1458D01*
G03X1320790Y1475567I-150J132D01*
G01Y1477505D01*
G03X1320740Y1477637I-200J0D01*
G02Y1480553I1661J1458D01*
G03X1320790Y1480685I-150J132D01*
G01Y1481305D01*
G02X1320992Y1481508I202J1D01*
G37*
G36*
G01X1338315D02*
X1341135D01*
G02X1341338Y1481305I0J-203D01*
G01Y1480683D01*
G03X1341388Y1480551I200J0D01*
G02Y1477639I-1664J-1456D01*
G03X1341338Y1477507I150J-132D01*
G01Y1475565D01*
G03X1341388Y1475433I200J0D01*
G02Y1472521I-1664J-1456D01*
G03X1341338Y1472389I150J-132D01*
G01Y1471767D01*
G02X1341135Y1471564I-203J0D01*
G01X1338315D01*
G02X1338112Y1471767I0J203D01*
G01Y1472389D01*
G03X1338062Y1472521I-200J0D01*
G02Y1475433I1664J1456D01*
G03X1338112Y1475565I-150J132D01*
G01Y1477507D01*
G03X1338062Y1477639I-200J0D01*
G02Y1480551I1664J1456D01*
G03X1338112Y1480683I-150J132D01*
G01Y1481305D01*
G02X1338315Y1481508I203J0D01*
G37*
G36*
G01X1355637D02*
X1358457D01*
G02X1358660Y1481305I0J-203D01*
G01Y1480683D01*
G03X1358710Y1480551I200J0D01*
G02Y1477639I-1664J-1456D01*
G03X1358660Y1477507I150J-132D01*
G01Y1475565D01*
G03X1358710Y1475433I200J0D01*
G02Y1472521I-1664J-1456D01*
G03X1358660Y1472389I150J-132D01*
G01Y1471767D01*
G02X1358457Y1471564I-203J0D01*
G01X1355637D01*
G02X1355434Y1471767I0J203D01*
G01Y1472389D01*
G03X1355384Y1472521I-200J0D01*
G02Y1475433I1664J1456D01*
G03X1355434Y1475565I-150J132D01*
G01Y1477507D01*
G03X1355384Y1477639I-200J0D01*
G02Y1480551I1664J1456D01*
G03X1355434Y1480683I-150J132D01*
G01Y1481305D01*
G02X1355637Y1481508I203J0D01*
G37*
G36*
G01X1476897D02*
X1479717D01*
G02X1479920Y1481305I0J-203D01*
G01Y1480683D01*
G03X1479970Y1480551I200J0D01*
G02Y1477639I-1664J-1456D01*
G03X1479920Y1477507I150J-132D01*
G01Y1475565D01*
G03X1479970Y1475433I200J0D01*
G02Y1472521I-1664J-1456D01*
G03X1479920Y1472389I150J-132D01*
G01Y1471767D01*
G02X1479717Y1471564I-203J0D01*
G01X1476897D01*
G02X1476694Y1471767I0J203D01*
G01Y1472389D01*
G03X1476644Y1472521I-200J0D01*
G02Y1475433I1664J1456D01*
G03X1476694Y1475565I-150J132D01*
G01Y1477507D01*
G03X1476644Y1477639I-200J0D01*
G02Y1480551I1664J1456D01*
G03X1476694Y1480683I-150J132D01*
G01Y1481305D01*
G02X1476897Y1481508I203J0D01*
G37*
G36*
G01X1494220D02*
X1497040D01*
G02X1497242Y1481305I-1J-203D01*
G01Y1480685D01*
G03X1497292Y1480553I200J0D01*
G02Y1477637I-1661J-1458D01*
G03X1497242Y1477505I150J-132D01*
G01Y1475567D01*
G03X1497292Y1475435I200J0D01*
G02Y1472519I-1661J-1458D01*
G03X1497242Y1472387I150J-132D01*
G01Y1471767D01*
G02X1497040Y1471564I-202J-1D01*
G01X1494220D01*
G02X1494018Y1471767I1J203D01*
G01Y1472387D01*
G03X1493968Y1472519I-200J0D01*
G02Y1475435I1661J1458D01*
G03X1494018Y1475567I-150J132D01*
G01Y1477505D01*
G03X1493968Y1477637I-200J0D01*
G02Y1480553I1661J1458D01*
G03X1494018Y1480685I-150J132D01*
G01Y1481305D01*
G02X1494220Y1481508I202J1D01*
G37*
G36*
G01X1511543D02*
X1514363D01*
G02X1514566Y1481305I0J-203D01*
G01Y1480683D01*
G03X1514616Y1480551I200J0D01*
G02Y1477639I-1664J-1456D01*
G03X1514566Y1477507I150J-132D01*
G01Y1475565D01*
G03X1514616Y1475433I200J0D01*
G02Y1472521I-1664J-1456D01*
G03X1514566Y1472389I150J-132D01*
G01Y1471767D01*
G02X1514363Y1471564I-203J0D01*
G01X1511543D01*
G02X1511340Y1471767I0J203D01*
G01Y1472389D01*
G03X1511290Y1472521I-200J0D01*
G02Y1475433I1664J1456D01*
G03X1511340Y1475565I-150J132D01*
G01Y1477507D01*
G03X1511290Y1477639I-200J0D01*
G02Y1480551I1664J1456D01*
G03X1511340Y1480683I-150J132D01*
G01Y1481305D01*
G02X1511543Y1481508I203J0D01*
G37*
G36*
G01X1528865D02*
X1531685D01*
G02X1531888Y1481305I0J-203D01*
G01Y1480683D01*
G03X1531938Y1480551I200J0D01*
G02Y1477639I-1664J-1456D01*
G03X1531888Y1477507I150J-132D01*
G01Y1475565D01*
G03X1531938Y1475433I200J0D01*
G02Y1472521I-1664J-1456D01*
G03X1531888Y1472389I150J-132D01*
G01Y1471767D01*
G02X1531685Y1471564I-203J0D01*
G01X1528865D01*
G02X1528662Y1471767I0J203D01*
G01Y1472389D01*
G03X1528612Y1472521I-200J0D01*
G02Y1475433I1664J1456D01*
G03X1528662Y1475565I-150J132D01*
G01Y1477507D01*
G03X1528612Y1477639I-200J0D01*
G02Y1480551I1664J1456D01*
G03X1528662Y1480683I-150J132D01*
G01Y1481305D01*
G02X1528865Y1481508I203J0D01*
G37*
G36*
G01X1684771D02*
X1687591D01*
G02X1687794Y1481305I0J-203D01*
G01Y1480683D01*
G03X1687844Y1480551I200J0D01*
G02Y1477639I-1664J-1456D01*
G03X1687794Y1477507I150J-132D01*
G01Y1475565D01*
G03X1687844Y1475433I200J0D01*
G02Y1472521I-1664J-1456D01*
G03X1687794Y1472389I150J-132D01*
G01Y1471767D01*
G02X1687591Y1471564I-203J0D01*
G01X1684771D01*
G02X1684568Y1471767I0J203D01*
G01Y1472389D01*
G03X1684518Y1472521I-200J0D01*
G02Y1475433I1664J1456D01*
G03X1684568Y1475565I-150J132D01*
G01Y1477507D01*
G03X1684518Y1477639I-200J0D01*
G02Y1480551I1664J1456D01*
G03X1684568Y1480683I-150J132D01*
G01Y1481305D01*
G02X1684771Y1481508I203J0D01*
G37*
G36*
G01X1702093D02*
X1704913D01*
G02X1705116Y1481305I0J-203D01*
G01Y1480683D01*
G03X1705166Y1480551I200J0D01*
G02Y1477639I-1664J-1456D01*
G03X1705116Y1477507I150J-132D01*
G01Y1475565D01*
G03X1705166Y1475433I200J0D01*
G02Y1472521I-1664J-1456D01*
G03X1705116Y1472389I150J-132D01*
G01Y1471767D01*
G02X1704913Y1471564I-203J0D01*
G01X1702093D01*
G02X1701890Y1471767I0J203D01*
G01Y1472389D01*
G03X1701840Y1472521I-200J0D01*
G02Y1475433I1664J1456D01*
G03X1701890Y1475565I-150J132D01*
G01Y1477507D01*
G03X1701840Y1477639I-200J0D01*
G02Y1480551I1664J1456D01*
G03X1701890Y1480683I-150J132D01*
G01Y1481305D01*
G02X1702093Y1481508I203J0D01*
G37*
G36*
G01X134456Y1485838D02*
X137276D01*
G02X137478Y1485635I-1J-203D01*
G01Y1485016D01*
G03X137528Y1484884I200J0D01*
G02Y1481968I-1661J-1458D01*
G03X137478Y1481836I150J-132D01*
G01Y1479898D01*
G03X137528Y1479766I200J0D01*
G02Y1476850I-1661J-1458D01*
G03X137478Y1476718I150J-132D01*
G01Y1476097D01*
G02X137276Y1475894I-202J-1D01*
G01X134456D01*
G02X134254Y1476097I1J203D01*
G01Y1476718D01*
G03X134204Y1476850I-200J0D01*
G02Y1479766I1661J1458D01*
G03X134254Y1479898I-150J132D01*
G01Y1481836D01*
G03X134204Y1481968I-200J0D01*
G02Y1484884I1661J1458D01*
G03X134254Y1485016I-150J132D01*
G01Y1485635D01*
G02X134456Y1485838I202J1D01*
G37*
G36*
G01X151779D02*
X154599D01*
G02X154802Y1485635I0J-203D01*
G01Y1485014D01*
G03X154852Y1484882I200J0D01*
G02Y1481970I-1664J-1456D01*
G03X154802Y1481838I150J-132D01*
G01Y1479896D01*
G03X154852Y1479764I200J0D01*
G02Y1476852I-1664J-1456D01*
G03X154802Y1476720I150J-132D01*
G01Y1476097D01*
G02X154599Y1475894I-203J0D01*
G01X151779D01*
G02X151576Y1476097I0J203D01*
G01Y1476720D01*
G03X151526Y1476852I-200J0D01*
G02Y1479764I1664J1456D01*
G03X151576Y1479896I-150J132D01*
G01Y1481838D01*
G03X151526Y1481970I-200J0D01*
G02Y1484882I1664J1456D01*
G03X151576Y1485014I-150J132D01*
G01Y1485635D01*
G02X151779Y1485838I203J0D01*
G37*
G36*
G01X169102D02*
X171922D01*
G02X172124Y1485635I-1J-203D01*
G01Y1485016D01*
G03X172174Y1484884I200J0D01*
G02Y1481968I-1661J-1458D01*
G03X172124Y1481836I150J-132D01*
G01Y1479898D01*
G03X172174Y1479766I200J0D01*
G02Y1476850I-1661J-1458D01*
G03X172124Y1476718I150J-132D01*
G01Y1476097D01*
G02X171922Y1475894I-202J-1D01*
G01X169102D01*
G02X168900Y1476097I1J203D01*
G01Y1476718D01*
G03X168850Y1476850I-200J0D01*
G02Y1479766I1661J1458D01*
G03X168900Y1479898I-150J132D01*
G01Y1481836D01*
G03X168850Y1481968I-200J0D01*
G02Y1484884I1661J1458D01*
G03X168900Y1485016I-150J132D01*
G01Y1485635D01*
G02X169102Y1485838I202J1D01*
G37*
G36*
G01X290361D02*
X293181D01*
G02X293384Y1485635I0J-203D01*
G01Y1485014D01*
G03X293434Y1484882I200J0D01*
G02Y1481970I-1664J-1456D01*
G03X293384Y1481838I150J-132D01*
G01Y1479896D01*
G03X293434Y1479764I200J0D01*
G02Y1476852I-1664J-1456D01*
G03X293384Y1476720I150J-132D01*
G01Y1476097D01*
G02X293181Y1475894I-203J0D01*
G01X290361D01*
G02X290158Y1476097I0J203D01*
G01Y1476720D01*
G03X290108Y1476852I-200J0D01*
G02Y1479764I1664J1456D01*
G03X290158Y1479896I-150J132D01*
G01Y1481838D01*
G03X290108Y1481970I-200J0D01*
G02Y1484882I1664J1456D01*
G03X290158Y1485014I-150J132D01*
G01Y1485635D01*
G02X290361Y1485838I203J0D01*
G37*
G36*
G01X463590D02*
X466410D01*
G02X466612Y1485635I-1J-203D01*
G01Y1485016D01*
G03X466662Y1484884I200J0D01*
G02Y1481968I-1661J-1458D01*
G03X466612Y1481836I150J-132D01*
G01Y1479898D01*
G03X466662Y1479766I200J0D01*
G02Y1476850I-1661J-1458D01*
G03X466612Y1476718I150J-132D01*
G01Y1476097D01*
G02X466410Y1475894I-202J-1D01*
G01X463590D01*
G02X463388Y1476097I1J203D01*
G01Y1476718D01*
G03X463338Y1476850I-200J0D01*
G02Y1479766I1661J1458D01*
G03X463388Y1479898I-150J132D01*
G01Y1481836D01*
G03X463338Y1481968I-200J0D01*
G02Y1484884I1661J1458D01*
G03X463388Y1485016I-150J132D01*
G01Y1485635D01*
G02X463590Y1485838I202J1D01*
G37*
G36*
G01X480913D02*
X483733D01*
G02X483936Y1485635I0J-203D01*
G01Y1485014D01*
G03X483986Y1484882I200J0D01*
G02Y1481970I-1664J-1456D01*
G03X483936Y1481838I150J-132D01*
G01Y1479896D01*
G03X483986Y1479764I200J0D01*
G02Y1476852I-1664J-1456D01*
G03X483936Y1476720I150J-132D01*
G01Y1476097D01*
G02X483733Y1475894I-203J0D01*
G01X480913D01*
G02X480710Y1476097I0J203D01*
G01Y1476720D01*
G03X480660Y1476852I-200J0D01*
G02Y1479764I1664J1456D01*
G03X480710Y1479896I-150J132D01*
G01Y1481838D01*
G03X480660Y1481970I-200J0D01*
G02Y1484882I1664J1456D01*
G03X480710Y1485014I-150J132D01*
G01Y1485635D01*
G02X480913Y1485838I203J0D01*
G37*
G36*
G01X498236D02*
X501056D01*
G02X501258Y1485635I-1J-203D01*
G01Y1485016D01*
G03X501308Y1484884I200J0D01*
G02Y1481968I-1661J-1458D01*
G03X501258Y1481836I150J-132D01*
G01Y1479898D01*
G03X501308Y1479766I200J0D01*
G02Y1476850I-1661J-1458D01*
G03X501258Y1476718I150J-132D01*
G01Y1476097D01*
G02X501056Y1475894I-202J-1D01*
G01X498236D01*
G02X498034Y1476097I1J203D01*
G01Y1476718D01*
G03X497984Y1476850I-200J0D01*
G02Y1479766I1661J1458D01*
G03X498034Y1479898I-150J132D01*
G01Y1481836D01*
G03X497984Y1481968I-200J0D01*
G02Y1484884I1661J1458D01*
G03X498034Y1485016I-150J132D01*
G01Y1485635D01*
G02X498236Y1485838I202J1D01*
G37*
G36*
G01X515559D02*
X518379D01*
G02X518582Y1485635I0J-203D01*
G01Y1485014D01*
G03X518632Y1484882I200J0D01*
G02Y1481970I-1664J-1456D01*
G03X518582Y1481838I150J-132D01*
G01Y1479896D01*
G03X518632Y1479764I200J0D01*
G02Y1476852I-1664J-1456D01*
G03X518582Y1476720I150J-132D01*
G01Y1476097D01*
G02X518379Y1475894I-203J0D01*
G01X515559D01*
G02X515356Y1476097I0J203D01*
G01Y1476720D01*
G03X515306Y1476852I-200J0D01*
G02Y1479764I1664J1456D01*
G03X515356Y1479896I-150J132D01*
G01Y1481838D01*
G03X515306Y1481970I-200J0D01*
G02Y1484882I1664J1456D01*
G03X515356Y1485014I-150J132D01*
G01Y1485635D01*
G02X515559Y1485838I203J0D01*
G37*
G36*
G01X654141D02*
X656961D01*
G02X657164Y1485635I0J-203D01*
G01Y1485014D01*
G03X657214Y1484882I200J0D01*
G02Y1481970I-1664J-1456D01*
G03X657164Y1481838I150J-132D01*
G01Y1479896D01*
G03X657214Y1479764I200J0D01*
G02Y1476852I-1664J-1456D01*
G03X657164Y1476720I150J-132D01*
G01Y1476097D01*
G02X656961Y1475894I-203J0D01*
G01X654141D01*
G02X653938Y1476097I0J203D01*
G01Y1476720D01*
G03X653888Y1476852I-200J0D01*
G02Y1479764I1664J1456D01*
G03X653938Y1479896I-150J132D01*
G01Y1481838D01*
G03X653888Y1481970I-200J0D01*
G02Y1484882I1664J1456D01*
G03X653938Y1485014I-150J132D01*
G01Y1485635D01*
G02X654141Y1485838I203J0D01*
G37*
G36*
G01X671464D02*
X674284D01*
G02X674486Y1485635I-1J-203D01*
G01Y1485016D01*
G03X674536Y1484884I200J0D01*
G02Y1481968I-1661J-1458D01*
G03X674486Y1481836I150J-132D01*
G01Y1479898D01*
G03X674536Y1479766I200J0D01*
G02Y1476850I-1661J-1458D01*
G03X674486Y1476718I150J-132D01*
G01Y1476097D01*
G02X674284Y1475894I-202J-1D01*
G01X671464D01*
G02X671262Y1476097I1J203D01*
G01Y1476718D01*
G03X671212Y1476850I-200J0D01*
G02Y1479766I1661J1458D01*
G03X671262Y1479898I-150J132D01*
G01Y1481836D01*
G03X671212Y1481968I-200J0D01*
G02Y1484884I1661J1458D01*
G03X671262Y1485016I-150J132D01*
G01Y1485635D01*
G02X671464Y1485838I202J1D01*
G37*
G36*
G01X688787D02*
X691607D01*
G02X691810Y1485635I0J-203D01*
G01Y1485014D01*
G03X691860Y1484882I200J0D01*
G02Y1481970I-1664J-1456D01*
G03X691810Y1481838I150J-132D01*
G01Y1479896D01*
G03X691860Y1479764I200J0D01*
G02Y1476852I-1664J-1456D01*
G03X691810Y1476720I150J-132D01*
G01Y1476097D01*
G02X691607Y1475894I-203J0D01*
G01X688787D01*
G02X688584Y1476097I0J203D01*
G01Y1476720D01*
G03X688534Y1476852I-200J0D01*
G02Y1479764I1664J1456D01*
G03X688584Y1479896I-150J132D01*
G01Y1481838D01*
G03X688534Y1481970I-200J0D01*
G02Y1484882I1664J1456D01*
G03X688584Y1485014I-150J132D01*
G01Y1485635D01*
G02X688787Y1485838I203J0D01*
G37*
G36*
G01X1173747D02*
X1176567D01*
G02X1176770Y1485635I0J-203D01*
G01Y1485014D01*
G03X1176820Y1484882I200J0D01*
G02Y1481970I-1664J-1456D01*
G03X1176770Y1481838I150J-132D01*
G01Y1479896D01*
G03X1176820Y1479764I200J0D01*
G02Y1476852I-1664J-1456D01*
G03X1176770Y1476720I150J-132D01*
G01Y1476097D01*
G02X1176567Y1475894I-203J0D01*
G01X1173747D01*
G02X1173544Y1476097I0J203D01*
G01Y1476720D01*
G03X1173494Y1476852I-200J0D01*
G02Y1479764I1664J1456D01*
G03X1173544Y1479896I-150J132D01*
G01Y1481838D01*
G03X1173494Y1481970I-200J0D01*
G02Y1484882I1664J1456D01*
G03X1173544Y1485014I-150J132D01*
G01Y1485635D01*
G02X1173747Y1485838I203J0D01*
G37*
G36*
G01X1191070D02*
X1193890D01*
G02X1194092Y1485635I-1J-203D01*
G01Y1485016D01*
G03X1194142Y1484884I200J0D01*
G02Y1481968I-1661J-1458D01*
G03X1194092Y1481836I150J-132D01*
G01Y1479898D01*
G03X1194142Y1479766I200J0D01*
G02Y1476850I-1661J-1458D01*
G03X1194092Y1476718I150J-132D01*
G01Y1476097D01*
G02X1193890Y1475894I-202J-1D01*
G01X1191070D01*
G02X1190868Y1476097I1J203D01*
G01Y1476718D01*
G03X1190818Y1476850I-200J0D01*
G02Y1479766I1661J1458D01*
G03X1190868Y1479898I-150J132D01*
G01Y1481836D01*
G03X1190818Y1481968I-200J0D01*
G02Y1484884I1661J1458D01*
G03X1190868Y1485016I-150J132D01*
G01Y1485635D01*
G02X1191070Y1485838I202J1D01*
G37*
G36*
G01X1312330D02*
X1315150D01*
G02X1315352Y1485635I-1J-203D01*
G01Y1485016D01*
G03X1315402Y1484884I200J0D01*
G02Y1481968I-1661J-1458D01*
G03X1315352Y1481836I150J-132D01*
G01Y1479898D01*
G03X1315402Y1479766I200J0D01*
G02Y1476850I-1661J-1458D01*
G03X1315352Y1476718I150J-132D01*
G01Y1476097D01*
G02X1315150Y1475894I-202J-1D01*
G01X1312330D01*
G02X1312128Y1476097I1J203D01*
G01Y1476718D01*
G03X1312078Y1476850I-200J0D01*
G02Y1479766I1661J1458D01*
G03X1312128Y1479898I-150J132D01*
G01Y1481836D01*
G03X1312078Y1481968I-200J0D01*
G02Y1484884I1661J1458D01*
G03X1312128Y1485016I-150J132D01*
G01Y1485635D01*
G02X1312330Y1485838I202J1D01*
G37*
G36*
G01X1329653D02*
X1332473D01*
G02X1332676Y1485635I0J-203D01*
G01Y1485014D01*
G03X1332726Y1484882I200J0D01*
G02Y1481970I-1664J-1456D01*
G03X1332676Y1481838I150J-132D01*
G01Y1479896D01*
G03X1332726Y1479764I200J0D01*
G02Y1476852I-1664J-1456D01*
G03X1332676Y1476720I150J-132D01*
G01Y1476097D01*
G02X1332473Y1475894I-203J0D01*
G01X1329653D01*
G02X1329450Y1476097I0J203D01*
G01Y1476720D01*
G03X1329400Y1476852I-200J0D01*
G02Y1479764I1664J1456D01*
G03X1329450Y1479896I-150J132D01*
G01Y1481838D01*
G03X1329400Y1481970I-200J0D01*
G02Y1484882I1664J1456D01*
G03X1329450Y1485014I-150J132D01*
G01Y1485635D01*
G02X1329653Y1485838I203J0D01*
G37*
G36*
G01X1346976D02*
X1349796D01*
G02X1349998Y1485635I-1J-203D01*
G01Y1485016D01*
G03X1350048Y1484884I200J0D01*
G02Y1481968I-1661J-1458D01*
G03X1349998Y1481836I150J-132D01*
G01Y1479898D01*
G03X1350048Y1479766I200J0D01*
G02Y1476850I-1661J-1458D01*
G03X1349998Y1476718I150J-132D01*
G01Y1476097D01*
G02X1349796Y1475894I-202J-1D01*
G01X1346976D01*
G02X1346774Y1476097I1J203D01*
G01Y1476718D01*
G03X1346724Y1476850I-200J0D01*
G02Y1479766I1661J1458D01*
G03X1346774Y1479898I-150J132D01*
G01Y1481836D01*
G03X1346724Y1481968I-200J0D01*
G02Y1484884I1661J1458D01*
G03X1346774Y1485016I-150J132D01*
G01Y1485635D01*
G02X1346976Y1485838I202J1D01*
G37*
G36*
G01X1364299D02*
X1367119D01*
G02X1367322Y1485635I0J-203D01*
G01Y1485014D01*
G03X1367372Y1484882I200J0D01*
G02Y1481970I-1664J-1456D01*
G03X1367322Y1481838I150J-132D01*
G01Y1479896D01*
G03X1367372Y1479764I200J0D01*
G02Y1476852I-1664J-1456D01*
G03X1367322Y1476720I150J-132D01*
G01Y1476097D01*
G02X1367119Y1475894I-203J0D01*
G01X1364299D01*
G02X1364096Y1476097I0J203D01*
G01Y1476720D01*
G03X1364046Y1476852I-200J0D01*
G02Y1479764I1664J1456D01*
G03X1364096Y1479896I-150J132D01*
G01Y1481838D01*
G03X1364046Y1481970I-200J0D01*
G02Y1484882I1664J1456D01*
G03X1364096Y1485014I-150J132D01*
G01Y1485635D01*
G02X1364299Y1485838I203J0D01*
G37*
G36*
G01X1485558D02*
X1488378D01*
G02X1488580Y1485635I-1J-203D01*
G01Y1485016D01*
G03X1488630Y1484884I200J0D01*
G02Y1481968I-1661J-1458D01*
G03X1488580Y1481836I150J-132D01*
G01Y1479898D01*
G03X1488630Y1479766I200J0D01*
G02Y1476850I-1661J-1458D01*
G03X1488580Y1476718I150J-132D01*
G01Y1476097D01*
G02X1488378Y1475894I-202J-1D01*
G01X1485558D01*
G02X1485356Y1476097I1J203D01*
G01Y1476718D01*
G03X1485306Y1476850I-200J0D01*
G02Y1479766I1661J1458D01*
G03X1485356Y1479898I-150J132D01*
G01Y1481836D01*
G03X1485306Y1481968I-200J0D01*
G02Y1484884I1661J1458D01*
G03X1485356Y1485016I-150J132D01*
G01Y1485635D01*
G02X1485558Y1485838I202J1D01*
G37*
G36*
G01X1502881D02*
X1505701D01*
G02X1505904Y1485635I0J-203D01*
G01Y1485014D01*
G03X1505954Y1484882I200J0D01*
G02Y1481970I-1664J-1456D01*
G03X1505904Y1481838I150J-132D01*
G01Y1479896D01*
G03X1505954Y1479764I200J0D01*
G02Y1476852I-1664J-1456D01*
G03X1505904Y1476720I150J-132D01*
G01Y1476097D01*
G02X1505701Y1475894I-203J0D01*
G01X1502881D01*
G02X1502678Y1476097I0J203D01*
G01Y1476720D01*
G03X1502628Y1476852I-200J0D01*
G02Y1479764I1664J1456D01*
G03X1502678Y1479896I-150J132D01*
G01Y1481838D01*
G03X1502628Y1481970I-200J0D01*
G02Y1484882I1664J1456D01*
G03X1502678Y1485014I-150J132D01*
G01Y1485635D01*
G02X1502881Y1485838I203J0D01*
G37*
G36*
G01X1520204D02*
X1523024D01*
G02X1523226Y1485635I-1J-203D01*
G01Y1485016D01*
G03X1523276Y1484884I200J0D01*
G02Y1481968I-1661J-1458D01*
G03X1523226Y1481836I150J-132D01*
G01Y1479898D01*
G03X1523276Y1479766I200J0D01*
G02Y1476850I-1661J-1458D01*
G03X1523226Y1476718I150J-132D01*
G01Y1476097D01*
G02X1523024Y1475894I-202J-1D01*
G01X1520204D01*
G02X1520002Y1476097I1J203D01*
G01Y1476718D01*
G03X1519952Y1476850I-200J0D01*
G02Y1479766I1661J1458D01*
G03X1520002Y1479898I-150J132D01*
G01Y1481836D01*
G03X1519952Y1481968I-200J0D01*
G02Y1484884I1661J1458D01*
G03X1520002Y1485016I-150J132D01*
G01Y1485635D01*
G02X1520204Y1485838I202J1D01*
G37*
G36*
G01X1537527D02*
X1540347D01*
G02X1540550Y1485635I0J-203D01*
G01Y1485014D01*
G03X1540600Y1484882I200J0D01*
G02Y1481970I-1664J-1456D01*
G03X1540550Y1481838I150J-132D01*
G01Y1479896D01*
G03X1540600Y1479764I200J0D01*
G02Y1476852I-1664J-1456D01*
G03X1540550Y1476720I150J-132D01*
G01Y1476097D01*
G02X1540347Y1475894I-203J0D01*
G01X1537527D01*
G02X1537324Y1476097I0J203D01*
G01Y1476720D01*
G03X1537274Y1476852I-200J0D01*
G02Y1479764I1664J1456D01*
G03X1537324Y1479896I-150J132D01*
G01Y1481838D01*
G03X1537274Y1481970I-200J0D01*
G02Y1484882I1664J1456D01*
G03X1537324Y1485014I-150J132D01*
G01Y1485635D01*
G02X1537527Y1485838I203J0D01*
G37*
G36*
G01X1693432D02*
X1696252D01*
G02X1696454Y1485635I-1J-203D01*
G01Y1485016D01*
G03X1696504Y1484884I200J0D01*
G02Y1481968I-1661J-1458D01*
G03X1696454Y1481836I150J-132D01*
G01Y1479898D01*
G03X1696504Y1479766I200J0D01*
G02Y1476850I-1661J-1458D01*
G03X1696454Y1476718I150J-132D01*
G01Y1476097D01*
G02X1696252Y1475894I-202J-1D01*
G01X1693432D01*
G02X1693230Y1476097I1J203D01*
G01Y1476718D01*
G03X1693180Y1476850I-200J0D01*
G02Y1479766I1661J1458D01*
G03X1693230Y1479898I-150J132D01*
G01Y1481836D01*
G03X1693180Y1481968I-200J0D01*
G02Y1484884I1661J1458D01*
G03X1693230Y1485016I-150J132D01*
G01Y1485635D01*
G02X1693432Y1485838I202J1D01*
G37*
G36*
G01X1710755D02*
X1713575D01*
G02X1713778Y1485635I0J-203D01*
G01Y1485014D01*
G03X1713828Y1484882I200J0D01*
G02Y1481970I-1664J-1456D01*
G03X1713778Y1481838I150J-132D01*
G01Y1479896D01*
G03X1713828Y1479764I200J0D01*
G02Y1476852I-1664J-1456D01*
G03X1713778Y1476720I150J-132D01*
G01Y1476097D01*
G02X1713575Y1475894I-203J0D01*
G01X1710755D01*
G02X1710552Y1476097I0J203D01*
G01Y1476720D01*
G03X1710502Y1476852I-200J0D01*
G02Y1479764I1664J1456D01*
G03X1710552Y1479896I-150J132D01*
G01Y1481838D01*
G03X1710502Y1481970I-200J0D01*
G02Y1484882I1664J1456D01*
G03X1710552Y1485014I-150J132D01*
G01Y1485635D01*
G02X1710755Y1485838I203J0D01*
G37*
G36*
G01X186425D02*
X189245D01*
G02X189448Y1485636I1J-202D01*
G01Y1485014D01*
G03X189498Y1484882I200J0D01*
G02Y1481970I-1664J-1456D01*
G03X189448Y1481838I150J-132D01*
G01Y1479896D01*
G03X189498Y1479764I200J0D01*
G02Y1476852I-1664J-1456D01*
G03X189448Y1476720I150J-132D01*
G01Y1476098D01*
G02X189245Y1475896I-203J1D01*
G01X186425D01*
G02X186222Y1476098I-1J202D01*
G01Y1476720D01*
G03X186172Y1476852I-200J0D01*
G02Y1479764I1664J1456D01*
G03X186222Y1479896I-150J132D01*
G01Y1481838D01*
G03X186172Y1481970I-200J0D01*
G02Y1484882I1664J1456D01*
G03X186222Y1485014I-150J132D01*
G01Y1485636D01*
G02X186425Y1485838I203J-1D01*
G37*
G36*
G01X125795Y1496862D02*
X128615D01*
G02X128818Y1496659I0J-203D01*
G01Y1496037D01*
G03X128868Y1495905I200J0D01*
G02Y1492993I-1664J-1456D01*
G03X128818Y1492861I150J-132D01*
G01Y1490919D01*
G03X128868Y1490787I200J0D01*
G02Y1487875I-1664J-1456D01*
G03X128818Y1487743I150J-132D01*
G01Y1487121D01*
G02X128615Y1486918I-203J0D01*
G01X125795D01*
G02X125592Y1487121I0J203D01*
G01Y1487743D01*
G03X125542Y1487875I-200J0D01*
G02Y1490787I1664J1456D01*
G03X125592Y1490919I-150J132D01*
G01Y1492861D01*
G03X125542Y1492993I-200J0D01*
G02Y1495905I1664J1456D01*
G03X125592Y1496037I-150J132D01*
G01Y1496659D01*
G02X125795Y1496862I203J0D01*
G37*
G36*
G01X143118D02*
X145938D01*
G02X146140Y1496659I-1J-203D01*
G01Y1496039D01*
G03X146190Y1495907I200J0D01*
G02Y1492991I-1661J-1458D01*
G03X146140Y1492859I150J-132D01*
G01Y1490921D01*
G03X146190Y1490789I200J0D01*
G02Y1487873I-1661J-1458D01*
G03X146140Y1487741I150J-132D01*
G01Y1487121D01*
G02X145938Y1486918I-202J-1D01*
G01X143118D01*
G02X142916Y1487121I1J203D01*
G01Y1487741D01*
G03X142866Y1487873I-200J0D01*
G02Y1490789I1661J1458D01*
G03X142916Y1490921I-150J132D01*
G01Y1492859D01*
G03X142866Y1492991I-200J0D01*
G02Y1495907I1661J1458D01*
G03X142916Y1496039I-150J132D01*
G01Y1496659D01*
G02X143118Y1496862I202J1D01*
G37*
G36*
G01X160440D02*
X163260D01*
G02X163462Y1496659I-1J-203D01*
G01Y1496039D01*
G03X163512Y1495907I200J0D01*
G02Y1492991I-1661J-1458D01*
G03X163462Y1492859I150J-132D01*
G01Y1490921D01*
G03X163512Y1490789I200J0D01*
G02Y1487873I-1661J-1458D01*
G03X163462Y1487741I150J-132D01*
G01Y1487121D01*
G02X163260Y1486918I-202J-1D01*
G01X160440D01*
G02X160238Y1487121I1J203D01*
G01Y1487741D01*
G03X160188Y1487873I-200J0D01*
G02Y1490789I1661J1458D01*
G03X160238Y1490921I-150J132D01*
G01Y1492859D01*
G03X160188Y1492991I-200J0D01*
G02Y1495907I1661J1458D01*
G03X160238Y1496039I-150J132D01*
G01Y1496659D01*
G02X160440Y1496862I202J1D01*
G37*
G36*
G01X281700D02*
X284520D01*
G02X284722Y1496659I-1J-203D01*
G01Y1496039D01*
G03X284772Y1495907I200J0D01*
G02Y1492991I-1661J-1458D01*
G03X284722Y1492859I150J-132D01*
G01Y1490921D01*
G03X284772Y1490789I200J0D01*
G02Y1487873I-1661J-1458D01*
G03X284722Y1487741I150J-132D01*
G01Y1487121D01*
G02X284520Y1486918I-202J-1D01*
G01X281700D01*
G02X281498Y1487121I1J203D01*
G01Y1487741D01*
G03X281448Y1487873I-200J0D01*
G02Y1490789I1661J1458D01*
G03X281498Y1490921I-150J132D01*
G01Y1492859D01*
G03X281448Y1492991I-200J0D01*
G02Y1495907I1661J1458D01*
G03X281498Y1496039I-150J132D01*
G01Y1496659D01*
G02X281700Y1496862I202J1D01*
G37*
G36*
G01X299023D02*
X301843D01*
G02X302046Y1496659I0J-203D01*
G01Y1496037D01*
G03X302096Y1495905I200J0D01*
G02Y1492993I-1664J-1456D01*
G03X302046Y1492861I150J-132D01*
G01Y1490919D01*
G03X302096Y1490787I200J0D01*
G02Y1487875I-1664J-1456D01*
G03X302046Y1487743I150J-132D01*
G01Y1487121D01*
G02X301843Y1486918I-203J0D01*
G01X299023D01*
G02X298820Y1487121I0J203D01*
G01Y1487743D01*
G03X298770Y1487875I-200J0D01*
G02Y1490787I1664J1456D01*
G03X298820Y1490919I-150J132D01*
G01Y1492861D01*
G03X298770Y1492993I-200J0D01*
G02Y1495905I1664J1456D01*
G03X298820Y1496037I-150J132D01*
G01Y1496659D01*
G02X299023Y1496862I203J0D01*
G37*
G36*
G01X454929D02*
X457749D01*
G02X457952Y1496659I0J-203D01*
G01Y1496037D01*
G03X458002Y1495905I200J0D01*
G02Y1492993I-1664J-1456D01*
G03X457952Y1492861I150J-132D01*
G01Y1490919D01*
G03X458002Y1490787I200J0D01*
G02Y1487875I-1664J-1456D01*
G03X457952Y1487743I150J-132D01*
G01Y1487121D01*
G02X457749Y1486918I-203J0D01*
G01X454929D01*
G02X454726Y1487121I0J203D01*
G01Y1487743D01*
G03X454676Y1487875I-200J0D01*
G02Y1490787I1664J1456D01*
G03X454726Y1490919I-150J132D01*
G01Y1492861D01*
G03X454676Y1492993I-200J0D01*
G02Y1495905I1664J1456D01*
G03X454726Y1496037I-150J132D01*
G01Y1496659D01*
G02X454929Y1496862I203J0D01*
G37*
G36*
G01X472252D02*
X475072D01*
G02X475274Y1496659I-1J-203D01*
G01Y1496039D01*
G03X475324Y1495907I200J0D01*
G02Y1492991I-1661J-1458D01*
G03X475274Y1492859I150J-132D01*
G01Y1490921D01*
G03X475324Y1490789I200J0D01*
G02Y1487873I-1661J-1458D01*
G03X475274Y1487741I150J-132D01*
G01Y1487121D01*
G02X475072Y1486918I-202J-1D01*
G01X472252D01*
G02X472050Y1487121I1J203D01*
G01Y1487741D01*
G03X472000Y1487873I-200J0D01*
G02Y1490789I1661J1458D01*
G03X472050Y1490921I-150J132D01*
G01Y1492859D01*
G03X472000Y1492991I-200J0D01*
G02Y1495907I1661J1458D01*
G03X472050Y1496039I-150J132D01*
G01Y1496659D01*
G02X472252Y1496862I202J1D01*
G37*
G36*
G01X489575D02*
X492395D01*
G02X492598Y1496659I0J-203D01*
G01Y1496037D01*
G03X492648Y1495905I200J0D01*
G02Y1492993I-1664J-1456D01*
G03X492598Y1492861I150J-132D01*
G01Y1490919D01*
G03X492648Y1490787I200J0D01*
G02Y1487875I-1664J-1456D01*
G03X492598Y1487743I150J-132D01*
G01Y1487121D01*
G02X492395Y1486918I-203J0D01*
G01X489575D01*
G02X489372Y1487121I0J203D01*
G01Y1487743D01*
G03X489322Y1487875I-200J0D01*
G02Y1490787I1664J1456D01*
G03X489372Y1490919I-150J132D01*
G01Y1492861D01*
G03X489322Y1492993I-200J0D01*
G02Y1495905I1664J1456D01*
G03X489372Y1496037I-150J132D01*
G01Y1496659D01*
G02X489575Y1496862I203J0D01*
G37*
G36*
G01X506897D02*
X509717D01*
G02X509920Y1496659I0J-203D01*
G01Y1496037D01*
G03X509970Y1495905I200J0D01*
G02Y1492993I-1664J-1456D01*
G03X509920Y1492861I150J-132D01*
G01Y1490919D01*
G03X509970Y1490787I200J0D01*
G02Y1487875I-1664J-1456D01*
G03X509920Y1487743I150J-132D01*
G01Y1487121D01*
G02X509717Y1486918I-203J0D01*
G01X506897D01*
G02X506694Y1487121I0J203D01*
G01Y1487743D01*
G03X506644Y1487875I-200J0D01*
G02Y1490787I1664J1456D01*
G03X506694Y1490919I-150J132D01*
G01Y1492861D01*
G03X506644Y1492993I-200J0D01*
G02Y1495905I1664J1456D01*
G03X506694Y1496037I-150J132D01*
G01Y1496659D01*
G02X506897Y1496862I203J0D01*
G37*
G36*
G01X645480D02*
X648300D01*
G02X648502Y1496659I-1J-203D01*
G01Y1496039D01*
G03X648552Y1495907I200J0D01*
G02Y1492991I-1661J-1458D01*
G03X648502Y1492859I150J-132D01*
G01Y1490921D01*
G03X648552Y1490789I200J0D01*
G02Y1487873I-1661J-1458D01*
G03X648502Y1487741I150J-132D01*
G01Y1487121D01*
G02X648300Y1486918I-202J-1D01*
G01X645480D01*
G02X645278Y1487121I1J203D01*
G01Y1487741D01*
G03X645228Y1487873I-200J0D01*
G02Y1490789I1661J1458D01*
G03X645278Y1490921I-150J132D01*
G01Y1492859D01*
G03X645228Y1492991I-200J0D01*
G02Y1495907I1661J1458D01*
G03X645278Y1496039I-150J132D01*
G01Y1496659D01*
G02X645480Y1496862I202J1D01*
G37*
G36*
G01X662803D02*
X665623D01*
G02X665826Y1496659I0J-203D01*
G01Y1496037D01*
G03X665876Y1495905I200J0D01*
G02Y1492993I-1664J-1456D01*
G03X665826Y1492861I150J-132D01*
G01Y1490919D01*
G03X665876Y1490787I200J0D01*
G02Y1487875I-1664J-1456D01*
G03X665826Y1487743I150J-132D01*
G01Y1487121D01*
G02X665623Y1486918I-203J0D01*
G01X662803D01*
G02X662600Y1487121I0J203D01*
G01Y1487743D01*
G03X662550Y1487875I-200J0D01*
G02Y1490787I1664J1456D01*
G03X662600Y1490919I-150J132D01*
G01Y1492861D01*
G03X662550Y1492993I-200J0D01*
G02Y1495905I1664J1456D01*
G03X662600Y1496037I-150J132D01*
G01Y1496659D01*
G02X662803Y1496862I203J0D01*
G37*
G36*
G01X680125D02*
X682945D01*
G02X683148Y1496659I0J-203D01*
G01Y1496037D01*
G03X683198Y1495905I200J0D01*
G02Y1492993I-1664J-1456D01*
G03X683148Y1492861I150J-132D01*
G01Y1490919D01*
G03X683198Y1490787I200J0D01*
G02Y1487875I-1664J-1456D01*
G03X683148Y1487743I150J-132D01*
G01Y1487121D01*
G02X682945Y1486918I-203J0D01*
G01X680125D01*
G02X679922Y1487121I0J203D01*
G01Y1487743D01*
G03X679872Y1487875I-200J0D01*
G02Y1490787I1664J1456D01*
G03X679922Y1490919I-150J132D01*
G01Y1492861D01*
G03X679872Y1492993I-200J0D01*
G02Y1495905I1664J1456D01*
G03X679922Y1496037I-150J132D01*
G01Y1496659D01*
G02X680125Y1496862I203J0D01*
G37*
G36*
G01X1165086D02*
X1167906D01*
G02X1168108Y1496659I-1J-203D01*
G01Y1496039D01*
G03X1168158Y1495907I200J0D01*
G02Y1492991I-1661J-1458D01*
G03X1168108Y1492859I150J-132D01*
G01Y1490921D01*
G03X1168158Y1490789I200J0D01*
G02Y1487873I-1661J-1458D01*
G03X1168108Y1487741I150J-132D01*
G01Y1487121D01*
G02X1167906Y1486918I-202J-1D01*
G01X1165086D01*
G02X1164884Y1487121I1J203D01*
G01Y1487741D01*
G03X1164834Y1487873I-200J0D01*
G02Y1490789I1661J1458D01*
G03X1164884Y1490921I-150J132D01*
G01Y1492859D01*
G03X1164834Y1492991I-200J0D01*
G02Y1495907I1661J1458D01*
G03X1164884Y1496039I-150J132D01*
G01Y1496659D01*
G02X1165086Y1496862I202J1D01*
G37*
G36*
G01X1182408D02*
X1185228D01*
G02X1185430Y1496659I-1J-203D01*
G01Y1496039D01*
G03X1185480Y1495907I200J0D01*
G02Y1492991I-1661J-1458D01*
G03X1185430Y1492859I150J-132D01*
G01Y1490921D01*
G03X1185480Y1490789I200J0D01*
G02Y1487873I-1661J-1458D01*
G03X1185430Y1487741I150J-132D01*
G01Y1487121D01*
G02X1185228Y1486918I-202J-1D01*
G01X1182408D01*
G02X1182206Y1487121I1J203D01*
G01Y1487741D01*
G03X1182156Y1487873I-200J0D01*
G02Y1490789I1661J1458D01*
G03X1182206Y1490921I-150J132D01*
G01Y1492859D01*
G03X1182156Y1492991I-200J0D01*
G02Y1495907I1661J1458D01*
G03X1182206Y1496039I-150J132D01*
G01Y1496659D01*
G02X1182408Y1496862I202J1D01*
G37*
G36*
G01X1303669D02*
X1306489D01*
G02X1306692Y1496659I0J-203D01*
G01Y1496037D01*
G03X1306742Y1495905I200J0D01*
G02Y1492993I-1664J-1456D01*
G03X1306692Y1492861I150J-132D01*
G01Y1490919D01*
G03X1306742Y1490787I200J0D01*
G02Y1487875I-1664J-1456D01*
G03X1306692Y1487743I150J-132D01*
G01Y1487121D01*
G02X1306489Y1486918I-203J0D01*
G01X1303669D01*
G02X1303466Y1487121I0J203D01*
G01Y1487743D01*
G03X1303416Y1487875I-200J0D01*
G02Y1490787I1664J1456D01*
G03X1303466Y1490919I-150J132D01*
G01Y1492861D01*
G03X1303416Y1492993I-200J0D01*
G02Y1495905I1664J1456D01*
G03X1303466Y1496037I-150J132D01*
G01Y1496659D01*
G02X1303669Y1496862I203J0D01*
G37*
G36*
G01X1320992D02*
X1323812D01*
G02X1324014Y1496659I-1J-203D01*
G01Y1496039D01*
G03X1324064Y1495907I200J0D01*
G02Y1492991I-1661J-1458D01*
G03X1324014Y1492859I150J-132D01*
G01Y1490921D01*
G03X1324064Y1490789I200J0D01*
G02Y1487873I-1661J-1458D01*
G03X1324014Y1487741I150J-132D01*
G01Y1487121D01*
G02X1323812Y1486918I-202J-1D01*
G01X1320992D01*
G02X1320790Y1487121I1J203D01*
G01Y1487741D01*
G03X1320740Y1487873I-200J0D01*
G02Y1490789I1661J1458D01*
G03X1320790Y1490921I-150J132D01*
G01Y1492859D01*
G03X1320740Y1492991I-200J0D01*
G02Y1495907I1661J1458D01*
G03X1320790Y1496039I-150J132D01*
G01Y1496659D01*
G02X1320992Y1496862I202J1D01*
G37*
G36*
G01X1338315D02*
X1341135D01*
G02X1341338Y1496659I0J-203D01*
G01Y1496037D01*
G03X1341388Y1495905I200J0D01*
G02Y1492993I-1664J-1456D01*
G03X1341338Y1492861I150J-132D01*
G01Y1490919D01*
G03X1341388Y1490787I200J0D01*
G02Y1487875I-1664J-1456D01*
G03X1341338Y1487743I150J-132D01*
G01Y1487121D01*
G02X1341135Y1486918I-203J0D01*
G01X1338315D01*
G02X1338112Y1487121I0J203D01*
G01Y1487743D01*
G03X1338062Y1487875I-200J0D01*
G02Y1490787I1664J1456D01*
G03X1338112Y1490919I-150J132D01*
G01Y1492861D01*
G03X1338062Y1492993I-200J0D01*
G02Y1495905I1664J1456D01*
G03X1338112Y1496037I-150J132D01*
G01Y1496659D01*
G02X1338315Y1496862I203J0D01*
G37*
G36*
G01X1355637D02*
X1358457D01*
G02X1358660Y1496659I0J-203D01*
G01Y1496037D01*
G03X1358710Y1495905I200J0D01*
G02Y1492993I-1664J-1456D01*
G03X1358660Y1492861I150J-132D01*
G01Y1490919D01*
G03X1358710Y1490787I200J0D01*
G02Y1487875I-1664J-1456D01*
G03X1358660Y1487743I150J-132D01*
G01Y1487121D01*
G02X1358457Y1486918I-203J0D01*
G01X1355637D01*
G02X1355434Y1487121I0J203D01*
G01Y1487743D01*
G03X1355384Y1487875I-200J0D01*
G02Y1490787I1664J1456D01*
G03X1355434Y1490919I-150J132D01*
G01Y1492861D01*
G03X1355384Y1492993I-200J0D01*
G02Y1495905I1664J1456D01*
G03X1355434Y1496037I-150J132D01*
G01Y1496659D01*
G02X1355637Y1496862I203J0D01*
G37*
G36*
G01X1476897D02*
X1479717D01*
G02X1479920Y1496659I0J-203D01*
G01Y1496037D01*
G03X1479970Y1495905I200J0D01*
G02Y1492993I-1664J-1456D01*
G03X1479920Y1492861I150J-132D01*
G01Y1490919D01*
G03X1479970Y1490787I200J0D01*
G02Y1487875I-1664J-1456D01*
G03X1479920Y1487743I150J-132D01*
G01Y1487121D01*
G02X1479717Y1486918I-203J0D01*
G01X1476897D01*
G02X1476694Y1487121I0J203D01*
G01Y1487743D01*
G03X1476644Y1487875I-200J0D01*
G02Y1490787I1664J1456D01*
G03X1476694Y1490919I-150J132D01*
G01Y1492861D01*
G03X1476644Y1492993I-200J0D01*
G02Y1495905I1664J1456D01*
G03X1476694Y1496037I-150J132D01*
G01Y1496659D01*
G02X1476897Y1496862I203J0D01*
G37*
G36*
G01X1494220D02*
X1497040D01*
G02X1497242Y1496659I-1J-203D01*
G01Y1496039D01*
G03X1497292Y1495907I200J0D01*
G02Y1492991I-1661J-1458D01*
G03X1497242Y1492859I150J-132D01*
G01Y1490921D01*
G03X1497292Y1490789I200J0D01*
G02Y1487873I-1661J-1458D01*
G03X1497242Y1487741I150J-132D01*
G01Y1487121D01*
G02X1497040Y1486918I-202J-1D01*
G01X1494220D01*
G02X1494018Y1487121I1J203D01*
G01Y1487741D01*
G03X1493968Y1487873I-200J0D01*
G02Y1490789I1661J1458D01*
G03X1494018Y1490921I-150J132D01*
G01Y1492859D01*
G03X1493968Y1492991I-200J0D01*
G02Y1495907I1661J1458D01*
G03X1494018Y1496039I-150J132D01*
G01Y1496659D01*
G02X1494220Y1496862I202J1D01*
G37*
G36*
G01X1511543D02*
X1514363D01*
G02X1514566Y1496659I0J-203D01*
G01Y1496037D01*
G03X1514616Y1495905I200J0D01*
G02Y1492993I-1664J-1456D01*
G03X1514566Y1492861I150J-132D01*
G01Y1490919D01*
G03X1514616Y1490787I200J0D01*
G02Y1487875I-1664J-1456D01*
G03X1514566Y1487743I150J-132D01*
G01Y1487121D01*
G02X1514363Y1486918I-203J0D01*
G01X1511543D01*
G02X1511340Y1487121I0J203D01*
G01Y1487743D01*
G03X1511290Y1487875I-200J0D01*
G02Y1490787I1664J1456D01*
G03X1511340Y1490919I-150J132D01*
G01Y1492861D01*
G03X1511290Y1492993I-200J0D01*
G02Y1495905I1664J1456D01*
G03X1511340Y1496037I-150J132D01*
G01Y1496659D01*
G02X1511543Y1496862I203J0D01*
G37*
G36*
G01X1528865D02*
X1531685D01*
G02X1531888Y1496659I0J-203D01*
G01Y1496037D01*
G03X1531938Y1495905I200J0D01*
G02Y1492993I-1664J-1456D01*
G03X1531888Y1492861I150J-132D01*
G01Y1490919D01*
G03X1531938Y1490787I200J0D01*
G02Y1487875I-1664J-1456D01*
G03X1531888Y1487743I150J-132D01*
G01Y1487121D01*
G02X1531685Y1486918I-203J0D01*
G01X1528865D01*
G02X1528662Y1487121I0J203D01*
G01Y1487743D01*
G03X1528612Y1487875I-200J0D01*
G02Y1490787I1664J1456D01*
G03X1528662Y1490919I-150J132D01*
G01Y1492861D01*
G03X1528612Y1492993I-200J0D01*
G02Y1495905I1664J1456D01*
G03X1528662Y1496037I-150J132D01*
G01Y1496659D01*
G02X1528865Y1496862I203J0D01*
G37*
G36*
G01X1684771D02*
X1687591D01*
G02X1687794Y1496659I0J-203D01*
G01Y1496037D01*
G03X1687844Y1495905I200J0D01*
G02Y1492993I-1664J-1456D01*
G03X1687794Y1492861I150J-132D01*
G01Y1490919D01*
G03X1687844Y1490787I200J0D01*
G02Y1487875I-1664J-1456D01*
G03X1687794Y1487743I150J-132D01*
G01Y1487121D01*
G02X1687591Y1486918I-203J0D01*
G01X1684771D01*
G02X1684568Y1487121I0J203D01*
G01Y1487743D01*
G03X1684518Y1487875I-200J0D01*
G02Y1490787I1664J1456D01*
G03X1684568Y1490919I-150J132D01*
G01Y1492861D01*
G03X1684518Y1492993I-200J0D01*
G02Y1495905I1664J1456D01*
G03X1684568Y1496037I-150J132D01*
G01Y1496659D01*
G02X1684771Y1496862I203J0D01*
G37*
G36*
G01X1702093D02*
X1704913D01*
G02X1705116Y1496659I0J-203D01*
G01Y1496037D01*
G03X1705166Y1495905I200J0D01*
G02Y1492993I-1664J-1456D01*
G03X1705116Y1492861I150J-132D01*
G01Y1490919D01*
G03X1705166Y1490787I200J0D01*
G02Y1487875I-1664J-1456D01*
G03X1705116Y1487743I150J-132D01*
G01Y1487121D01*
G02X1704913Y1486918I-203J0D01*
G01X1702093D01*
G02X1701890Y1487121I0J203D01*
G01Y1487743D01*
G03X1701840Y1487875I-200J0D01*
G02Y1490787I1664J1456D01*
G03X1701890Y1490919I-150J132D01*
G01Y1492861D01*
G03X1701840Y1492993I-200J0D01*
G02Y1495905I1664J1456D01*
G03X1701890Y1496037I-150J132D01*
G01Y1496659D01*
G02X1702093Y1496862I203J0D01*
G37*
G36*
G01X134456Y1501192D02*
X137276D01*
G02X137478Y1500989I-1J-203D01*
G01Y1500370D01*
G03X137528Y1500238I200J0D01*
G02Y1497322I-1661J-1458D01*
G03X137478Y1497190I150J-132D01*
G01Y1495252D01*
G03X137528Y1495120I200J0D01*
G02Y1492204I-1661J-1458D01*
G03X137478Y1492072I150J-132D01*
G01Y1491451D01*
G02X137276Y1491248I-202J-1D01*
G01X134456D01*
G02X134254Y1491451I1J203D01*
G01Y1492072D01*
G03X134204Y1492204I-200J0D01*
G02Y1495120I1661J1458D01*
G03X134254Y1495252I-150J132D01*
G01Y1497190D01*
G03X134204Y1497322I-200J0D01*
G02Y1500238I1661J1458D01*
G03X134254Y1500370I-150J132D01*
G01Y1500989D01*
G02X134456Y1501192I202J1D01*
G37*
G36*
G01X151779D02*
X154599D01*
G02X154802Y1500989I0J-203D01*
G01Y1500368D01*
G03X154852Y1500236I200J0D01*
G02Y1497324I-1664J-1456D01*
G03X154802Y1497192I150J-132D01*
G01Y1495250D01*
G03X154852Y1495118I200J0D01*
G02Y1492206I-1664J-1456D01*
G03X154802Y1492074I150J-132D01*
G01Y1491451D01*
G02X154599Y1491248I-203J0D01*
G01X151779D01*
G02X151576Y1491451I0J203D01*
G01Y1492074D01*
G03X151526Y1492206I-200J0D01*
G02Y1495118I1664J1456D01*
G03X151576Y1495250I-150J132D01*
G01Y1497192D01*
G03X151526Y1497324I-200J0D01*
G02Y1500236I1664J1456D01*
G03X151576Y1500368I-150J132D01*
G01Y1500989D01*
G02X151779Y1501192I203J0D01*
G37*
G36*
G01X169102D02*
X171922D01*
G02X172124Y1500989I-1J-203D01*
G01Y1500370D01*
G03X172174Y1500238I200J0D01*
G02Y1497322I-1661J-1458D01*
G03X172124Y1497190I150J-132D01*
G01Y1495252D01*
G03X172174Y1495120I200J0D01*
G02Y1492204I-1661J-1458D01*
G03X172124Y1492072I150J-132D01*
G01Y1491451D01*
G02X171922Y1491248I-202J-1D01*
G01X169102D01*
G02X168900Y1491451I1J203D01*
G01Y1492072D01*
G03X168850Y1492204I-200J0D01*
G02Y1495120I1661J1458D01*
G03X168900Y1495252I-150J132D01*
G01Y1497190D01*
G03X168850Y1497322I-200J0D01*
G02Y1500238I1661J1458D01*
G03X168900Y1500370I-150J132D01*
G01Y1500989D01*
G02X169102Y1501192I202J1D01*
G37*
G36*
G01X290361D02*
X293181D01*
G02X293384Y1500989I0J-203D01*
G01Y1500368D01*
G03X293434Y1500236I200J0D01*
G02Y1497324I-1664J-1456D01*
G03X293384Y1497192I150J-132D01*
G01Y1495250D01*
G03X293434Y1495118I200J0D01*
G02Y1492206I-1664J-1456D01*
G03X293384Y1492074I150J-132D01*
G01Y1491451D01*
G02X293181Y1491248I-203J0D01*
G01X290361D01*
G02X290158Y1491451I0J203D01*
G01Y1492074D01*
G03X290108Y1492206I-200J0D01*
G02Y1495118I1664J1456D01*
G03X290158Y1495250I-150J132D01*
G01Y1497192D01*
G03X290108Y1497324I-200J0D01*
G02Y1500236I1664J1456D01*
G03X290158Y1500368I-150J132D01*
G01Y1500989D01*
G02X290361Y1501192I203J0D01*
G37*
G36*
G01X463590D02*
X466410D01*
G02X466612Y1500989I-1J-203D01*
G01Y1500370D01*
G03X466662Y1500238I200J0D01*
G02Y1497322I-1661J-1458D01*
G03X466612Y1497190I150J-132D01*
G01Y1495252D01*
G03X466662Y1495120I200J0D01*
G02Y1492204I-1661J-1458D01*
G03X466612Y1492072I150J-132D01*
G01Y1491451D01*
G02X466410Y1491248I-202J-1D01*
G01X463590D01*
G02X463388Y1491451I1J203D01*
G01Y1492072D01*
G03X463338Y1492204I-200J0D01*
G02Y1495120I1661J1458D01*
G03X463388Y1495252I-150J132D01*
G01Y1497190D01*
G03X463338Y1497322I-200J0D01*
G02Y1500238I1661J1458D01*
G03X463388Y1500370I-150J132D01*
G01Y1500989D01*
G02X463590Y1501192I202J1D01*
G37*
G36*
G01X480913D02*
X483733D01*
G02X483936Y1500989I0J-203D01*
G01Y1500368D01*
G03X483986Y1500236I200J0D01*
G02Y1497324I-1664J-1456D01*
G03X483936Y1497192I150J-132D01*
G01Y1495250D01*
G03X483986Y1495118I200J0D01*
G02Y1492206I-1664J-1456D01*
G03X483936Y1492074I150J-132D01*
G01Y1491451D01*
G02X483733Y1491248I-203J0D01*
G01X480913D01*
G02X480710Y1491451I0J203D01*
G01Y1492074D01*
G03X480660Y1492206I-200J0D01*
G02Y1495118I1664J1456D01*
G03X480710Y1495250I-150J132D01*
G01Y1497192D01*
G03X480660Y1497324I-200J0D01*
G02Y1500236I1664J1456D01*
G03X480710Y1500368I-150J132D01*
G01Y1500989D01*
G02X480913Y1501192I203J0D01*
G37*
G36*
G01X498236D02*
X501056D01*
G02X501258Y1500989I-1J-203D01*
G01Y1500370D01*
G03X501308Y1500238I200J0D01*
G02Y1497322I-1661J-1458D01*
G03X501258Y1497190I150J-132D01*
G01Y1495252D01*
G03X501308Y1495120I200J0D01*
G02Y1492204I-1661J-1458D01*
G03X501258Y1492072I150J-132D01*
G01Y1491451D01*
G02X501056Y1491248I-202J-1D01*
G01X498236D01*
G02X498034Y1491451I1J203D01*
G01Y1492072D01*
G03X497984Y1492204I-200J0D01*
G02Y1495120I1661J1458D01*
G03X498034Y1495252I-150J132D01*
G01Y1497190D01*
G03X497984Y1497322I-200J0D01*
G02Y1500238I1661J1458D01*
G03X498034Y1500370I-150J132D01*
G01Y1500989D01*
G02X498236Y1501192I202J1D01*
G37*
G36*
G01X515559D02*
X518379D01*
G02X518582Y1500989I0J-203D01*
G01Y1500368D01*
G03X518632Y1500236I200J0D01*
G02Y1497324I-1664J-1456D01*
G03X518582Y1497192I150J-132D01*
G01Y1495250D01*
G03X518632Y1495118I200J0D01*
G02Y1492206I-1664J-1456D01*
G03X518582Y1492074I150J-132D01*
G01Y1491451D01*
G02X518379Y1491248I-203J0D01*
G01X515559D01*
G02X515356Y1491451I0J203D01*
G01Y1492074D01*
G03X515306Y1492206I-200J0D01*
G02Y1495118I1664J1456D01*
G03X515356Y1495250I-150J132D01*
G01Y1497192D01*
G03X515306Y1497324I-200J0D01*
G02Y1500236I1664J1456D01*
G03X515356Y1500368I-150J132D01*
G01Y1500989D01*
G02X515559Y1501192I203J0D01*
G37*
G36*
G01X654141D02*
X656961D01*
G02X657164Y1500989I0J-203D01*
G01Y1500368D01*
G03X657214Y1500236I200J0D01*
G02Y1497324I-1664J-1456D01*
G03X657164Y1497192I150J-132D01*
G01Y1495250D01*
G03X657214Y1495118I200J0D01*
G02Y1492206I-1664J-1456D01*
G03X657164Y1492074I150J-132D01*
G01Y1491451D01*
G02X656961Y1491248I-203J0D01*
G01X654141D01*
G02X653938Y1491451I0J203D01*
G01Y1492074D01*
G03X653888Y1492206I-200J0D01*
G02Y1495118I1664J1456D01*
G03X653938Y1495250I-150J132D01*
G01Y1497192D01*
G03X653888Y1497324I-200J0D01*
G02Y1500236I1664J1456D01*
G03X653938Y1500368I-150J132D01*
G01Y1500989D01*
G02X654141Y1501192I203J0D01*
G37*
G36*
G01X671464D02*
X674284D01*
G02X674486Y1500989I-1J-203D01*
G01Y1500370D01*
G03X674536Y1500238I200J0D01*
G02Y1497322I-1661J-1458D01*
G03X674486Y1497190I150J-132D01*
G01Y1495252D01*
G03X674536Y1495120I200J0D01*
G02Y1492204I-1661J-1458D01*
G03X674486Y1492072I150J-132D01*
G01Y1491451D01*
G02X674284Y1491248I-202J-1D01*
G01X671464D01*
G02X671262Y1491451I1J203D01*
G01Y1492072D01*
G03X671212Y1492204I-200J0D01*
G02Y1495120I1661J1458D01*
G03X671262Y1495252I-150J132D01*
G01Y1497190D01*
G03X671212Y1497322I-200J0D01*
G02Y1500238I1661J1458D01*
G03X671262Y1500370I-150J132D01*
G01Y1500989D01*
G02X671464Y1501192I202J1D01*
G37*
G36*
G01X688787D02*
X691607D01*
G02X691810Y1500989I0J-203D01*
G01Y1500368D01*
G03X691860Y1500236I200J0D01*
G02Y1497324I-1664J-1456D01*
G03X691810Y1497192I150J-132D01*
G01Y1495250D01*
G03X691860Y1495118I200J0D01*
G02Y1492206I-1664J-1456D01*
G03X691810Y1492074I150J-132D01*
G01Y1491451D01*
G02X691607Y1491248I-203J0D01*
G01X688787D01*
G02X688584Y1491451I0J203D01*
G01Y1492074D01*
G03X688534Y1492206I-200J0D01*
G02Y1495118I1664J1456D01*
G03X688584Y1495250I-150J132D01*
G01Y1497192D01*
G03X688534Y1497324I-200J0D01*
G02Y1500236I1664J1456D01*
G03X688584Y1500368I-150J132D01*
G01Y1500989D01*
G02X688787Y1501192I203J0D01*
G37*
G36*
G01X1173747D02*
X1176567D01*
G02X1176770Y1500989I0J-203D01*
G01Y1500368D01*
G03X1176820Y1500236I200J0D01*
G02Y1497324I-1664J-1456D01*
G03X1176770Y1497192I150J-132D01*
G01Y1495250D01*
G03X1176820Y1495118I200J0D01*
G02Y1492206I-1664J-1456D01*
G03X1176770Y1492074I150J-132D01*
G01Y1491451D01*
G02X1176567Y1491248I-203J0D01*
G01X1173747D01*
G02X1173544Y1491451I0J203D01*
G01Y1492074D01*
G03X1173494Y1492206I-200J0D01*
G02Y1495118I1664J1456D01*
G03X1173544Y1495250I-150J132D01*
G01Y1497192D01*
G03X1173494Y1497324I-200J0D01*
G02Y1500236I1664J1456D01*
G03X1173544Y1500368I-150J132D01*
G01Y1500989D01*
G02X1173747Y1501192I203J0D01*
G37*
G36*
G01X1191070D02*
X1193890D01*
G02X1194092Y1500989I-1J-203D01*
G01Y1500370D01*
G03X1194142Y1500238I200J0D01*
G02Y1497322I-1661J-1458D01*
G03X1194092Y1497190I150J-132D01*
G01Y1495252D01*
G03X1194142Y1495120I200J0D01*
G02Y1492204I-1661J-1458D01*
G03X1194092Y1492072I150J-132D01*
G01Y1491451D01*
G02X1193890Y1491248I-202J-1D01*
G01X1191070D01*
G02X1190868Y1491451I1J203D01*
G01Y1492072D01*
G03X1190818Y1492204I-200J0D01*
G02Y1495120I1661J1458D01*
G03X1190868Y1495252I-150J132D01*
G01Y1497190D01*
G03X1190818Y1497322I-200J0D01*
G02Y1500238I1661J1458D01*
G03X1190868Y1500370I-150J132D01*
G01Y1500989D01*
G02X1191070Y1501192I202J1D01*
G37*
G36*
G01X1312330D02*
X1315150D01*
G02X1315352Y1500989I-1J-203D01*
G01Y1500370D01*
G03X1315402Y1500238I200J0D01*
G02Y1497322I-1661J-1458D01*
G03X1315352Y1497190I150J-132D01*
G01Y1495252D01*
G03X1315402Y1495120I200J0D01*
G02Y1492204I-1661J-1458D01*
G03X1315352Y1492072I150J-132D01*
G01Y1491451D01*
G02X1315150Y1491248I-202J-1D01*
G01X1312330D01*
G02X1312128Y1491451I1J203D01*
G01Y1492072D01*
G03X1312078Y1492204I-200J0D01*
G02Y1495120I1661J1458D01*
G03X1312128Y1495252I-150J132D01*
G01Y1497190D01*
G03X1312078Y1497322I-200J0D01*
G02Y1500238I1661J1458D01*
G03X1312128Y1500370I-150J132D01*
G01Y1500989D01*
G02X1312330Y1501192I202J1D01*
G37*
G36*
G01X1329653D02*
X1332473D01*
G02X1332676Y1500989I0J-203D01*
G01Y1500368D01*
G03X1332726Y1500236I200J0D01*
G02Y1497324I-1664J-1456D01*
G03X1332676Y1497192I150J-132D01*
G01Y1495250D01*
G03X1332726Y1495118I200J0D01*
G02Y1492206I-1664J-1456D01*
G03X1332676Y1492074I150J-132D01*
G01Y1491451D01*
G02X1332473Y1491248I-203J0D01*
G01X1329653D01*
G02X1329450Y1491451I0J203D01*
G01Y1492074D01*
G03X1329400Y1492206I-200J0D01*
G02Y1495118I1664J1456D01*
G03X1329450Y1495250I-150J132D01*
G01Y1497192D01*
G03X1329400Y1497324I-200J0D01*
G02Y1500236I1664J1456D01*
G03X1329450Y1500368I-150J132D01*
G01Y1500989D01*
G02X1329653Y1501192I203J0D01*
G37*
G36*
G01X1346976D02*
X1349796D01*
G02X1349998Y1500989I-1J-203D01*
G01Y1500370D01*
G03X1350048Y1500238I200J0D01*
G02Y1497322I-1661J-1458D01*
G03X1349998Y1497190I150J-132D01*
G01Y1495252D01*
G03X1350048Y1495120I200J0D01*
G02Y1492204I-1661J-1458D01*
G03X1349998Y1492072I150J-132D01*
G01Y1491451D01*
G02X1349796Y1491248I-202J-1D01*
G01X1346976D01*
G02X1346774Y1491451I1J203D01*
G01Y1492072D01*
G03X1346724Y1492204I-200J0D01*
G02Y1495120I1661J1458D01*
G03X1346774Y1495252I-150J132D01*
G01Y1497190D01*
G03X1346724Y1497322I-200J0D01*
G02Y1500238I1661J1458D01*
G03X1346774Y1500370I-150J132D01*
G01Y1500989D01*
G02X1346976Y1501192I202J1D01*
G37*
G36*
G01X1364299D02*
X1367119D01*
G02X1367322Y1500989I0J-203D01*
G01Y1500368D01*
G03X1367372Y1500236I200J0D01*
G02Y1497324I-1664J-1456D01*
G03X1367322Y1497192I150J-132D01*
G01Y1495250D01*
G03X1367372Y1495118I200J0D01*
G02Y1492206I-1664J-1456D01*
G03X1367322Y1492074I150J-132D01*
G01Y1491451D01*
G02X1367119Y1491248I-203J0D01*
G01X1364299D01*
G02X1364096Y1491451I0J203D01*
G01Y1492074D01*
G03X1364046Y1492206I-200J0D01*
G02Y1495118I1664J1456D01*
G03X1364096Y1495250I-150J132D01*
G01Y1497192D01*
G03X1364046Y1497324I-200J0D01*
G02Y1500236I1664J1456D01*
G03X1364096Y1500368I-150J132D01*
G01Y1500989D01*
G02X1364299Y1501192I203J0D01*
G37*
G36*
G01X1485558D02*
X1488378D01*
G02X1488580Y1500989I-1J-203D01*
G01Y1500370D01*
G03X1488630Y1500238I200J0D01*
G02Y1497322I-1661J-1458D01*
G03X1488580Y1497190I150J-132D01*
G01Y1495252D01*
G03X1488630Y1495120I200J0D01*
G02Y1492204I-1661J-1458D01*
G03X1488580Y1492072I150J-132D01*
G01Y1491451D01*
G02X1488378Y1491248I-202J-1D01*
G01X1485558D01*
G02X1485356Y1491451I1J203D01*
G01Y1492072D01*
G03X1485306Y1492204I-200J0D01*
G02Y1495120I1661J1458D01*
G03X1485356Y1495252I-150J132D01*
G01Y1497190D01*
G03X1485306Y1497322I-200J0D01*
G02Y1500238I1661J1458D01*
G03X1485356Y1500370I-150J132D01*
G01Y1500989D01*
G02X1485558Y1501192I202J1D01*
G37*
G36*
G01X1502881D02*
X1505701D01*
G02X1505904Y1500989I0J-203D01*
G01Y1500368D01*
G03X1505954Y1500236I200J0D01*
G02Y1497324I-1664J-1456D01*
G03X1505904Y1497192I150J-132D01*
G01Y1495250D01*
G03X1505954Y1495118I200J0D01*
G02Y1492206I-1664J-1456D01*
G03X1505904Y1492074I150J-132D01*
G01Y1491451D01*
G02X1505701Y1491248I-203J0D01*
G01X1502881D01*
G02X1502678Y1491451I0J203D01*
G01Y1492074D01*
G03X1502628Y1492206I-200J0D01*
G02Y1495118I1664J1456D01*
G03X1502678Y1495250I-150J132D01*
G01Y1497192D01*
G03X1502628Y1497324I-200J0D01*
G02Y1500236I1664J1456D01*
G03X1502678Y1500368I-150J132D01*
G01Y1500989D01*
G02X1502881Y1501192I203J0D01*
G37*
G36*
G01X1520204D02*
X1523024D01*
G02X1523226Y1500989I-1J-203D01*
G01Y1500370D01*
G03X1523276Y1500238I200J0D01*
G02Y1497322I-1661J-1458D01*
G03X1523226Y1497190I150J-132D01*
G01Y1495252D01*
G03X1523276Y1495120I200J0D01*
G02Y1492204I-1661J-1458D01*
G03X1523226Y1492072I150J-132D01*
G01Y1491451D01*
G02X1523024Y1491248I-202J-1D01*
G01X1520204D01*
G02X1520002Y1491451I1J203D01*
G01Y1492072D01*
G03X1519952Y1492204I-200J0D01*
G02Y1495120I1661J1458D01*
G03X1520002Y1495252I-150J132D01*
G01Y1497190D01*
G03X1519952Y1497322I-200J0D01*
G02Y1500238I1661J1458D01*
G03X1520002Y1500370I-150J132D01*
G01Y1500989D01*
G02X1520204Y1501192I202J1D01*
G37*
G36*
G01X1537527D02*
X1540347D01*
G02X1540550Y1500989I0J-203D01*
G01Y1500368D01*
G03X1540600Y1500236I200J0D01*
G02Y1497324I-1664J-1456D01*
G03X1540550Y1497192I150J-132D01*
G01Y1495250D01*
G03X1540600Y1495118I200J0D01*
G02Y1492206I-1664J-1456D01*
G03X1540550Y1492074I150J-132D01*
G01Y1491451D01*
G02X1540347Y1491248I-203J0D01*
G01X1537527D01*
G02X1537324Y1491451I0J203D01*
G01Y1492074D01*
G03X1537274Y1492206I-200J0D01*
G02Y1495118I1664J1456D01*
G03X1537324Y1495250I-150J132D01*
G01Y1497192D01*
G03X1537274Y1497324I-200J0D01*
G02Y1500236I1664J1456D01*
G03X1537324Y1500368I-150J132D01*
G01Y1500989D01*
G02X1537527Y1501192I203J0D01*
G37*
G36*
G01X1693432D02*
X1696252D01*
G02X1696454Y1500989I-1J-203D01*
G01Y1500370D01*
G03X1696504Y1500238I200J0D01*
G02Y1497322I-1661J-1458D01*
G03X1696454Y1497190I150J-132D01*
G01Y1495252D01*
G03X1696504Y1495120I200J0D01*
G02Y1492204I-1661J-1458D01*
G03X1696454Y1492072I150J-132D01*
G01Y1491451D01*
G02X1696252Y1491248I-202J-1D01*
G01X1693432D01*
G02X1693230Y1491451I1J203D01*
G01Y1492072D01*
G03X1693180Y1492204I-200J0D01*
G02Y1495120I1661J1458D01*
G03X1693230Y1495252I-150J132D01*
G01Y1497190D01*
G03X1693180Y1497322I-200J0D01*
G02Y1500238I1661J1458D01*
G03X1693230Y1500370I-150J132D01*
G01Y1500989D01*
G02X1693432Y1501192I202J1D01*
G37*
G36*
G01X1710755D02*
X1713575D01*
G02X1713778Y1500989I0J-203D01*
G01Y1500368D01*
G03X1713828Y1500236I200J0D01*
G02Y1497324I-1664J-1456D01*
G03X1713778Y1497192I150J-132D01*
G01Y1495250D01*
G03X1713828Y1495118I200J0D01*
G02Y1492206I-1664J-1456D01*
G03X1713778Y1492074I150J-132D01*
G01Y1491451D01*
G02X1713575Y1491248I-203J0D01*
G01X1710755D01*
G02X1710552Y1491451I0J203D01*
G01Y1492074D01*
G03X1710502Y1492206I-200J0D01*
G02Y1495118I1664J1456D01*
G03X1710552Y1495250I-150J132D01*
G01Y1497192D01*
G03X1710502Y1497324I-200J0D01*
G02Y1500236I1664J1456D01*
G03X1710552Y1500368I-150J132D01*
G01Y1500989D01*
G02X1710755Y1501192I203J0D01*
G37*
G36*
G01X143118Y1512216D02*
X145938D01*
G02X146140Y1512014I0J-202D01*
G01Y1511394D01*
G03X146190Y1511262I200J0D01*
G02Y1508346I-1661J-1458D01*
G03X146140Y1508214I150J-132D01*
G01Y1506275D01*
G03X146190Y1506143I200J0D01*
G02Y1503227I-1661J-1458D01*
G03X146140Y1503095I150J-132D01*
G01Y1502476D01*
G02X145938Y1502274I-202J0D01*
G01X143118D01*
G02X142916Y1502476I0J202D01*
G01Y1503095D01*
G03X142866Y1503227I-200J0D01*
G02Y1506143I1661J1458D01*
G03X142916Y1506275I-150J132D01*
G01Y1508214D01*
G03X142866Y1508346I-200J0D01*
G02Y1511262I1661J1458D01*
G03X142916Y1511394I-150J132D01*
G01Y1512014D01*
G02X143118Y1512216I202J0D01*
G37*
G36*
G01X160440D02*
X163260D01*
G02X163462Y1512014I0J-202D01*
G01Y1511394D01*
G03X163512Y1511262I200J0D01*
G02Y1508346I-1661J-1458D01*
G03X163462Y1508214I150J-132D01*
G01Y1506275D01*
G03X163512Y1506143I200J0D01*
G02Y1503227I-1661J-1458D01*
G03X163462Y1503095I150J-132D01*
G01Y1502476D01*
G02X163260Y1502274I-202J0D01*
G01X160440D01*
G02X160238Y1502476I0J202D01*
G01Y1503095D01*
G03X160188Y1503227I-200J0D01*
G02Y1506143I1661J1458D01*
G03X160238Y1506275I-150J132D01*
G01Y1508214D01*
G03X160188Y1508346I-200J0D01*
G02Y1511262I1661J1458D01*
G03X160238Y1511394I-150J132D01*
G01Y1512014D01*
G02X160440Y1512216I202J0D01*
G37*
G36*
G01X281700D02*
X284520D01*
G02X284722Y1512014I0J-202D01*
G01Y1511394D01*
G03X284772Y1511262I200J0D01*
G02Y1508346I-1661J-1458D01*
G03X284722Y1508214I150J-132D01*
G01Y1506275D01*
G03X284772Y1506143I200J0D01*
G02Y1503227I-1661J-1458D01*
G03X284722Y1503095I150J-132D01*
G01Y1502476D01*
G02X284520Y1502274I-202J0D01*
G01X281700D01*
G02X281498Y1502476I0J202D01*
G01Y1503095D01*
G03X281448Y1503227I-200J0D01*
G02Y1506143I1661J1458D01*
G03X281498Y1506275I-150J132D01*
G01Y1508214D01*
G03X281448Y1508346I-200J0D01*
G02Y1511262I1661J1458D01*
G03X281498Y1511394I-150J132D01*
G01Y1512014D01*
G02X281700Y1512216I202J0D01*
G37*
G36*
G01X472252D02*
X475072D01*
G02X475274Y1512014I0J-202D01*
G01Y1511394D01*
G03X475324Y1511262I200J0D01*
G02Y1508346I-1661J-1458D01*
G03X475274Y1508214I150J-132D01*
G01Y1506275D01*
G03X475324Y1506143I200J0D01*
G02Y1503227I-1661J-1458D01*
G03X475274Y1503095I150J-132D01*
G01Y1502476D01*
G02X475072Y1502274I-202J0D01*
G01X472252D01*
G02X472050Y1502476I0J202D01*
G01Y1503095D01*
G03X472000Y1503227I-200J0D01*
G02Y1506143I1661J1458D01*
G03X472050Y1506275I-150J132D01*
G01Y1508214D01*
G03X472000Y1508346I-200J0D01*
G02Y1511262I1661J1458D01*
G03X472050Y1511394I-150J132D01*
G01Y1512014D01*
G02X472252Y1512216I202J0D01*
G37*
G36*
G01X645480D02*
X648300D01*
G02X648502Y1512014I0J-202D01*
G01Y1511394D01*
G03X648552Y1511262I200J0D01*
G02Y1508346I-1661J-1458D01*
G03X648502Y1508214I150J-132D01*
G01Y1506275D01*
G03X648552Y1506143I200J0D01*
G02Y1503227I-1661J-1458D01*
G03X648502Y1503095I150J-132D01*
G01Y1502476D01*
G02X648300Y1502274I-202J0D01*
G01X645480D01*
G02X645278Y1502476I0J202D01*
G01Y1503095D01*
G03X645228Y1503227I-200J0D01*
G02Y1506143I1661J1458D01*
G03X645278Y1506275I-150J132D01*
G01Y1508214D01*
G03X645228Y1508346I-200J0D01*
G02Y1511262I1661J1458D01*
G03X645278Y1511394I-150J132D01*
G01Y1512014D01*
G02X645480Y1512216I202J0D01*
G37*
G36*
G01X1165086D02*
X1167906D01*
G02X1168108Y1512014I0J-202D01*
G01Y1511394D01*
G03X1168158Y1511262I200J0D01*
G02Y1508346I-1661J-1458D01*
G03X1168108Y1508214I150J-132D01*
G01Y1506275D01*
G03X1168158Y1506143I200J0D01*
G02Y1503227I-1661J-1458D01*
G03X1168108Y1503095I150J-132D01*
G01Y1502476D01*
G02X1167906Y1502274I-202J0D01*
G01X1165086D01*
G02X1164884Y1502476I0J202D01*
G01Y1503095D01*
G03X1164834Y1503227I-200J0D01*
G02Y1506143I1661J1458D01*
G03X1164884Y1506275I-150J132D01*
G01Y1508214D01*
G03X1164834Y1508346I-200J0D01*
G02Y1511262I1661J1458D01*
G03X1164884Y1511394I-150J132D01*
G01Y1512014D01*
G02X1165086Y1512216I202J0D01*
G37*
G36*
G01X1182408D02*
X1185228D01*
G02X1185430Y1512014I0J-202D01*
G01Y1511394D01*
G03X1185480Y1511262I200J0D01*
G02Y1508346I-1661J-1458D01*
G03X1185430Y1508214I150J-132D01*
G01Y1506275D01*
G03X1185480Y1506143I200J0D01*
G02Y1503227I-1661J-1458D01*
G03X1185430Y1503095I150J-132D01*
G01Y1502476D01*
G02X1185228Y1502274I-202J0D01*
G01X1182408D01*
G02X1182206Y1502476I0J202D01*
G01Y1503095D01*
G03X1182156Y1503227I-200J0D01*
G02Y1506143I1661J1458D01*
G03X1182206Y1506275I-150J132D01*
G01Y1508214D01*
G03X1182156Y1508346I-200J0D01*
G02Y1511262I1661J1458D01*
G03X1182206Y1511394I-150J132D01*
G01Y1512014D01*
G02X1182408Y1512216I202J0D01*
G37*
G36*
G01X1320992D02*
X1323812D01*
G02X1324014Y1512014I0J-202D01*
G01Y1511394D01*
G03X1324064Y1511262I200J0D01*
G02Y1508346I-1661J-1458D01*
G03X1324014Y1508214I150J-132D01*
G01Y1506275D01*
G03X1324064Y1506143I200J0D01*
G02Y1503227I-1661J-1458D01*
G03X1324014Y1503095I150J-132D01*
G01Y1502476D01*
G02X1323812Y1502274I-202J0D01*
G01X1320992D01*
G02X1320790Y1502476I0J202D01*
G01Y1503095D01*
G03X1320740Y1503227I-200J0D01*
G02Y1506143I1661J1458D01*
G03X1320790Y1506275I-150J132D01*
G01Y1508214D01*
G03X1320740Y1508346I-200J0D01*
G02Y1511262I1661J1458D01*
G03X1320790Y1511394I-150J132D01*
G01Y1512014D01*
G02X1320992Y1512216I202J0D01*
G37*
G36*
G01X1494220D02*
X1497040D01*
G02X1497242Y1512014I0J-202D01*
G01Y1511394D01*
G03X1497292Y1511262I200J0D01*
G02Y1508346I-1661J-1458D01*
G03X1497242Y1508214I150J-132D01*
G01Y1506275D01*
G03X1497292Y1506143I200J0D01*
G02Y1503227I-1661J-1458D01*
G03X1497242Y1503095I150J-132D01*
G01Y1502476D01*
G02X1497040Y1502274I-202J0D01*
G01X1494220D01*
G02X1494018Y1502476I0J202D01*
G01Y1503095D01*
G03X1493968Y1503227I-200J0D01*
G02Y1506143I1661J1458D01*
G03X1494018Y1506275I-150J132D01*
G01Y1508214D01*
G03X1493968Y1508346I-200J0D01*
G02Y1511262I1661J1458D01*
G03X1494018Y1511394I-150J132D01*
G01Y1512014D01*
G02X1494220Y1512216I202J0D01*
G37*
G36*
G01X125795D02*
X128615D01*
G02X128818Y1512014I1J-202D01*
G01Y1511392D01*
G03X128868Y1511260I200J0D01*
G02Y1508348I-1664J-1456D01*
G03X128818Y1508216I150J-132D01*
G01Y1506273D01*
G03X128868Y1506141I200J0D01*
G02Y1503229I-1664J-1456D01*
G03X128818Y1503097I150J-132D01*
G01Y1502476D01*
G02X128615Y1502274I-203J1D01*
G01X125795D01*
G02X125592Y1502476I-1J202D01*
G01Y1503097D01*
G03X125542Y1503229I-200J0D01*
G02Y1506141I1664J1456D01*
G03X125592Y1506273I-150J132D01*
G01Y1508216D01*
G03X125542Y1508348I-200J0D01*
G02Y1511260I1664J1456D01*
G03X125592Y1511392I-150J132D01*
G01Y1512014D01*
G02X125795Y1512216I203J-1D01*
G37*
G36*
G01X299023D02*
X301843D01*
G02X302046Y1512014I1J-202D01*
G01Y1511392D01*
G03X302096Y1511260I200J0D01*
G02Y1508348I-1664J-1456D01*
G03X302046Y1508216I150J-132D01*
G01Y1506273D01*
G03X302096Y1506141I200J0D01*
G02Y1503229I-1664J-1456D01*
G03X302046Y1503097I150J-132D01*
G01Y1502476D01*
G02X301843Y1502274I-203J1D01*
G01X299023D01*
G02X298820Y1502476I-1J202D01*
G01Y1503097D01*
G03X298770Y1503229I-200J0D01*
G02Y1506141I1664J1456D01*
G03X298820Y1506273I-150J132D01*
G01Y1508216D01*
G03X298770Y1508348I-200J0D01*
G02Y1511260I1664J1456D01*
G03X298820Y1511392I-150J132D01*
G01Y1512014D01*
G02X299023Y1512216I203J-1D01*
G37*
G36*
G01X454929D02*
X457749D01*
G02X457952Y1512014I1J-202D01*
G01Y1511392D01*
G03X458002Y1511260I200J0D01*
G02Y1508348I-1664J-1456D01*
G03X457952Y1508216I150J-132D01*
G01Y1506273D01*
G03X458002Y1506141I200J0D01*
G02Y1503229I-1664J-1456D01*
G03X457952Y1503097I150J-132D01*
G01Y1502476D01*
G02X457749Y1502274I-203J1D01*
G01X454929D01*
G02X454726Y1502476I-1J202D01*
G01Y1503097D01*
G03X454676Y1503229I-200J0D01*
G02Y1506141I1664J1456D01*
G03X454726Y1506273I-150J132D01*
G01Y1508216D01*
G03X454676Y1508348I-200J0D01*
G02Y1511260I1664J1456D01*
G03X454726Y1511392I-150J132D01*
G01Y1512014D01*
G02X454929Y1512216I203J-1D01*
G37*
G36*
G01X489575D02*
X492395D01*
G02X492598Y1512014I1J-202D01*
G01Y1511392D01*
G03X492648Y1511260I200J0D01*
G02Y1508348I-1664J-1456D01*
G03X492598Y1508216I150J-132D01*
G01Y1506273D01*
G03X492648Y1506141I200J0D01*
G02Y1503229I-1664J-1456D01*
G03X492598Y1503097I150J-132D01*
G01Y1502476D01*
G02X492395Y1502274I-203J1D01*
G01X489575D01*
G02X489372Y1502476I-1J202D01*
G01Y1503097D01*
G03X489322Y1503229I-200J0D01*
G02Y1506141I1664J1456D01*
G03X489372Y1506273I-150J132D01*
G01Y1508216D01*
G03X489322Y1508348I-200J0D01*
G02Y1511260I1664J1456D01*
G03X489372Y1511392I-150J132D01*
G01Y1512014D01*
G02X489575Y1512216I203J-1D01*
G37*
G36*
G01X506897D02*
X509717D01*
G02X509920Y1512014I1J-202D01*
G01Y1511392D01*
G03X509970Y1511260I200J0D01*
G02Y1508348I-1664J-1456D01*
G03X509920Y1508216I150J-132D01*
G01Y1506273D01*
G03X509970Y1506141I200J0D01*
G02Y1503229I-1664J-1456D01*
G03X509920Y1503097I150J-132D01*
G01Y1502476D01*
G02X509717Y1502274I-203J1D01*
G01X506897D01*
G02X506694Y1502476I-1J202D01*
G01Y1503097D01*
G03X506644Y1503229I-200J0D01*
G02Y1506141I1664J1456D01*
G03X506694Y1506273I-150J132D01*
G01Y1508216D01*
G03X506644Y1508348I-200J0D01*
G02Y1511260I1664J1456D01*
G03X506694Y1511392I-150J132D01*
G01Y1512014D01*
G02X506897Y1512216I203J-1D01*
G37*
G36*
G01X662803D02*
X665623D01*
G02X665826Y1512014I1J-202D01*
G01Y1511392D01*
G03X665876Y1511260I200J0D01*
G02Y1508348I-1664J-1456D01*
G03X665826Y1508216I150J-132D01*
G01Y1506273D01*
G03X665876Y1506141I200J0D01*
G02Y1503229I-1664J-1456D01*
G03X665826Y1503097I150J-132D01*
G01Y1502476D01*
G02X665623Y1502274I-203J1D01*
G01X662803D01*
G02X662600Y1502476I-1J202D01*
G01Y1503097D01*
G03X662550Y1503229I-200J0D01*
G02Y1506141I1664J1456D01*
G03X662600Y1506273I-150J132D01*
G01Y1508216D01*
G03X662550Y1508348I-200J0D01*
G02Y1511260I1664J1456D01*
G03X662600Y1511392I-150J132D01*
G01Y1512014D01*
G02X662803Y1512216I203J-1D01*
G37*
G36*
G01X680125D02*
X682945D01*
G02X683148Y1512014I1J-202D01*
G01Y1511392D01*
G03X683198Y1511260I200J0D01*
G02Y1508348I-1664J-1456D01*
G03X683148Y1508216I150J-132D01*
G01Y1506273D01*
G03X683198Y1506141I200J0D01*
G02Y1503229I-1664J-1456D01*
G03X683148Y1503097I150J-132D01*
G01Y1502476D01*
G02X682945Y1502274I-203J1D01*
G01X680125D01*
G02X679922Y1502476I-1J202D01*
G01Y1503097D01*
G03X679872Y1503229I-200J0D01*
G02Y1506141I1664J1456D01*
G03X679922Y1506273I-150J132D01*
G01Y1508216D01*
G03X679872Y1508348I-200J0D01*
G02Y1511260I1664J1456D01*
G03X679922Y1511392I-150J132D01*
G01Y1512014D01*
G02X680125Y1512216I203J-1D01*
G37*
G36*
G01X1303669D02*
X1306489D01*
G02X1306692Y1512014I1J-202D01*
G01Y1511392D01*
G03X1306742Y1511260I200J0D01*
G02Y1508348I-1664J-1456D01*
G03X1306692Y1508216I150J-132D01*
G01Y1506273D01*
G03X1306742Y1506141I200J0D01*
G02Y1503229I-1664J-1456D01*
G03X1306692Y1503097I150J-132D01*
G01Y1502476D01*
G02X1306489Y1502274I-203J1D01*
G01X1303669D01*
G02X1303466Y1502476I-1J202D01*
G01Y1503097D01*
G03X1303416Y1503229I-200J0D01*
G02Y1506141I1664J1456D01*
G03X1303466Y1506273I-150J132D01*
G01Y1508216D01*
G03X1303416Y1508348I-200J0D01*
G02Y1511260I1664J1456D01*
G03X1303466Y1511392I-150J132D01*
G01Y1512014D01*
G02X1303669Y1512216I203J-1D01*
G37*
G36*
G01X1338315D02*
X1341135D01*
G02X1341338Y1512014I1J-202D01*
G01Y1511392D01*
G03X1341388Y1511260I200J0D01*
G02Y1508348I-1664J-1456D01*
G03X1341338Y1508216I150J-132D01*
G01Y1506273D01*
G03X1341388Y1506141I200J0D01*
G02Y1503229I-1664J-1456D01*
G03X1341338Y1503097I150J-132D01*
G01Y1502476D01*
G02X1341135Y1502274I-203J1D01*
G01X1338315D01*
G02X1338112Y1502476I-1J202D01*
G01Y1503097D01*
G03X1338062Y1503229I-200J0D01*
G02Y1506141I1664J1456D01*
G03X1338112Y1506273I-150J132D01*
G01Y1508216D01*
G03X1338062Y1508348I-200J0D01*
G02Y1511260I1664J1456D01*
G03X1338112Y1511392I-150J132D01*
G01Y1512014D01*
G02X1338315Y1512216I203J-1D01*
G37*
G36*
G01X1355637D02*
X1358457D01*
G02X1358660Y1512014I1J-202D01*
G01Y1511392D01*
G03X1358710Y1511260I200J0D01*
G02Y1508348I-1664J-1456D01*
G03X1358660Y1508216I150J-132D01*
G01Y1506273D01*
G03X1358710Y1506141I200J0D01*
G02Y1503229I-1664J-1456D01*
G03X1358660Y1503097I150J-132D01*
G01Y1502476D01*
G02X1358457Y1502274I-203J1D01*
G01X1355637D01*
G02X1355434Y1502476I-1J202D01*
G01Y1503097D01*
G03X1355384Y1503229I-200J0D01*
G02Y1506141I1664J1456D01*
G03X1355434Y1506273I-150J132D01*
G01Y1508216D01*
G03X1355384Y1508348I-200J0D01*
G02Y1511260I1664J1456D01*
G03X1355434Y1511392I-150J132D01*
G01Y1512014D01*
G02X1355637Y1512216I203J-1D01*
G37*
G36*
G01X1476897D02*
X1479717D01*
G02X1479920Y1512014I1J-202D01*
G01Y1511392D01*
G03X1479970Y1511260I200J0D01*
G02Y1508348I-1664J-1456D01*
G03X1479920Y1508216I150J-132D01*
G01Y1506273D01*
G03X1479970Y1506141I200J0D01*
G02Y1503229I-1664J-1456D01*
G03X1479920Y1503097I150J-132D01*
G01Y1502476D01*
G02X1479717Y1502274I-203J1D01*
G01X1476897D01*
G02X1476694Y1502476I-1J202D01*
G01Y1503097D01*
G03X1476644Y1503229I-200J0D01*
G02Y1506141I1664J1456D01*
G03X1476694Y1506273I-150J132D01*
G01Y1508216D01*
G03X1476644Y1508348I-200J0D01*
G02Y1511260I1664J1456D01*
G03X1476694Y1511392I-150J132D01*
G01Y1512014D01*
G02X1476897Y1512216I203J-1D01*
G37*
G36*
G01X1511543D02*
X1514363D01*
G02X1514566Y1512014I1J-202D01*
G01Y1511392D01*
G03X1514616Y1511260I200J0D01*
G02Y1508348I-1664J-1456D01*
G03X1514566Y1508216I150J-132D01*
G01Y1506273D01*
G03X1514616Y1506141I200J0D01*
G02Y1503229I-1664J-1456D01*
G03X1514566Y1503097I150J-132D01*
G01Y1502476D01*
G02X1514363Y1502274I-203J1D01*
G01X1511543D01*
G02X1511340Y1502476I-1J202D01*
G01Y1503097D01*
G03X1511290Y1503229I-200J0D01*
G02Y1506141I1664J1456D01*
G03X1511340Y1506273I-150J132D01*
G01Y1508216D01*
G03X1511290Y1508348I-200J0D01*
G02Y1511260I1664J1456D01*
G03X1511340Y1511392I-150J132D01*
G01Y1512014D01*
G02X1511543Y1512216I203J-1D01*
G37*
G36*
G01X1528865D02*
X1531685D01*
G02X1531888Y1512014I1J-202D01*
G01Y1511392D01*
G03X1531938Y1511260I200J0D01*
G02Y1508348I-1664J-1456D01*
G03X1531888Y1508216I150J-132D01*
G01Y1506273D01*
G03X1531938Y1506141I200J0D01*
G02Y1503229I-1664J-1456D01*
G03X1531888Y1503097I150J-132D01*
G01Y1502476D01*
G02X1531685Y1502274I-203J1D01*
G01X1528865D01*
G02X1528662Y1502476I-1J202D01*
G01Y1503097D01*
G03X1528612Y1503229I-200J0D01*
G02Y1506141I1664J1456D01*
G03X1528662Y1506273I-150J132D01*
G01Y1508216D01*
G03X1528612Y1508348I-200J0D01*
G02Y1511260I1664J1456D01*
G03X1528662Y1511392I-150J132D01*
G01Y1512014D01*
G02X1528865Y1512216I203J-1D01*
G37*
G36*
G01X1684771D02*
X1687591D01*
G02X1687794Y1512014I1J-202D01*
G01Y1511392D01*
G03X1687844Y1511260I200J0D01*
G02Y1508348I-1664J-1456D01*
G03X1687794Y1508216I150J-132D01*
G01Y1506273D01*
G03X1687844Y1506141I200J0D01*
G02Y1503229I-1664J-1456D01*
G03X1687794Y1503097I150J-132D01*
G01Y1502476D01*
G02X1687591Y1502274I-203J1D01*
G01X1684771D01*
G02X1684568Y1502476I-1J202D01*
G01Y1503097D01*
G03X1684518Y1503229I-200J0D01*
G02Y1506141I1664J1456D01*
G03X1684568Y1506273I-150J132D01*
G01Y1508216D01*
G03X1684518Y1508348I-200J0D01*
G02Y1511260I1664J1456D01*
G03X1684568Y1511392I-150J132D01*
G01Y1512014D01*
G02X1684771Y1512216I203J-1D01*
G37*
G36*
G01X1702093D02*
X1704913D01*
G02X1705116Y1512014I1J-202D01*
G01Y1511392D01*
G03X1705166Y1511260I200J0D01*
G02Y1508348I-1664J-1456D01*
G03X1705116Y1508216I150J-132D01*
G01Y1506273D01*
G03X1705166Y1506141I200J0D01*
G02Y1503229I-1664J-1456D01*
G03X1705116Y1503097I150J-132D01*
G01Y1502476D01*
G02X1704913Y1502274I-203J1D01*
G01X1702093D01*
G02X1701890Y1502476I-1J202D01*
G01Y1503097D01*
G03X1701840Y1503229I-200J0D01*
G02Y1506141I1664J1456D01*
G03X1701890Y1506273I-150J132D01*
G01Y1508216D01*
G03X1701840Y1508348I-200J0D01*
G02Y1511260I1664J1456D01*
G03X1701890Y1511392I-150J132D01*
G01Y1512014D01*
G02X1702093Y1512216I203J-1D01*
G37*
G36*
G01X134456Y1516546D02*
X137276D01*
G02X137478Y1516344I0J-202D01*
G01Y1515724D01*
G03X137528Y1515592I200J0D01*
G02Y1512676I-1661J-1458D01*
G03X137478Y1512544I150J-132D01*
G01Y1510606D01*
G03X137528Y1510474I200J0D01*
G02Y1507558I-1661J-1458D01*
G03X137478Y1507426I150J-132D01*
G01Y1506806D01*
G02X137276Y1506604I-202J0D01*
G01X134456D01*
G02X134254Y1506806I0J202D01*
G01Y1507426D01*
G03X134204Y1507558I-200J0D01*
G02Y1510474I1661J1458D01*
G03X134254Y1510606I-150J132D01*
G01Y1512544D01*
G03X134204Y1512676I-200J0D01*
G02Y1515592I1661J1458D01*
G03X134254Y1515724I-150J132D01*
G01Y1516344D01*
G02X134456Y1516546I202J0D01*
G37*
G36*
G01X169102D02*
X171922D01*
G02X172124Y1516344I0J-202D01*
G01Y1515724D01*
G03X172174Y1515592I200J0D01*
G02Y1512676I-1661J-1458D01*
G03X172124Y1512544I150J-132D01*
G01Y1510606D01*
G03X172174Y1510474I200J0D01*
G02Y1507558I-1661J-1458D01*
G03X172124Y1507426I150J-132D01*
G01Y1506806D01*
G02X171922Y1506604I-202J0D01*
G01X169102D01*
G02X168900Y1506806I0J202D01*
G01Y1507426D01*
G03X168850Y1507558I-200J0D01*
G02Y1510474I1661J1458D01*
G03X168900Y1510606I-150J132D01*
G01Y1512544D01*
G03X168850Y1512676I-200J0D01*
G02Y1515592I1661J1458D01*
G03X168900Y1515724I-150J132D01*
G01Y1516344D01*
G02X169102Y1516546I202J0D01*
G37*
G36*
G01X463590D02*
X466410D01*
G02X466612Y1516344I0J-202D01*
G01Y1515724D01*
G03X466662Y1515592I200J0D01*
G02Y1512676I-1661J-1458D01*
G03X466612Y1512544I150J-132D01*
G01Y1510606D01*
G03X466662Y1510474I200J0D01*
G02Y1507558I-1661J-1458D01*
G03X466612Y1507426I150J-132D01*
G01Y1506806D01*
G02X466410Y1506604I-202J0D01*
G01X463590D01*
G02X463388Y1506806I0J202D01*
G01Y1507426D01*
G03X463338Y1507558I-200J0D01*
G02Y1510474I1661J1458D01*
G03X463388Y1510606I-150J132D01*
G01Y1512544D01*
G03X463338Y1512676I-200J0D01*
G02Y1515592I1661J1458D01*
G03X463388Y1515724I-150J132D01*
G01Y1516344D01*
G02X463590Y1516546I202J0D01*
G37*
G36*
G01X498236D02*
X501056D01*
G02X501258Y1516344I0J-202D01*
G01Y1515724D01*
G03X501308Y1515592I200J0D01*
G02Y1512676I-1661J-1458D01*
G03X501258Y1512544I150J-132D01*
G01Y1510606D01*
G03X501308Y1510474I200J0D01*
G02Y1507558I-1661J-1458D01*
G03X501258Y1507426I150J-132D01*
G01Y1506806D01*
G02X501056Y1506604I-202J0D01*
G01X498236D01*
G02X498034Y1506806I0J202D01*
G01Y1507426D01*
G03X497984Y1507558I-200J0D01*
G02Y1510474I1661J1458D01*
G03X498034Y1510606I-150J132D01*
G01Y1512544D01*
G03X497984Y1512676I-200J0D01*
G02Y1515592I1661J1458D01*
G03X498034Y1515724I-150J132D01*
G01Y1516344D01*
G02X498236Y1516546I202J0D01*
G37*
G36*
G01X671464D02*
X674284D01*
G02X674486Y1516344I0J-202D01*
G01Y1515724D01*
G03X674536Y1515592I200J0D01*
G02Y1512676I-1661J-1458D01*
G03X674486Y1512544I150J-132D01*
G01Y1510606D01*
G03X674536Y1510474I200J0D01*
G02Y1507558I-1661J-1458D01*
G03X674486Y1507426I150J-132D01*
G01Y1506806D01*
G02X674284Y1506604I-202J0D01*
G01X671464D01*
G02X671262Y1506806I0J202D01*
G01Y1507426D01*
G03X671212Y1507558I-200J0D01*
G02Y1510474I1661J1458D01*
G03X671262Y1510606I-150J132D01*
G01Y1512544D01*
G03X671212Y1512676I-200J0D01*
G02Y1515592I1661J1458D01*
G03X671262Y1515724I-150J132D01*
G01Y1516344D01*
G02X671464Y1516546I202J0D01*
G37*
G36*
G01X1191070D02*
X1193890D01*
G02X1194092Y1516344I0J-202D01*
G01Y1515724D01*
G03X1194142Y1515592I200J0D01*
G02Y1512676I-1661J-1458D01*
G03X1194092Y1512544I150J-132D01*
G01Y1510606D01*
G03X1194142Y1510474I200J0D01*
G02Y1507558I-1661J-1458D01*
G03X1194092Y1507426I150J-132D01*
G01Y1506806D01*
G02X1193890Y1506604I-202J0D01*
G01X1191070D01*
G02X1190868Y1506806I0J202D01*
G01Y1507426D01*
G03X1190818Y1507558I-200J0D01*
G02Y1510474I1661J1458D01*
G03X1190868Y1510606I-150J132D01*
G01Y1512544D01*
G03X1190818Y1512676I-200J0D01*
G02Y1515592I1661J1458D01*
G03X1190868Y1515724I-150J132D01*
G01Y1516344D01*
G02X1191070Y1516546I202J0D01*
G37*
G36*
G01X1312330D02*
X1315150D01*
G02X1315352Y1516344I0J-202D01*
G01Y1515724D01*
G03X1315402Y1515592I200J0D01*
G02Y1512676I-1661J-1458D01*
G03X1315352Y1512544I150J-132D01*
G01Y1510606D01*
G03X1315402Y1510474I200J0D01*
G02Y1507558I-1661J-1458D01*
G03X1315352Y1507426I150J-132D01*
G01Y1506806D01*
G02X1315150Y1506604I-202J0D01*
G01X1312330D01*
G02X1312128Y1506806I0J202D01*
G01Y1507426D01*
G03X1312078Y1507558I-200J0D01*
G02Y1510474I1661J1458D01*
G03X1312128Y1510606I-150J132D01*
G01Y1512544D01*
G03X1312078Y1512676I-200J0D01*
G02Y1515592I1661J1458D01*
G03X1312128Y1515724I-150J132D01*
G01Y1516344D01*
G02X1312330Y1516546I202J0D01*
G37*
G36*
G01X1346976D02*
X1349796D01*
G02X1349998Y1516344I0J-202D01*
G01Y1515724D01*
G03X1350048Y1515592I200J0D01*
G02Y1512676I-1661J-1458D01*
G03X1349998Y1512544I150J-132D01*
G01Y1510606D01*
G03X1350048Y1510474I200J0D01*
G02Y1507558I-1661J-1458D01*
G03X1349998Y1507426I150J-132D01*
G01Y1506806D01*
G02X1349796Y1506604I-202J0D01*
G01X1346976D01*
G02X1346774Y1506806I0J202D01*
G01Y1507426D01*
G03X1346724Y1507558I-200J0D01*
G02Y1510474I1661J1458D01*
G03X1346774Y1510606I-150J132D01*
G01Y1512544D01*
G03X1346724Y1512676I-200J0D01*
G02Y1515592I1661J1458D01*
G03X1346774Y1515724I-150J132D01*
G01Y1516344D01*
G02X1346976Y1516546I202J0D01*
G37*
G36*
G01X1485558D02*
X1488378D01*
G02X1488580Y1516344I0J-202D01*
G01Y1515724D01*
G03X1488630Y1515592I200J0D01*
G02Y1512676I-1661J-1458D01*
G03X1488580Y1512544I150J-132D01*
G01Y1510606D01*
G03X1488630Y1510474I200J0D01*
G02Y1507558I-1661J-1458D01*
G03X1488580Y1507426I150J-132D01*
G01Y1506806D01*
G02X1488378Y1506604I-202J0D01*
G01X1485558D01*
G02X1485356Y1506806I0J202D01*
G01Y1507426D01*
G03X1485306Y1507558I-200J0D01*
G02Y1510474I1661J1458D01*
G03X1485356Y1510606I-150J132D01*
G01Y1512544D01*
G03X1485306Y1512676I-200J0D01*
G02Y1515592I1661J1458D01*
G03X1485356Y1515724I-150J132D01*
G01Y1516344D01*
G02X1485558Y1516546I202J0D01*
G37*
G36*
G01X1520204D02*
X1523024D01*
G02X1523226Y1516344I0J-202D01*
G01Y1515724D01*
G03X1523276Y1515592I200J0D01*
G02Y1512676I-1661J-1458D01*
G03X1523226Y1512544I150J-132D01*
G01Y1510606D01*
G03X1523276Y1510474I200J0D01*
G02Y1507558I-1661J-1458D01*
G03X1523226Y1507426I150J-132D01*
G01Y1506806D01*
G02X1523024Y1506604I-202J0D01*
G01X1520204D01*
G02X1520002Y1506806I0J202D01*
G01Y1507426D01*
G03X1519952Y1507558I-200J0D01*
G02Y1510474I1661J1458D01*
G03X1520002Y1510606I-150J132D01*
G01Y1512544D01*
G03X1519952Y1512676I-200J0D01*
G02Y1515592I1661J1458D01*
G03X1520002Y1515724I-150J132D01*
G01Y1516344D01*
G02X1520204Y1516546I202J0D01*
G37*
G36*
G01X1693432D02*
X1696252D01*
G02X1696454Y1516344I0J-202D01*
G01Y1515724D01*
G03X1696504Y1515592I200J0D01*
G02Y1512676I-1661J-1458D01*
G03X1696454Y1512544I150J-132D01*
G01Y1510606D01*
G03X1696504Y1510474I200J0D01*
G02Y1507558I-1661J-1458D01*
G03X1696454Y1507426I150J-132D01*
G01Y1506806D01*
G02X1696252Y1506604I-202J0D01*
G01X1693432D01*
G02X1693230Y1506806I0J202D01*
G01Y1507426D01*
G03X1693180Y1507558I-200J0D01*
G02Y1510474I1661J1458D01*
G03X1693230Y1510606I-150J132D01*
G01Y1512544D01*
G03X1693180Y1512676I-200J0D01*
G02Y1515592I1661J1458D01*
G03X1693230Y1515724I-150J132D01*
G01Y1516344D01*
G02X1693432Y1516546I202J0D01*
G37*
G36*
G01X151779D02*
X154599D01*
G02X154802Y1516344I1J-202D01*
G01Y1515722D01*
G03X154852Y1515590I200J0D01*
G02Y1512678I-1664J-1456D01*
G03X154802Y1512546I150J-132D01*
G01Y1510604D01*
G03X154852Y1510472I200J0D01*
G02Y1507560I-1664J-1456D01*
G03X154802Y1507428I150J-132D01*
G01Y1506806D01*
G02X154599Y1506604I-203J1D01*
G01X151779D01*
G02X151576Y1506806I-1J202D01*
G01Y1507428D01*
G03X151526Y1507560I-200J0D01*
G02Y1510472I1664J1456D01*
G03X151576Y1510604I-150J132D01*
G01Y1512546D01*
G03X151526Y1512678I-200J0D01*
G02Y1515590I1664J1456D01*
G03X151576Y1515722I-150J132D01*
G01Y1516344D01*
G02X151779Y1516546I203J-1D01*
G37*
G36*
G01X290361D02*
X293181D01*
G02X293384Y1516344I1J-202D01*
G01Y1515722D01*
G03X293434Y1515590I200J0D01*
G02Y1512678I-1664J-1456D01*
G03X293384Y1512546I150J-132D01*
G01Y1510604D01*
G03X293434Y1510472I200J0D01*
G02Y1507560I-1664J-1456D01*
G03X293384Y1507428I150J-132D01*
G01Y1506806D01*
G02X293181Y1506604I-203J1D01*
G01X290361D01*
G02X290158Y1506806I-1J202D01*
G01Y1507428D01*
G03X290108Y1507560I-200J0D01*
G02Y1510472I1664J1456D01*
G03X290158Y1510604I-150J132D01*
G01Y1512546D01*
G03X290108Y1512678I-200J0D01*
G02Y1515590I1664J1456D01*
G03X290158Y1515722I-150J132D01*
G01Y1516344D01*
G02X290361Y1516546I203J-1D01*
G37*
G36*
G01X480913D02*
X483733D01*
G02X483936Y1516344I1J-202D01*
G01Y1515722D01*
G03X483986Y1515590I200J0D01*
G02Y1512678I-1664J-1456D01*
G03X483936Y1512546I150J-132D01*
G01Y1510604D01*
G03X483986Y1510472I200J0D01*
G02Y1507560I-1664J-1456D01*
G03X483936Y1507428I150J-132D01*
G01Y1506806D01*
G02X483733Y1506604I-203J1D01*
G01X480913D01*
G02X480710Y1506806I-1J202D01*
G01Y1507428D01*
G03X480660Y1507560I-200J0D01*
G02Y1510472I1664J1456D01*
G03X480710Y1510604I-150J132D01*
G01Y1512546D01*
G03X480660Y1512678I-200J0D01*
G02Y1515590I1664J1456D01*
G03X480710Y1515722I-150J132D01*
G01Y1516344D01*
G02X480913Y1516546I203J-1D01*
G37*
G36*
G01X515559D02*
X518379D01*
G02X518582Y1516344I1J-202D01*
G01Y1515722D01*
G03X518632Y1515590I200J0D01*
G02Y1512678I-1664J-1456D01*
G03X518582Y1512546I150J-132D01*
G01Y1510604D01*
G03X518632Y1510472I200J0D01*
G02Y1507560I-1664J-1456D01*
G03X518582Y1507428I150J-132D01*
G01Y1506806D01*
G02X518379Y1506604I-203J1D01*
G01X515559D01*
G02X515356Y1506806I-1J202D01*
G01Y1507428D01*
G03X515306Y1507560I-200J0D01*
G02Y1510472I1664J1456D01*
G03X515356Y1510604I-150J132D01*
G01Y1512546D01*
G03X515306Y1512678I-200J0D01*
G02Y1515590I1664J1456D01*
G03X515356Y1515722I-150J132D01*
G01Y1516344D01*
G02X515559Y1516546I203J-1D01*
G37*
G36*
G01X654141D02*
X656961D01*
G02X657164Y1516344I1J-202D01*
G01Y1515722D01*
G03X657214Y1515590I200J0D01*
G02Y1512678I-1664J-1456D01*
G03X657164Y1512546I150J-132D01*
G01Y1510604D01*
G03X657214Y1510472I200J0D01*
G02Y1507560I-1664J-1456D01*
G03X657164Y1507428I150J-132D01*
G01Y1506806D01*
G02X656961Y1506604I-203J1D01*
G01X654141D01*
G02X653938Y1506806I-1J202D01*
G01Y1507428D01*
G03X653888Y1507560I-200J0D01*
G02Y1510472I1664J1456D01*
G03X653938Y1510604I-150J132D01*
G01Y1512546D01*
G03X653888Y1512678I-200J0D01*
G02Y1515590I1664J1456D01*
G03X653938Y1515722I-150J132D01*
G01Y1516344D01*
G02X654141Y1516546I203J-1D01*
G37*
G36*
G01X688787D02*
X691607D01*
G02X691810Y1516344I1J-202D01*
G01Y1515722D01*
G03X691860Y1515590I200J0D01*
G02Y1512678I-1664J-1456D01*
G03X691810Y1512546I150J-132D01*
G01Y1510604D01*
G03X691860Y1510472I200J0D01*
G02Y1507560I-1664J-1456D01*
G03X691810Y1507428I150J-132D01*
G01Y1506806D01*
G02X691607Y1506604I-203J1D01*
G01X688787D01*
G02X688584Y1506806I-1J202D01*
G01Y1507428D01*
G03X688534Y1507560I-200J0D01*
G02Y1510472I1664J1456D01*
G03X688584Y1510604I-150J132D01*
G01Y1512546D01*
G03X688534Y1512678I-200J0D01*
G02Y1515590I1664J1456D01*
G03X688584Y1515722I-150J132D01*
G01Y1516344D01*
G02X688787Y1516546I203J-1D01*
G37*
G36*
G01X1173747D02*
X1176567D01*
G02X1176770Y1516344I1J-202D01*
G01Y1515722D01*
G03X1176820Y1515590I200J0D01*
G02Y1512678I-1664J-1456D01*
G03X1176770Y1512546I150J-132D01*
G01Y1510604D01*
G03X1176820Y1510472I200J0D01*
G02Y1507560I-1664J-1456D01*
G03X1176770Y1507428I150J-132D01*
G01Y1506806D01*
G02X1176567Y1506604I-203J1D01*
G01X1173747D01*
G02X1173544Y1506806I-1J202D01*
G01Y1507428D01*
G03X1173494Y1507560I-200J0D01*
G02Y1510472I1664J1456D01*
G03X1173544Y1510604I-150J132D01*
G01Y1512546D01*
G03X1173494Y1512678I-200J0D01*
G02Y1515590I1664J1456D01*
G03X1173544Y1515722I-150J132D01*
G01Y1516344D01*
G02X1173747Y1516546I203J-1D01*
G37*
G36*
G01X1329653D02*
X1332473D01*
G02X1332676Y1516344I1J-202D01*
G01Y1515722D01*
G03X1332726Y1515590I200J0D01*
G02Y1512678I-1664J-1456D01*
G03X1332676Y1512546I150J-132D01*
G01Y1510604D01*
G03X1332726Y1510472I200J0D01*
G02Y1507560I-1664J-1456D01*
G03X1332676Y1507428I150J-132D01*
G01Y1506806D01*
G02X1332473Y1506604I-203J1D01*
G01X1329653D01*
G02X1329450Y1506806I-1J202D01*
G01Y1507428D01*
G03X1329400Y1507560I-200J0D01*
G02Y1510472I1664J1456D01*
G03X1329450Y1510604I-150J132D01*
G01Y1512546D01*
G03X1329400Y1512678I-200J0D01*
G02Y1515590I1664J1456D01*
G03X1329450Y1515722I-150J132D01*
G01Y1516344D01*
G02X1329653Y1516546I203J-1D01*
G37*
G36*
G01X1364299D02*
X1367119D01*
G02X1367322Y1516344I1J-202D01*
G01Y1515722D01*
G03X1367372Y1515590I200J0D01*
G02Y1512678I-1664J-1456D01*
G03X1367322Y1512546I150J-132D01*
G01Y1510604D01*
G03X1367372Y1510472I200J0D01*
G02Y1507560I-1664J-1456D01*
G03X1367322Y1507428I150J-132D01*
G01Y1506806D01*
G02X1367119Y1506604I-203J1D01*
G01X1364299D01*
G02X1364096Y1506806I-1J202D01*
G01Y1507428D01*
G03X1364046Y1507560I-200J0D01*
G02Y1510472I1664J1456D01*
G03X1364096Y1510604I-150J132D01*
G01Y1512546D01*
G03X1364046Y1512678I-200J0D01*
G02Y1515590I1664J1456D01*
G03X1364096Y1515722I-150J132D01*
G01Y1516344D01*
G02X1364299Y1516546I203J-1D01*
G37*
G36*
G01X1502881D02*
X1505701D01*
G02X1505904Y1516344I1J-202D01*
G01Y1515722D01*
G03X1505954Y1515590I200J0D01*
G02Y1512678I-1664J-1456D01*
G03X1505904Y1512546I150J-132D01*
G01Y1510604D01*
G03X1505954Y1510472I200J0D01*
G02Y1507560I-1664J-1456D01*
G03X1505904Y1507428I150J-132D01*
G01Y1506806D01*
G02X1505701Y1506604I-203J1D01*
G01X1502881D01*
G02X1502678Y1506806I-1J202D01*
G01Y1507428D01*
G03X1502628Y1507560I-200J0D01*
G02Y1510472I1664J1456D01*
G03X1502678Y1510604I-150J132D01*
G01Y1512546D01*
G03X1502628Y1512678I-200J0D01*
G02Y1515590I1664J1456D01*
G03X1502678Y1515722I-150J132D01*
G01Y1516344D01*
G02X1502881Y1516546I203J-1D01*
G37*
G36*
G01X1537527D02*
X1540347D01*
G02X1540550Y1516344I1J-202D01*
G01Y1515722D01*
G03X1540600Y1515590I200J0D01*
G02Y1512678I-1664J-1456D01*
G03X1540550Y1512546I150J-132D01*
G01Y1510604D01*
G03X1540600Y1510472I200J0D01*
G02Y1507560I-1664J-1456D01*
G03X1540550Y1507428I150J-132D01*
G01Y1506806D01*
G02X1540347Y1506604I-203J1D01*
G01X1537527D01*
G02X1537324Y1506806I-1J202D01*
G01Y1507428D01*
G03X1537274Y1507560I-200J0D01*
G02Y1510472I1664J1456D01*
G03X1537324Y1510604I-150J132D01*
G01Y1512546D01*
G03X1537274Y1512678I-200J0D01*
G02Y1515590I1664J1456D01*
G03X1537324Y1515722I-150J132D01*
G01Y1516344D01*
G02X1537527Y1516546I203J-1D01*
G37*
G36*
G01X1710755D02*
X1713575D01*
G02X1713778Y1516344I1J-202D01*
G01Y1515722D01*
G03X1713828Y1515590I200J0D01*
G02Y1512678I-1664J-1456D01*
G03X1713778Y1512546I150J-132D01*
G01Y1510604D01*
G03X1713828Y1510472I200J0D01*
G02Y1507560I-1664J-1456D01*
G03X1713778Y1507428I150J-132D01*
G01Y1506806D01*
G02X1713575Y1506604I-203J1D01*
G01X1710755D01*
G02X1710552Y1506806I-1J202D01*
G01Y1507428D01*
G03X1710502Y1507560I-200J0D01*
G02Y1510472I1664J1456D01*
G03X1710552Y1510604I-150J132D01*
G01Y1512546D01*
G03X1710502Y1512678I-200J0D01*
G02Y1515590I1664J1456D01*
G03X1710552Y1515722I-150J132D01*
G01Y1516344D01*
G02X1710755Y1516546I203J-1D01*
G37*
G36*
G01X108472Y1568516D02*
X111292D01*
G02X111494Y1568313I-1J-203D01*
G01Y1567693D01*
G03X111544Y1567561I200J0D01*
G02Y1564645I-1661J-1458D01*
G03X111494Y1564513I150J-132D01*
G01Y1562575D01*
G03X111544Y1562443I200J0D01*
G02Y1559527I-1661J-1458D01*
G03X111494Y1559395I150J-132D01*
G01Y1558775D01*
G02X111292Y1558572I-202J-1D01*
G01X108472D01*
G02X108270Y1558775I1J203D01*
G01Y1559395D01*
G03X108220Y1559527I-200J0D01*
G02Y1562443I1661J1458D01*
G03X108270Y1562575I-150J132D01*
G01Y1564513D01*
G03X108220Y1564645I-200J0D01*
G02Y1567561I1661J1458D01*
G03X108270Y1567693I-150J132D01*
G01Y1568313D01*
G02X108472Y1568516I202J1D01*
G37*
G36*
G01X125795D02*
X128615D01*
G02X128818Y1568313I0J-203D01*
G01Y1567691D01*
G03X128868Y1567559I200J0D01*
G02Y1564647I-1664J-1456D01*
G03X128818Y1564515I150J-132D01*
G01Y1562573D01*
G03X128868Y1562441I200J0D01*
G02Y1559529I-1664J-1456D01*
G03X128818Y1559397I150J-132D01*
G01Y1558775D01*
G02X128615Y1558572I-203J0D01*
G01X125795D01*
G02X125592Y1558775I0J203D01*
G01Y1559397D01*
G03X125542Y1559529I-200J0D01*
G02Y1562441I1664J1456D01*
G03X125592Y1562573I-150J132D01*
G01Y1564515D01*
G03X125542Y1564647I-200J0D01*
G02Y1567559I1664J1456D01*
G03X125592Y1567691I-150J132D01*
G01Y1568313D01*
G02X125795Y1568516I203J0D01*
G37*
G36*
G01X143118D02*
X145938D01*
G02X146140Y1568313I-1J-203D01*
G01Y1567693D01*
G03X146190Y1567561I200J0D01*
G02Y1564645I-1661J-1458D01*
G03X146140Y1564513I150J-132D01*
G01Y1562575D01*
G03X146190Y1562443I200J0D01*
G02Y1559527I-1661J-1458D01*
G03X146140Y1559395I150J-132D01*
G01Y1558775D01*
G02X145938Y1558572I-202J-1D01*
G01X143118D01*
G02X142916Y1558775I1J203D01*
G01Y1559395D01*
G03X142866Y1559527I-200J0D01*
G02Y1562443I1661J1458D01*
G03X142916Y1562575I-150J132D01*
G01Y1564513D01*
G03X142866Y1564645I-200J0D01*
G02Y1567561I1661J1458D01*
G03X142916Y1567693I-150J132D01*
G01Y1568313D01*
G02X143118Y1568516I202J1D01*
G37*
G36*
G01X160440D02*
X163260D01*
G02X163462Y1568313I-1J-203D01*
G01Y1567693D01*
G03X163512Y1567561I200J0D01*
G02Y1564645I-1661J-1458D01*
G03X163462Y1564513I150J-132D01*
G01Y1562575D01*
G03X163512Y1562443I200J0D01*
G02Y1559527I-1661J-1458D01*
G03X163462Y1559395I150J-132D01*
G01Y1558775D01*
G02X163260Y1558572I-202J-1D01*
G01X160440D01*
G02X160238Y1558775I1J203D01*
G01Y1559395D01*
G03X160188Y1559527I-200J0D01*
G02Y1562443I1661J1458D01*
G03X160238Y1562575I-150J132D01*
G01Y1564513D01*
G03X160188Y1564645I-200J0D01*
G02Y1567561I1661J1458D01*
G03X160238Y1567693I-150J132D01*
G01Y1568313D01*
G02X160440Y1568516I202J1D01*
G37*
G36*
G01X281700D02*
X284520D01*
G02X284722Y1568313I-1J-203D01*
G01Y1567693D01*
G03X284772Y1567561I200J0D01*
G02Y1564645I-1661J-1458D01*
G03X284722Y1564513I150J-132D01*
G01Y1562575D01*
G03X284772Y1562443I200J0D01*
G02Y1559527I-1661J-1458D01*
G03X284722Y1559395I150J-132D01*
G01Y1558775D01*
G02X284520Y1558572I-202J-1D01*
G01X281700D01*
G02X281498Y1558775I1J203D01*
G01Y1559395D01*
G03X281448Y1559527I-200J0D01*
G02Y1562443I1661J1458D01*
G03X281498Y1562575I-150J132D01*
G01Y1564513D01*
G03X281448Y1564645I-200J0D01*
G02Y1567561I1661J1458D01*
G03X281498Y1567693I-150J132D01*
G01Y1568313D01*
G02X281700Y1568516I202J1D01*
G37*
G36*
G01X299023D02*
X301843D01*
G02X302046Y1568313I0J-203D01*
G01Y1567691D01*
G03X302096Y1567559I200J0D01*
G02Y1564647I-1664J-1456D01*
G03X302046Y1564515I150J-132D01*
G01Y1562573D01*
G03X302096Y1562441I200J0D01*
G02Y1559529I-1664J-1456D01*
G03X302046Y1559397I150J-132D01*
G01Y1558775D01*
G02X301843Y1558572I-203J0D01*
G01X299023D01*
G02X298820Y1558775I0J203D01*
G01Y1559397D01*
G03X298770Y1559529I-200J0D01*
G02Y1562441I1664J1456D01*
G03X298820Y1562573I-150J132D01*
G01Y1564515D01*
G03X298770Y1564647I-200J0D01*
G02Y1567559I1664J1456D01*
G03X298820Y1567691I-150J132D01*
G01Y1568313D01*
G02X299023Y1568516I203J0D01*
G37*
G36*
G01X316346D02*
X319166D01*
G02X319368Y1568313I-1J-203D01*
G01Y1567693D01*
G03X319418Y1567561I200J0D01*
G02Y1564645I-1661J-1458D01*
G03X319368Y1564513I150J-132D01*
G01Y1562575D01*
G03X319418Y1562443I200J0D01*
G02Y1559527I-1661J-1458D01*
G03X319368Y1559395I150J-132D01*
G01Y1558775D01*
G02X319166Y1558572I-202J-1D01*
G01X316346D01*
G02X316144Y1558775I1J203D01*
G01Y1559395D01*
G03X316094Y1559527I-200J0D01*
G02Y1562443I1661J1458D01*
G03X316144Y1562575I-150J132D01*
G01Y1564513D01*
G03X316094Y1564645I-200J0D01*
G02Y1567561I1661J1458D01*
G03X316144Y1567693I-150J132D01*
G01Y1568313D01*
G02X316346Y1568516I202J1D01*
G37*
G36*
G01X333668D02*
X336488D01*
G02X336690Y1568313I-1J-203D01*
G01Y1567693D01*
G03X336740Y1567561I200J0D01*
G02Y1564645I-1661J-1458D01*
G03X336690Y1564513I150J-132D01*
G01Y1562575D01*
G03X336740Y1562443I200J0D01*
G02Y1559527I-1661J-1458D01*
G03X336690Y1559395I150J-132D01*
G01Y1558775D01*
G02X336488Y1558572I-202J-1D01*
G01X333668D01*
G02X333466Y1558775I1J203D01*
G01Y1559395D01*
G03X333416Y1559527I-200J0D01*
G02Y1562443I1661J1458D01*
G03X333466Y1562575I-150J132D01*
G01Y1564513D01*
G03X333416Y1564645I-200J0D01*
G02Y1567561I1661J1458D01*
G03X333466Y1567693I-150J132D01*
G01Y1568313D01*
G02X333668Y1568516I202J1D01*
G37*
G36*
G01X628157D02*
X630977D01*
G02X631180Y1568313I0J-203D01*
G01Y1567691D01*
G03X631230Y1567559I200J0D01*
G02Y1564647I-1664J-1456D01*
G03X631180Y1564515I150J-132D01*
G01Y1562573D01*
G03X631230Y1562441I200J0D01*
G02Y1559529I-1664J-1456D01*
G03X631180Y1559397I150J-132D01*
G01Y1558775D01*
G02X630977Y1558572I-203J0D01*
G01X628157D01*
G02X627954Y1558775I0J203D01*
G01Y1559397D01*
G03X627904Y1559529I-200J0D01*
G02Y1562441I1664J1456D01*
G03X627954Y1562573I-150J132D01*
G01Y1564515D01*
G03X627904Y1564647I-200J0D01*
G02Y1567559I1664J1456D01*
G03X627954Y1567691I-150J132D01*
G01Y1568313D01*
G02X628157Y1568516I203J0D01*
G37*
G36*
G01X645480D02*
X648300D01*
G02X648502Y1568313I-1J-203D01*
G01Y1567693D01*
G03X648552Y1567561I200J0D01*
G02Y1564645I-1661J-1458D01*
G03X648502Y1564513I150J-132D01*
G01Y1562575D01*
G03X648552Y1562443I200J0D01*
G02Y1559527I-1661J-1458D01*
G03X648502Y1559395I150J-132D01*
G01Y1558775D01*
G02X648300Y1558572I-202J-1D01*
G01X645480D01*
G02X645278Y1558775I1J203D01*
G01Y1559395D01*
G03X645228Y1559527I-200J0D01*
G02Y1562443I1661J1458D01*
G03X645278Y1562575I-150J132D01*
G01Y1564513D01*
G03X645228Y1564645I-200J0D01*
G02Y1567561I1661J1458D01*
G03X645278Y1567693I-150J132D01*
G01Y1568313D01*
G02X645480Y1568516I202J1D01*
G37*
G36*
G01X662803D02*
X665623D01*
G02X665826Y1568313I0J-203D01*
G01Y1567691D01*
G03X665876Y1567559I200J0D01*
G02Y1564647I-1664J-1456D01*
G03X665826Y1564515I150J-132D01*
G01Y1562573D01*
G03X665876Y1562441I200J0D01*
G02Y1559529I-1664J-1456D01*
G03X665826Y1559397I150J-132D01*
G01Y1558775D01*
G02X665623Y1558572I-203J0D01*
G01X662803D01*
G02X662600Y1558775I0J203D01*
G01Y1559397D01*
G03X662550Y1559529I-200J0D01*
G02Y1562441I1664J1456D01*
G03X662600Y1562573I-150J132D01*
G01Y1564515D01*
G03X662550Y1564647I-200J0D01*
G02Y1567559I1664J1456D01*
G03X662600Y1567691I-150J132D01*
G01Y1568313D01*
G02X662803Y1568516I203J0D01*
G37*
G36*
G01X680125D02*
X682945D01*
G02X683148Y1568313I0J-203D01*
G01Y1567691D01*
G03X683198Y1567559I200J0D01*
G02Y1564647I-1664J-1456D01*
G03X683148Y1564515I150J-132D01*
G01Y1562573D01*
G03X683198Y1562441I200J0D01*
G02Y1559529I-1664J-1456D01*
G03X683148Y1559397I150J-132D01*
G01Y1558775D01*
G02X682945Y1558572I-203J0D01*
G01X680125D01*
G02X679922Y1558775I0J203D01*
G01Y1559397D01*
G03X679872Y1559529I-200J0D01*
G02Y1562441I1664J1456D01*
G03X679922Y1562573I-150J132D01*
G01Y1564515D01*
G03X679872Y1564647I-200J0D01*
G02Y1567559I1664J1456D01*
G03X679922Y1567691I-150J132D01*
G01Y1568313D01*
G02X680125Y1568516I203J0D01*
G37*
G36*
G01X1130440D02*
X1133260D01*
G02X1133462Y1568313I-1J-203D01*
G01Y1567693D01*
G03X1133512Y1567561I200J0D01*
G02Y1564645I-1661J-1458D01*
G03X1133462Y1564513I150J-132D01*
G01Y1562575D01*
G03X1133512Y1562443I200J0D01*
G02Y1559527I-1661J-1458D01*
G03X1133462Y1559395I150J-132D01*
G01Y1558775D01*
G02X1133260Y1558572I-202J-1D01*
G01X1130440D01*
G02X1130238Y1558775I1J203D01*
G01Y1559395D01*
G03X1130188Y1559527I-200J0D01*
G02Y1562443I1661J1458D01*
G03X1130238Y1562575I-150J132D01*
G01Y1564513D01*
G03X1130188Y1564645I-200J0D01*
G02Y1567561I1661J1458D01*
G03X1130238Y1567693I-150J132D01*
G01Y1568313D01*
G02X1130440Y1568516I202J1D01*
G37*
G36*
G01X1147763D02*
X1150583D01*
G02X1150786Y1568313I0J-203D01*
G01Y1567691D01*
G03X1150836Y1567559I200J0D01*
G02Y1564647I-1664J-1456D01*
G03X1150786Y1564515I150J-132D01*
G01Y1562573D01*
G03X1150836Y1562441I200J0D01*
G02Y1559529I-1664J-1456D01*
G03X1150786Y1559397I150J-132D01*
G01Y1558775D01*
G02X1150583Y1558572I-203J0D01*
G01X1147763D01*
G02X1147560Y1558775I0J203D01*
G01Y1559397D01*
G03X1147510Y1559529I-200J0D01*
G02Y1562441I1664J1456D01*
G03X1147560Y1562573I-150J132D01*
G01Y1564515D01*
G03X1147510Y1564647I-200J0D01*
G02Y1567559I1664J1456D01*
G03X1147560Y1567691I-150J132D01*
G01Y1568313D01*
G02X1147763Y1568516I203J0D01*
G37*
G36*
G01X1165086D02*
X1167906D01*
G02X1168108Y1568313I-1J-203D01*
G01Y1567693D01*
G03X1168158Y1567561I200J0D01*
G02Y1564645I-1661J-1458D01*
G03X1168108Y1564513I150J-132D01*
G01Y1562575D01*
G03X1168158Y1562443I200J0D01*
G02Y1559527I-1661J-1458D01*
G03X1168108Y1559395I150J-132D01*
G01Y1558775D01*
G02X1167906Y1558572I-202J-1D01*
G01X1165086D01*
G02X1164884Y1558775I1J203D01*
G01Y1559395D01*
G03X1164834Y1559527I-200J0D01*
G02Y1562443I1661J1458D01*
G03X1164884Y1562575I-150J132D01*
G01Y1564513D01*
G03X1164834Y1564645I-200J0D01*
G02Y1567561I1661J1458D01*
G03X1164884Y1567693I-150J132D01*
G01Y1568313D01*
G02X1165086Y1568516I202J1D01*
G37*
G36*
G01X1182408D02*
X1185228D01*
G02X1185430Y1568313I-1J-203D01*
G01Y1567693D01*
G03X1185480Y1567561I200J0D01*
G02Y1564645I-1661J-1458D01*
G03X1185430Y1564513I150J-132D01*
G01Y1562575D01*
G03X1185480Y1562443I200J0D01*
G02Y1559527I-1661J-1458D01*
G03X1185430Y1559395I150J-132D01*
G01Y1558775D01*
G02X1185228Y1558572I-202J-1D01*
G01X1182408D01*
G02X1182206Y1558775I1J203D01*
G01Y1559395D01*
G03X1182156Y1559527I-200J0D01*
G02Y1562443I1661J1458D01*
G03X1182206Y1562575I-150J132D01*
G01Y1564513D01*
G03X1182156Y1564645I-200J0D01*
G02Y1567561I1661J1458D01*
G03X1182206Y1567693I-150J132D01*
G01Y1568313D01*
G02X1182408Y1568516I202J1D01*
G37*
G36*
G01X1303669D02*
X1306489D01*
G02X1306692Y1568313I0J-203D01*
G01Y1567691D01*
G03X1306742Y1567559I200J0D01*
G02Y1564647I-1664J-1456D01*
G03X1306692Y1564515I150J-132D01*
G01Y1562573D01*
G03X1306742Y1562441I200J0D01*
G02Y1559529I-1664J-1456D01*
G03X1306692Y1559397I150J-132D01*
G01Y1558775D01*
G02X1306489Y1558572I-203J0D01*
G01X1303669D01*
G02X1303466Y1558775I0J203D01*
G01Y1559397D01*
G03X1303416Y1559529I-200J0D01*
G02Y1562441I1664J1456D01*
G03X1303466Y1562573I-150J132D01*
G01Y1564515D01*
G03X1303416Y1564647I-200J0D01*
G02Y1567559I1664J1456D01*
G03X1303466Y1567691I-150J132D01*
G01Y1568313D01*
G02X1303669Y1568516I203J0D01*
G37*
G36*
G01X1320992D02*
X1323812D01*
G02X1324014Y1568313I-1J-203D01*
G01Y1567693D01*
G03X1324064Y1567561I200J0D01*
G02Y1564645I-1661J-1458D01*
G03X1324014Y1564513I150J-132D01*
G01Y1562575D01*
G03X1324064Y1562443I200J0D01*
G02Y1559527I-1661J-1458D01*
G03X1324014Y1559395I150J-132D01*
G01Y1558775D01*
G02X1323812Y1558572I-202J-1D01*
G01X1320992D01*
G02X1320790Y1558775I1J203D01*
G01Y1559395D01*
G03X1320740Y1559527I-200J0D01*
G02Y1562443I1661J1458D01*
G03X1320790Y1562575I-150J132D01*
G01Y1564513D01*
G03X1320740Y1564645I-200J0D01*
G02Y1567561I1661J1458D01*
G03X1320790Y1567693I-150J132D01*
G01Y1568313D01*
G02X1320992Y1568516I202J1D01*
G37*
G36*
G01X1338315D02*
X1341135D01*
G02X1341338Y1568313I0J-203D01*
G01Y1567691D01*
G03X1341388Y1567559I200J0D01*
G02Y1564647I-1664J-1456D01*
G03X1341338Y1564515I150J-132D01*
G01Y1562573D01*
G03X1341388Y1562441I200J0D01*
G02Y1559529I-1664J-1456D01*
G03X1341338Y1559397I150J-132D01*
G01Y1558775D01*
G02X1341135Y1558572I-203J0D01*
G01X1338315D01*
G02X1338112Y1558775I0J203D01*
G01Y1559397D01*
G03X1338062Y1559529I-200J0D01*
G02Y1562441I1664J1456D01*
G03X1338112Y1562573I-150J132D01*
G01Y1564515D01*
G03X1338062Y1564647I-200J0D01*
G02Y1567559I1664J1456D01*
G03X1338112Y1567691I-150J132D01*
G01Y1568313D01*
G02X1338315Y1568516I203J0D01*
G37*
G36*
G01X1355637D02*
X1358457D01*
G02X1358660Y1568313I0J-203D01*
G01Y1567691D01*
G03X1358710Y1567559I200J0D01*
G02Y1564647I-1664J-1456D01*
G03X1358660Y1564515I150J-132D01*
G01Y1562573D01*
G03X1358710Y1562441I200J0D01*
G02Y1559529I-1664J-1456D01*
G03X1358660Y1559397I150J-132D01*
G01Y1558775D01*
G02X1358457Y1558572I-203J0D01*
G01X1355637D01*
G02X1355434Y1558775I0J203D01*
G01Y1559397D01*
G03X1355384Y1559529I-200J0D01*
G02Y1562441I1664J1456D01*
G03X1355434Y1562573I-150J132D01*
G01Y1564515D01*
G03X1355384Y1564647I-200J0D01*
G02Y1567559I1664J1456D01*
G03X1355434Y1567691I-150J132D01*
G01Y1568313D01*
G02X1355637Y1568516I203J0D01*
G37*
G36*
G01X1476897D02*
X1479717D01*
G02X1479920Y1568313I0J-203D01*
G01Y1567691D01*
G03X1479970Y1567559I200J0D01*
G02Y1564647I-1664J-1456D01*
G03X1479920Y1564515I150J-132D01*
G01Y1562573D01*
G03X1479970Y1562441I200J0D01*
G02Y1559529I-1664J-1456D01*
G03X1479920Y1559397I150J-132D01*
G01Y1558775D01*
G02X1479717Y1558572I-203J0D01*
G01X1476897D01*
G02X1476694Y1558775I0J203D01*
G01Y1559397D01*
G03X1476644Y1559529I-200J0D01*
G02Y1562441I1664J1456D01*
G03X1476694Y1562573I-150J132D01*
G01Y1564515D01*
G03X1476644Y1564647I-200J0D01*
G02Y1567559I1664J1456D01*
G03X1476694Y1567691I-150J132D01*
G01Y1568313D01*
G02X1476897Y1568516I203J0D01*
G37*
G36*
G01X1650125D02*
X1652945D01*
G02X1653148Y1568313I0J-203D01*
G01Y1567691D01*
G03X1653198Y1567559I200J0D01*
G02Y1564647I-1664J-1456D01*
G03X1653148Y1564515I150J-132D01*
G01Y1562573D01*
G03X1653198Y1562441I200J0D01*
G02Y1559529I-1664J-1456D01*
G03X1653148Y1559397I150J-132D01*
G01Y1558775D01*
G02X1652945Y1558572I-203J0D01*
G01X1650125D01*
G02X1649922Y1558775I0J203D01*
G01Y1559397D01*
G03X1649872Y1559529I-200J0D01*
G02Y1562441I1664J1456D01*
G03X1649922Y1562573I-150J132D01*
G01Y1564515D01*
G03X1649872Y1564647I-200J0D01*
G02Y1567559I1664J1456D01*
G03X1649922Y1567691I-150J132D01*
G01Y1568313D01*
G02X1650125Y1568516I203J0D01*
G37*
G36*
G01X1667448D02*
X1670268D01*
G02X1670470Y1568313I-1J-203D01*
G01Y1567693D01*
G03X1670520Y1567561I200J0D01*
G02Y1564645I-1661J-1458D01*
G03X1670470Y1564513I150J-132D01*
G01Y1562575D01*
G03X1670520Y1562443I200J0D01*
G02Y1559527I-1661J-1458D01*
G03X1670470Y1559395I150J-132D01*
G01Y1558775D01*
G02X1670268Y1558572I-202J-1D01*
G01X1667448D01*
G02X1667246Y1558775I1J203D01*
G01Y1559395D01*
G03X1667196Y1559527I-200J0D01*
G02Y1562443I1661J1458D01*
G03X1667246Y1562575I-150J132D01*
G01Y1564513D01*
G03X1667196Y1564645I-200J0D01*
G02Y1567561I1661J1458D01*
G03X1667246Y1567693I-150J132D01*
G01Y1568313D01*
G02X1667448Y1568516I202J1D01*
G37*
G36*
G01X1684771D02*
X1687591D01*
G02X1687794Y1568313I0J-203D01*
G01Y1567691D01*
G03X1687844Y1567559I200J0D01*
G02Y1564647I-1664J-1456D01*
G03X1687794Y1564515I150J-132D01*
G01Y1562573D01*
G03X1687844Y1562441I200J0D01*
G02Y1559529I-1664J-1456D01*
G03X1687794Y1559397I150J-132D01*
G01Y1558775D01*
G02X1687591Y1558572I-203J0D01*
G01X1684771D01*
G02X1684568Y1558775I0J203D01*
G01Y1559397D01*
G03X1684518Y1559529I-200J0D01*
G02Y1562441I1664J1456D01*
G03X1684568Y1562573I-150J132D01*
G01Y1564515D01*
G03X1684518Y1564647I-200J0D01*
G02Y1567559I1664J1456D01*
G03X1684568Y1567691I-150J132D01*
G01Y1568313D01*
G02X1684771Y1568516I203J0D01*
G37*
G36*
G01X1702093D02*
X1704913D01*
G02X1705116Y1568313I0J-203D01*
G01Y1567691D01*
G03X1705166Y1567559I200J0D01*
G02Y1564647I-1664J-1456D01*
G03X1705116Y1564515I150J-132D01*
G01Y1562573D01*
G03X1705166Y1562441I200J0D01*
G02Y1559529I-1664J-1456D01*
G03X1705116Y1559397I150J-132D01*
G01Y1558775D01*
G02X1704913Y1558572I-203J0D01*
G01X1702093D01*
G02X1701890Y1558775I0J203D01*
G01Y1559397D01*
G03X1701840Y1559529I-200J0D01*
G02Y1562441I1664J1456D01*
G03X1701890Y1562573I-150J132D01*
G01Y1564515D01*
G03X1701840Y1564647I-200J0D01*
G02Y1567559I1664J1456D01*
G03X1701890Y1567691I-150J132D01*
G01Y1568313D01*
G02X1702093Y1568516I203J0D01*
G37*
G36*
G01X134456Y1572846D02*
X137276D01*
G02X137478Y1572644I0J-202D01*
G01Y1572024D01*
G03X137528Y1571892I200J0D01*
G02Y1568976I-1661J-1458D01*
G03X137478Y1568844I150J-132D01*
G01Y1566905D01*
G03X137528Y1566773I200J0D01*
G02Y1563857I-1661J-1458D01*
G03X137478Y1563725I150J-132D01*
G01Y1563106D01*
G02X137276Y1562904I-202J0D01*
G01X134456D01*
G02X134254Y1563106I0J202D01*
G01Y1563725D01*
G03X134204Y1563857I-200J0D01*
G02Y1566773I1661J1458D01*
G03X134254Y1566905I-150J132D01*
G01Y1568844D01*
G03X134204Y1568976I-200J0D01*
G02Y1571892I1661J1458D01*
G03X134254Y1572024I-150J132D01*
G01Y1572644D01*
G02X134456Y1572846I202J0D01*
G37*
G36*
G01X169102D02*
X171922D01*
G02X172124Y1572644I0J-202D01*
G01Y1572024D01*
G03X172174Y1571892I200J0D01*
G02Y1568976I-1661J-1458D01*
G03X172124Y1568844I150J-132D01*
G01Y1566905D01*
G03X172174Y1566773I200J0D01*
G02Y1563857I-1661J-1458D01*
G03X172124Y1563725I150J-132D01*
G01Y1563106D01*
G02X171922Y1562904I-202J0D01*
G01X169102D01*
G02X168900Y1563106I0J202D01*
G01Y1563725D01*
G03X168850Y1563857I-200J0D01*
G02Y1566773I1661J1458D01*
G03X168900Y1566905I-150J132D01*
G01Y1568844D01*
G03X168850Y1568976I-200J0D01*
G02Y1571892I1661J1458D01*
G03X168900Y1572024I-150J132D01*
G01Y1572644D01*
G02X169102Y1572846I202J0D01*
G37*
G36*
G01X307684D02*
X310504D01*
G02X310706Y1572644I0J-202D01*
G01Y1572024D01*
G03X310756Y1571892I200J0D01*
G02Y1568976I-1661J-1458D01*
G03X310706Y1568844I150J-132D01*
G01Y1566905D01*
G03X310756Y1566773I200J0D01*
G02Y1563857I-1661J-1458D01*
G03X310706Y1563725I150J-132D01*
G01Y1563106D01*
G02X310504Y1562904I-202J0D01*
G01X307684D01*
G02X307482Y1563106I0J202D01*
G01Y1563725D01*
G03X307432Y1563857I-200J0D01*
G02Y1566773I1661J1458D01*
G03X307482Y1566905I-150J132D01*
G01Y1568844D01*
G03X307432Y1568976I-200J0D01*
G02Y1571892I1661J1458D01*
G03X307482Y1572024I-150J132D01*
G01Y1572644D01*
G02X307684Y1572846I202J0D01*
G37*
G36*
G01X342330D02*
X345150D01*
G02X345352Y1572644I0J-202D01*
G01Y1572024D01*
G03X345402Y1571892I200J0D01*
G02Y1568976I-1661J-1458D01*
G03X345352Y1568844I150J-132D01*
G01Y1566905D01*
G03X345402Y1566773I200J0D01*
G02Y1563857I-1661J-1458D01*
G03X345352Y1563725I150J-132D01*
G01Y1563106D01*
G02X345150Y1562904I-202J0D01*
G01X342330D01*
G02X342128Y1563106I0J202D01*
G01Y1563725D01*
G03X342078Y1563857I-200J0D01*
G02Y1566773I1661J1458D01*
G03X342128Y1566905I-150J132D01*
G01Y1568844D01*
G03X342078Y1568976I-200J0D01*
G02Y1571892I1661J1458D01*
G03X342128Y1572024I-150J132D01*
G01Y1572644D01*
G02X342330Y1572846I202J0D01*
G37*
G36*
G01X636818D02*
X639638D01*
G02X639840Y1572644I0J-202D01*
G01Y1572024D01*
G03X639890Y1571892I200J0D01*
G02Y1568976I-1661J-1458D01*
G03X639840Y1568844I150J-132D01*
G01Y1566905D01*
G03X639890Y1566773I200J0D01*
G02Y1563857I-1661J-1458D01*
G03X639840Y1563725I150J-132D01*
G01Y1563106D01*
G02X639638Y1562904I-202J0D01*
G01X636818D01*
G02X636616Y1563106I0J202D01*
G01Y1563725D01*
G03X636566Y1563857I-200J0D01*
G02Y1566773I1661J1458D01*
G03X636616Y1566905I-150J132D01*
G01Y1568844D01*
G03X636566Y1568976I-200J0D01*
G02Y1571892I1661J1458D01*
G03X636616Y1572024I-150J132D01*
G01Y1572644D01*
G02X636818Y1572846I202J0D01*
G37*
G36*
G01X671464D02*
X674284D01*
G02X674486Y1572644I0J-202D01*
G01Y1572024D01*
G03X674536Y1571892I200J0D01*
G02Y1568976I-1661J-1458D01*
G03X674486Y1568844I150J-132D01*
G01Y1566905D01*
G03X674536Y1566773I200J0D01*
G02Y1563857I-1661J-1458D01*
G03X674486Y1563725I150J-132D01*
G01Y1563106D01*
G02X674284Y1562904I-202J0D01*
G01X671464D01*
G02X671262Y1563106I0J202D01*
G01Y1563725D01*
G03X671212Y1563857I-200J0D01*
G02Y1566773I1661J1458D01*
G03X671262Y1566905I-150J132D01*
G01Y1568844D01*
G03X671212Y1568976I-200J0D01*
G02Y1571892I1661J1458D01*
G03X671262Y1572024I-150J132D01*
G01Y1572644D01*
G02X671464Y1572846I202J0D01*
G37*
G36*
G01X1156424D02*
X1159244D01*
G02X1159446Y1572644I0J-202D01*
G01Y1572024D01*
G03X1159496Y1571892I200J0D01*
G02Y1568976I-1661J-1458D01*
G03X1159446Y1568844I150J-132D01*
G01Y1566905D01*
G03X1159496Y1566773I200J0D01*
G02Y1563857I-1661J-1458D01*
G03X1159446Y1563725I150J-132D01*
G01Y1563106D01*
G02X1159244Y1562904I-202J0D01*
G01X1156424D01*
G02X1156222Y1563106I0J202D01*
G01Y1563725D01*
G03X1156172Y1563857I-200J0D01*
G02Y1566773I1661J1458D01*
G03X1156222Y1566905I-150J132D01*
G01Y1568844D01*
G03X1156172Y1568976I-200J0D01*
G02Y1571892I1661J1458D01*
G03X1156222Y1572024I-150J132D01*
G01Y1572644D01*
G02X1156424Y1572846I202J0D01*
G37*
G36*
G01X1191070D02*
X1193890D01*
G02X1194092Y1572644I0J-202D01*
G01Y1572024D01*
G03X1194142Y1571892I200J0D01*
G02Y1568976I-1661J-1458D01*
G03X1194092Y1568844I150J-132D01*
G01Y1566905D01*
G03X1194142Y1566773I200J0D01*
G02Y1563857I-1661J-1458D01*
G03X1194092Y1563725I150J-132D01*
G01Y1563106D01*
G02X1193890Y1562904I-202J0D01*
G01X1191070D01*
G02X1190868Y1563106I0J202D01*
G01Y1563725D01*
G03X1190818Y1563857I-200J0D01*
G02Y1566773I1661J1458D01*
G03X1190868Y1566905I-150J132D01*
G01Y1568844D01*
G03X1190818Y1568976I-200J0D01*
G02Y1571892I1661J1458D01*
G03X1190868Y1572024I-150J132D01*
G01Y1572644D01*
G02X1191070Y1572846I202J0D01*
G37*
G36*
G01X1312330D02*
X1315150D01*
G02X1315352Y1572644I0J-202D01*
G01Y1572024D01*
G03X1315402Y1571892I200J0D01*
G02Y1568976I-1661J-1458D01*
G03X1315352Y1568844I150J-132D01*
G01Y1566905D01*
G03X1315402Y1566773I200J0D01*
G02Y1563857I-1661J-1458D01*
G03X1315352Y1563725I150J-132D01*
G01Y1563106D01*
G02X1315150Y1562904I-202J0D01*
G01X1312330D01*
G02X1312128Y1563106I0J202D01*
G01Y1563725D01*
G03X1312078Y1563857I-200J0D01*
G02Y1566773I1661J1458D01*
G03X1312128Y1566905I-150J132D01*
G01Y1568844D01*
G03X1312078Y1568976I-200J0D01*
G02Y1571892I1661J1458D01*
G03X1312128Y1572024I-150J132D01*
G01Y1572644D01*
G02X1312330Y1572846I202J0D01*
G37*
G36*
G01X1346976D02*
X1349796D01*
G02X1349998Y1572644I0J-202D01*
G01Y1572024D01*
G03X1350048Y1571892I200J0D01*
G02Y1568976I-1661J-1458D01*
G03X1349998Y1568844I150J-132D01*
G01Y1566905D01*
G03X1350048Y1566773I200J0D01*
G02Y1563857I-1661J-1458D01*
G03X1349998Y1563725I150J-132D01*
G01Y1563106D01*
G02X1349796Y1562904I-202J0D01*
G01X1346976D01*
G02X1346774Y1563106I0J202D01*
G01Y1563725D01*
G03X1346724Y1563857I-200J0D01*
G02Y1566773I1661J1458D01*
G03X1346774Y1566905I-150J132D01*
G01Y1568844D01*
G03X1346724Y1568976I-200J0D01*
G02Y1571892I1661J1458D01*
G03X1346774Y1572024I-150J132D01*
G01Y1572644D01*
G02X1346976Y1572846I202J0D01*
G37*
G36*
G01X1658786D02*
X1661606D01*
G02X1661808Y1572644I0J-202D01*
G01Y1572024D01*
G03X1661858Y1571892I200J0D01*
G02Y1568976I-1661J-1458D01*
G03X1661808Y1568844I150J-132D01*
G01Y1566905D01*
G03X1661858Y1566773I200J0D01*
G02Y1563857I-1661J-1458D01*
G03X1661808Y1563725I150J-132D01*
G01Y1563106D01*
G02X1661606Y1562904I-202J0D01*
G01X1658786D01*
G02X1658584Y1563106I0J202D01*
G01Y1563725D01*
G03X1658534Y1563857I-200J0D01*
G02Y1566773I1661J1458D01*
G03X1658584Y1566905I-150J132D01*
G01Y1568844D01*
G03X1658534Y1568976I-200J0D01*
G02Y1571892I1661J1458D01*
G03X1658584Y1572024I-150J132D01*
G01Y1572644D01*
G02X1658786Y1572846I202J0D01*
G37*
G36*
G01X1693432D02*
X1696252D01*
G02X1696454Y1572644I0J-202D01*
G01Y1572024D01*
G03X1696504Y1571892I200J0D01*
G02Y1568976I-1661J-1458D01*
G03X1696454Y1568844I150J-132D01*
G01Y1566905D01*
G03X1696504Y1566773I200J0D01*
G02Y1563857I-1661J-1458D01*
G03X1696454Y1563725I150J-132D01*
G01Y1563106D01*
G02X1696252Y1562904I-202J0D01*
G01X1693432D01*
G02X1693230Y1563106I0J202D01*
G01Y1563725D01*
G03X1693180Y1563857I-200J0D01*
G02Y1566773I1661J1458D01*
G03X1693230Y1566905I-150J132D01*
G01Y1568844D01*
G03X1693180Y1568976I-200J0D01*
G02Y1571892I1661J1458D01*
G03X1693230Y1572024I-150J132D01*
G01Y1572644D01*
G02X1693432Y1572846I202J0D01*
G37*
G36*
G01X117133D02*
X119953D01*
G02X120156Y1572644I1J-202D01*
G01Y1572022D01*
G03X120206Y1571890I200J0D01*
G02Y1568978I-1664J-1456D01*
G03X120156Y1568846I150J-132D01*
G01Y1566903D01*
G03X120206Y1566771I200J0D01*
G02Y1563859I-1664J-1456D01*
G03X120156Y1563727I150J-132D01*
G01Y1563106D01*
G02X119953Y1562904I-203J1D01*
G01X117133D01*
G02X116930Y1563106I-1J202D01*
G01Y1563727D01*
G03X116880Y1563859I-200J0D01*
G02Y1566771I1664J1456D01*
G03X116930Y1566903I-150J132D01*
G01Y1568846D01*
G03X116880Y1568978I-200J0D01*
G02Y1571890I1664J1456D01*
G03X116930Y1572022I-150J132D01*
G01Y1572644D01*
G02X117133Y1572846I203J-1D01*
G37*
G36*
G01X151779D02*
X154599D01*
G02X154802Y1572644I1J-202D01*
G01Y1572022D01*
G03X154852Y1571890I200J0D01*
G02Y1568978I-1664J-1456D01*
G03X154802Y1568846I150J-132D01*
G01Y1566903D01*
G03X154852Y1566771I200J0D01*
G02Y1563859I-1664J-1456D01*
G03X154802Y1563727I150J-132D01*
G01Y1563106D01*
G02X154599Y1562904I-203J1D01*
G01X151779D01*
G02X151576Y1563106I-1J202D01*
G01Y1563727D01*
G03X151526Y1563859I-200J0D01*
G02Y1566771I1664J1456D01*
G03X151576Y1566903I-150J132D01*
G01Y1568846D01*
G03X151526Y1568978I-200J0D01*
G02Y1571890I1664J1456D01*
G03X151576Y1572022I-150J132D01*
G01Y1572644D01*
G02X151779Y1572846I203J-1D01*
G37*
G36*
G01X290361D02*
X293181D01*
G02X293384Y1572644I1J-202D01*
G01Y1572022D01*
G03X293434Y1571890I200J0D01*
G02Y1568978I-1664J-1456D01*
G03X293384Y1568846I150J-132D01*
G01Y1566903D01*
G03X293434Y1566771I200J0D01*
G02Y1563859I-1664J-1456D01*
G03X293384Y1563727I150J-132D01*
G01Y1563106D01*
G02X293181Y1562904I-203J1D01*
G01X290361D01*
G02X290158Y1563106I-1J202D01*
G01Y1563727D01*
G03X290108Y1563859I-200J0D01*
G02Y1566771I1664J1456D01*
G03X290158Y1566903I-150J132D01*
G01Y1568846D01*
G03X290108Y1568978I-200J0D01*
G02Y1571890I1664J1456D01*
G03X290158Y1572022I-150J132D01*
G01Y1572644D01*
G02X290361Y1572846I203J-1D01*
G37*
G36*
G01X325007D02*
X327827D01*
G02X328030Y1572644I1J-202D01*
G01Y1572022D01*
G03X328080Y1571890I200J0D01*
G02Y1568978I-1664J-1456D01*
G03X328030Y1568846I150J-132D01*
G01Y1566903D01*
G03X328080Y1566771I200J0D01*
G02Y1563859I-1664J-1456D01*
G03X328030Y1563727I150J-132D01*
G01Y1563106D01*
G02X327827Y1562904I-203J1D01*
G01X325007D01*
G02X324804Y1563106I-1J202D01*
G01Y1563727D01*
G03X324754Y1563859I-200J0D01*
G02Y1566771I1664J1456D01*
G03X324804Y1566903I-150J132D01*
G01Y1568846D01*
G03X324754Y1568978I-200J0D01*
G02Y1571890I1664J1456D01*
G03X324804Y1572022I-150J132D01*
G01Y1572644D01*
G02X325007Y1572846I203J-1D01*
G37*
G36*
G01X515559D02*
X518379D01*
G02X518582Y1572644I1J-202D01*
G01Y1572022D01*
G03X518632Y1571890I200J0D01*
G02Y1568978I-1664J-1456D01*
G03X518582Y1568846I150J-132D01*
G01Y1566903D01*
G03X518632Y1566771I200J0D01*
G02Y1563859I-1664J-1456D01*
G03X518582Y1563727I150J-132D01*
G01Y1563106D01*
G02X518379Y1562904I-203J1D01*
G01X515559D01*
G02X515356Y1563106I-1J202D01*
G01Y1563727D01*
G03X515306Y1563859I-200J0D01*
G02Y1566771I1664J1456D01*
G03X515356Y1566903I-150J132D01*
G01Y1568846D01*
G03X515306Y1568978I-200J0D01*
G02Y1571890I1664J1456D01*
G03X515356Y1572022I-150J132D01*
G01Y1572644D01*
G02X515559Y1572846I203J-1D01*
G37*
G36*
G01X654141D02*
X656961D01*
G02X657164Y1572644I1J-202D01*
G01Y1572022D01*
G03X657214Y1571890I200J0D01*
G02Y1568978I-1664J-1456D01*
G03X657164Y1568846I150J-132D01*
G01Y1566903D01*
G03X657214Y1566771I200J0D01*
G02Y1563859I-1664J-1456D01*
G03X657164Y1563727I150J-132D01*
G01Y1563106D01*
G02X656961Y1562904I-203J1D01*
G01X654141D01*
G02X653938Y1563106I-1J202D01*
G01Y1563727D01*
G03X653888Y1563859I-200J0D01*
G02Y1566771I1664J1456D01*
G03X653938Y1566903I-150J132D01*
G01Y1568846D01*
G03X653888Y1568978I-200J0D01*
G02Y1571890I1664J1456D01*
G03X653938Y1572022I-150J132D01*
G01Y1572644D01*
G02X654141Y1572846I203J-1D01*
G37*
G36*
G01X688787D02*
X691607D01*
G02X691810Y1572644I1J-202D01*
G01Y1572022D01*
G03X691860Y1571890I200J0D01*
G02Y1568978I-1664J-1456D01*
G03X691810Y1568846I150J-132D01*
G01Y1566903D01*
G03X691860Y1566771I200J0D01*
G02Y1563859I-1664J-1456D01*
G03X691810Y1563727I150J-132D01*
G01Y1563106D01*
G02X691607Y1562904I-203J1D01*
G01X688787D01*
G02X688584Y1563106I-1J202D01*
G01Y1563727D01*
G03X688534Y1563859I-200J0D01*
G02Y1566771I1664J1456D01*
G03X688584Y1566903I-150J132D01*
G01Y1568846D01*
G03X688534Y1568978I-200J0D01*
G02Y1571890I1664J1456D01*
G03X688584Y1572022I-150J132D01*
G01Y1572644D01*
G02X688787Y1572846I203J-1D01*
G37*
G36*
G01X1139101D02*
X1141921D01*
G02X1142124Y1572644I1J-202D01*
G01Y1572022D01*
G03X1142174Y1571890I200J0D01*
G02Y1568978I-1664J-1456D01*
G03X1142124Y1568846I150J-132D01*
G01Y1566903D01*
G03X1142174Y1566771I200J0D01*
G02Y1563859I-1664J-1456D01*
G03X1142124Y1563727I150J-132D01*
G01Y1563106D01*
G02X1141921Y1562904I-203J1D01*
G01X1139101D01*
G02X1138898Y1563106I-1J202D01*
G01Y1563727D01*
G03X1138848Y1563859I-200J0D01*
G02Y1566771I1664J1456D01*
G03X1138898Y1566903I-150J132D01*
G01Y1568846D01*
G03X1138848Y1568978I-200J0D01*
G02Y1571890I1664J1456D01*
G03X1138898Y1572022I-150J132D01*
G01Y1572644D01*
G02X1139101Y1572846I203J-1D01*
G37*
G36*
G01X1173747D02*
X1176567D01*
G02X1176770Y1572644I1J-202D01*
G01Y1572022D01*
G03X1176820Y1571890I200J0D01*
G02Y1568978I-1664J-1456D01*
G03X1176770Y1568846I150J-132D01*
G01Y1566903D01*
G03X1176820Y1566771I200J0D01*
G02Y1563859I-1664J-1456D01*
G03X1176770Y1563727I150J-132D01*
G01Y1563106D01*
G02X1176567Y1562904I-203J1D01*
G01X1173747D01*
G02X1173544Y1563106I-1J202D01*
G01Y1563727D01*
G03X1173494Y1563859I-200J0D01*
G02Y1566771I1664J1456D01*
G03X1173544Y1566903I-150J132D01*
G01Y1568846D01*
G03X1173494Y1568978I-200J0D01*
G02Y1571890I1664J1456D01*
G03X1173544Y1572022I-150J132D01*
G01Y1572644D01*
G02X1173747Y1572846I203J-1D01*
G37*
G36*
G01X1329653D02*
X1332473D01*
G02X1332676Y1572644I1J-202D01*
G01Y1572022D01*
G03X1332726Y1571890I200J0D01*
G02Y1568978I-1664J-1456D01*
G03X1332676Y1568846I150J-132D01*
G01Y1566903D01*
G03X1332726Y1566771I200J0D01*
G02Y1563859I-1664J-1456D01*
G03X1332676Y1563727I150J-132D01*
G01Y1563106D01*
G02X1332473Y1562904I-203J1D01*
G01X1329653D01*
G02X1329450Y1563106I-1J202D01*
G01Y1563727D01*
G03X1329400Y1563859I-200J0D01*
G02Y1566771I1664J1456D01*
G03X1329450Y1566903I-150J132D01*
G01Y1568846D01*
G03X1329400Y1568978I-200J0D01*
G02Y1571890I1664J1456D01*
G03X1329450Y1572022I-150J132D01*
G01Y1572644D01*
G02X1329653Y1572846I203J-1D01*
G37*
G36*
G01X1364299D02*
X1367119D01*
G02X1367322Y1572644I1J-202D01*
G01Y1572022D01*
G03X1367372Y1571890I200J0D01*
G02Y1568978I-1664J-1456D01*
G03X1367322Y1568846I150J-132D01*
G01Y1566903D01*
G03X1367372Y1566771I200J0D01*
G02Y1563859I-1664J-1456D01*
G03X1367322Y1563727I150J-132D01*
G01Y1563106D01*
G02X1367119Y1562904I-203J1D01*
G01X1364299D01*
G02X1364096Y1563106I-1J202D01*
G01Y1563727D01*
G03X1364046Y1563859I-200J0D01*
G02Y1566771I1664J1456D01*
G03X1364096Y1566903I-150J132D01*
G01Y1568846D01*
G03X1364046Y1568978I-200J0D01*
G02Y1571890I1664J1456D01*
G03X1364096Y1572022I-150J132D01*
G01Y1572644D01*
G02X1364299Y1572846I203J-1D01*
G37*
G36*
G01X1676109D02*
X1678929D01*
G02X1679132Y1572644I1J-202D01*
G01Y1572022D01*
G03X1679182Y1571890I200J0D01*
G02Y1568978I-1664J-1456D01*
G03X1679132Y1568846I150J-132D01*
G01Y1566903D01*
G03X1679182Y1566771I200J0D01*
G02Y1563859I-1664J-1456D01*
G03X1679132Y1563727I150J-132D01*
G01Y1563106D01*
G02X1678929Y1562904I-203J1D01*
G01X1676109D01*
G02X1675906Y1563106I-1J202D01*
G01Y1563727D01*
G03X1675856Y1563859I-200J0D01*
G02Y1566771I1664J1456D01*
G03X1675906Y1566903I-150J132D01*
G01Y1568846D01*
G03X1675856Y1568978I-200J0D01*
G02Y1571890I1664J1456D01*
G03X1675906Y1572022I-150J132D01*
G01Y1572644D01*
G02X1676109Y1572846I203J-1D01*
G37*
G36*
G01X1710755D02*
X1713575D01*
G02X1713778Y1572644I1J-202D01*
G01Y1572022D01*
G03X1713828Y1571890I200J0D01*
G02Y1568978I-1664J-1456D01*
G03X1713778Y1568846I150J-132D01*
G01Y1566903D01*
G03X1713828Y1566771I200J0D01*
G02Y1563859I-1664J-1456D01*
G03X1713778Y1563727I150J-132D01*
G01Y1563106D01*
G02X1713575Y1562904I-203J1D01*
G01X1710755D01*
G02X1710552Y1563106I-1J202D01*
G01Y1563727D01*
G03X1710502Y1563859I-200J0D01*
G02Y1566771I1664J1456D01*
G03X1710552Y1566903I-150J132D01*
G01Y1568846D01*
G03X1710502Y1568978I-200J0D01*
G02Y1571890I1664J1456D01*
G03X1710552Y1572022I-150J132D01*
G01Y1572644D01*
G02X1710755Y1572846I203J-1D01*
G37*
G36*
G01X108472Y1583870D02*
X111292D01*
G02X111494Y1583667I-1J-203D01*
G01Y1583047D01*
G03X111544Y1582915I200J0D01*
G02Y1579999I-1661J-1458D01*
G03X111494Y1579867I150J-132D01*
G01Y1577929D01*
G03X111544Y1577797I200J0D01*
G02Y1574881I-1661J-1458D01*
G03X111494Y1574749I150J-132D01*
G01Y1574129D01*
G02X111292Y1573926I-202J-1D01*
G01X108472D01*
G02X108270Y1574129I1J203D01*
G01Y1574749D01*
G03X108220Y1574881I-200J0D01*
G02Y1577797I1661J1458D01*
G03X108270Y1577929I-150J132D01*
G01Y1579867D01*
G03X108220Y1579999I-200J0D01*
G02Y1582915I1661J1458D01*
G03X108270Y1583047I-150J132D01*
G01Y1583667D01*
G02X108472Y1583870I202J1D01*
G37*
G36*
G01X125795D02*
X128615D01*
G02X128818Y1583667I0J-203D01*
G01Y1583045D01*
G03X128868Y1582913I200J0D01*
G02Y1580001I-1664J-1456D01*
G03X128818Y1579869I150J-132D01*
G01Y1577927D01*
G03X128868Y1577795I200J0D01*
G02Y1574883I-1664J-1456D01*
G03X128818Y1574751I150J-132D01*
G01Y1574129D01*
G02X128615Y1573926I-203J0D01*
G01X125795D01*
G02X125592Y1574129I0J203D01*
G01Y1574751D01*
G03X125542Y1574883I-200J0D01*
G02Y1577795I1664J1456D01*
G03X125592Y1577927I-150J132D01*
G01Y1579869D01*
G03X125542Y1580001I-200J0D01*
G02Y1582913I1664J1456D01*
G03X125592Y1583045I-150J132D01*
G01Y1583667D01*
G02X125795Y1583870I203J0D01*
G37*
G36*
G01X143118D02*
X145938D01*
G02X146140Y1583667I-1J-203D01*
G01Y1583047D01*
G03X146190Y1582915I200J0D01*
G02Y1579999I-1661J-1458D01*
G03X146140Y1579867I150J-132D01*
G01Y1577929D01*
G03X146190Y1577797I200J0D01*
G02Y1574881I-1661J-1458D01*
G03X146140Y1574749I150J-132D01*
G01Y1574129D01*
G02X145938Y1573926I-202J-1D01*
G01X143118D01*
G02X142916Y1574129I1J203D01*
G01Y1574749D01*
G03X142866Y1574881I-200J0D01*
G02Y1577797I1661J1458D01*
G03X142916Y1577929I-150J132D01*
G01Y1579867D01*
G03X142866Y1579999I-200J0D01*
G02Y1582915I1661J1458D01*
G03X142916Y1583047I-150J132D01*
G01Y1583667D01*
G02X143118Y1583870I202J1D01*
G37*
G36*
G01X160440D02*
X163260D01*
G02X163462Y1583667I-1J-203D01*
G01Y1583047D01*
G03X163512Y1582915I200J0D01*
G02Y1579999I-1661J-1458D01*
G03X163462Y1579867I150J-132D01*
G01Y1577929D01*
G03X163512Y1577797I200J0D01*
G02Y1574881I-1661J-1458D01*
G03X163462Y1574749I150J-132D01*
G01Y1574129D01*
G02X163260Y1573926I-202J-1D01*
G01X160440D01*
G02X160238Y1574129I1J203D01*
G01Y1574749D01*
G03X160188Y1574881I-200J0D01*
G02Y1577797I1661J1458D01*
G03X160238Y1577929I-150J132D01*
G01Y1579867D01*
G03X160188Y1579999I-200J0D01*
G02Y1582915I1661J1458D01*
G03X160238Y1583047I-150J132D01*
G01Y1583667D01*
G02X160440Y1583870I202J1D01*
G37*
G36*
G01X281700D02*
X284520D01*
G02X284722Y1583667I-1J-203D01*
G01Y1583047D01*
G03X284772Y1582915I200J0D01*
G02Y1579999I-1661J-1458D01*
G03X284722Y1579867I150J-132D01*
G01Y1577929D01*
G03X284772Y1577797I200J0D01*
G02Y1574881I-1661J-1458D01*
G03X284722Y1574749I150J-132D01*
G01Y1574129D01*
G02X284520Y1573926I-202J-1D01*
G01X281700D01*
G02X281498Y1574129I1J203D01*
G01Y1574749D01*
G03X281448Y1574881I-200J0D01*
G02Y1577797I1661J1458D01*
G03X281498Y1577929I-150J132D01*
G01Y1579867D01*
G03X281448Y1579999I-200J0D01*
G02Y1582915I1661J1458D01*
G03X281498Y1583047I-150J132D01*
G01Y1583667D01*
G02X281700Y1583870I202J1D01*
G37*
G36*
G01X299023D02*
X301843D01*
G02X302046Y1583667I0J-203D01*
G01Y1583045D01*
G03X302096Y1582913I200J0D01*
G02Y1580001I-1664J-1456D01*
G03X302046Y1579869I150J-132D01*
G01Y1577927D01*
G03X302096Y1577795I200J0D01*
G02Y1574883I-1664J-1456D01*
G03X302046Y1574751I150J-132D01*
G01Y1574129D01*
G02X301843Y1573926I-203J0D01*
G01X299023D01*
G02X298820Y1574129I0J203D01*
G01Y1574751D01*
G03X298770Y1574883I-200J0D01*
G02Y1577795I1664J1456D01*
G03X298820Y1577927I-150J132D01*
G01Y1579869D01*
G03X298770Y1580001I-200J0D01*
G02Y1582913I1664J1456D01*
G03X298820Y1583045I-150J132D01*
G01Y1583667D01*
G02X299023Y1583870I203J0D01*
G37*
G36*
G01X316346D02*
X319166D01*
G02X319368Y1583667I-1J-203D01*
G01Y1583047D01*
G03X319418Y1582915I200J0D01*
G02Y1579999I-1661J-1458D01*
G03X319368Y1579867I150J-132D01*
G01Y1577929D01*
G03X319418Y1577797I200J0D01*
G02Y1574881I-1661J-1458D01*
G03X319368Y1574749I150J-132D01*
G01Y1574129D01*
G02X319166Y1573926I-202J-1D01*
G01X316346D01*
G02X316144Y1574129I1J203D01*
G01Y1574749D01*
G03X316094Y1574881I-200J0D01*
G02Y1577797I1661J1458D01*
G03X316144Y1577929I-150J132D01*
G01Y1579867D01*
G03X316094Y1579999I-200J0D01*
G02Y1582915I1661J1458D01*
G03X316144Y1583047I-150J132D01*
G01Y1583667D01*
G02X316346Y1583870I202J1D01*
G37*
G36*
G01X333668D02*
X336488D01*
G02X336690Y1583667I-1J-203D01*
G01Y1583047D01*
G03X336740Y1582915I200J0D01*
G02Y1579999I-1661J-1458D01*
G03X336690Y1579867I150J-132D01*
G01Y1577929D01*
G03X336740Y1577797I200J0D01*
G02Y1574881I-1661J-1458D01*
G03X336690Y1574749I150J-132D01*
G01Y1574129D01*
G02X336488Y1573926I-202J-1D01*
G01X333668D01*
G02X333466Y1574129I1J203D01*
G01Y1574749D01*
G03X333416Y1574881I-200J0D01*
G02Y1577797I1661J1458D01*
G03X333466Y1577929I-150J132D01*
G01Y1579867D01*
G03X333416Y1579999I-200J0D01*
G02Y1582915I1661J1458D01*
G03X333466Y1583047I-150J132D01*
G01Y1583667D01*
G02X333668Y1583870I202J1D01*
G37*
G36*
G01X628157D02*
X630977D01*
G02X631180Y1583667I0J-203D01*
G01Y1583045D01*
G03X631230Y1582913I200J0D01*
G02Y1580001I-1664J-1456D01*
G03X631180Y1579869I150J-132D01*
G01Y1577927D01*
G03X631230Y1577795I200J0D01*
G02Y1574883I-1664J-1456D01*
G03X631180Y1574751I150J-132D01*
G01Y1574129D01*
G02X630977Y1573926I-203J0D01*
G01X628157D01*
G02X627954Y1574129I0J203D01*
G01Y1574751D01*
G03X627904Y1574883I-200J0D01*
G02Y1577795I1664J1456D01*
G03X627954Y1577927I-150J132D01*
G01Y1579869D01*
G03X627904Y1580001I-200J0D01*
G02Y1582913I1664J1456D01*
G03X627954Y1583045I-150J132D01*
G01Y1583667D01*
G02X628157Y1583870I203J0D01*
G37*
G36*
G01X645480D02*
X648300D01*
G02X648502Y1583667I-1J-203D01*
G01Y1583047D01*
G03X648552Y1582915I200J0D01*
G02Y1579999I-1661J-1458D01*
G03X648502Y1579867I150J-132D01*
G01Y1577929D01*
G03X648552Y1577797I200J0D01*
G02Y1574881I-1661J-1458D01*
G03X648502Y1574749I150J-132D01*
G01Y1574129D01*
G02X648300Y1573926I-202J-1D01*
G01X645480D01*
G02X645278Y1574129I1J203D01*
G01Y1574749D01*
G03X645228Y1574881I-200J0D01*
G02Y1577797I1661J1458D01*
G03X645278Y1577929I-150J132D01*
G01Y1579867D01*
G03X645228Y1579999I-200J0D01*
G02Y1582915I1661J1458D01*
G03X645278Y1583047I-150J132D01*
G01Y1583667D01*
G02X645480Y1583870I202J1D01*
G37*
G36*
G01X662803D02*
X665623D01*
G02X665826Y1583667I0J-203D01*
G01Y1583045D01*
G03X665876Y1582913I200J0D01*
G02Y1580001I-1664J-1456D01*
G03X665826Y1579869I150J-132D01*
G01Y1577927D01*
G03X665876Y1577795I200J0D01*
G02Y1574883I-1664J-1456D01*
G03X665826Y1574751I150J-132D01*
G01Y1574129D01*
G02X665623Y1573926I-203J0D01*
G01X662803D01*
G02X662600Y1574129I0J203D01*
G01Y1574751D01*
G03X662550Y1574883I-200J0D01*
G02Y1577795I1664J1456D01*
G03X662600Y1577927I-150J132D01*
G01Y1579869D01*
G03X662550Y1580001I-200J0D01*
G02Y1582913I1664J1456D01*
G03X662600Y1583045I-150J132D01*
G01Y1583667D01*
G02X662803Y1583870I203J0D01*
G37*
G36*
G01X680125D02*
X682945D01*
G02X683148Y1583667I0J-203D01*
G01Y1583045D01*
G03X683198Y1582913I200J0D01*
G02Y1580001I-1664J-1456D01*
G03X683148Y1579869I150J-132D01*
G01Y1577927D01*
G03X683198Y1577795I200J0D01*
G02Y1574883I-1664J-1456D01*
G03X683148Y1574751I150J-132D01*
G01Y1574129D01*
G02X682945Y1573926I-203J0D01*
G01X680125D01*
G02X679922Y1574129I0J203D01*
G01Y1574751D01*
G03X679872Y1574883I-200J0D01*
G02Y1577795I1664J1456D01*
G03X679922Y1577927I-150J132D01*
G01Y1579869D01*
G03X679872Y1580001I-200J0D01*
G02Y1582913I1664J1456D01*
G03X679922Y1583045I-150J132D01*
G01Y1583667D01*
G02X680125Y1583870I203J0D01*
G37*
G36*
G01X1130440D02*
X1133260D01*
G02X1133462Y1583667I-1J-203D01*
G01Y1583047D01*
G03X1133512Y1582915I200J0D01*
G02Y1579999I-1661J-1458D01*
G03X1133462Y1579867I150J-132D01*
G01Y1577929D01*
G03X1133512Y1577797I200J0D01*
G02Y1574881I-1661J-1458D01*
G03X1133462Y1574749I150J-132D01*
G01Y1574129D01*
G02X1133260Y1573926I-202J-1D01*
G01X1130440D01*
G02X1130238Y1574129I1J203D01*
G01Y1574749D01*
G03X1130188Y1574881I-200J0D01*
G02Y1577797I1661J1458D01*
G03X1130238Y1577929I-150J132D01*
G01Y1579867D01*
G03X1130188Y1579999I-200J0D01*
G02Y1582915I1661J1458D01*
G03X1130238Y1583047I-150J132D01*
G01Y1583667D01*
G02X1130440Y1583870I202J1D01*
G37*
G36*
G01X1147763D02*
X1150583D01*
G02X1150786Y1583667I0J-203D01*
G01Y1583045D01*
G03X1150836Y1582913I200J0D01*
G02Y1580001I-1664J-1456D01*
G03X1150786Y1579869I150J-132D01*
G01Y1577927D01*
G03X1150836Y1577795I200J0D01*
G02Y1574883I-1664J-1456D01*
G03X1150786Y1574751I150J-132D01*
G01Y1574129D01*
G02X1150583Y1573926I-203J0D01*
G01X1147763D01*
G02X1147560Y1574129I0J203D01*
G01Y1574751D01*
G03X1147510Y1574883I-200J0D01*
G02Y1577795I1664J1456D01*
G03X1147560Y1577927I-150J132D01*
G01Y1579869D01*
G03X1147510Y1580001I-200J0D01*
G02Y1582913I1664J1456D01*
G03X1147560Y1583045I-150J132D01*
G01Y1583667D01*
G02X1147763Y1583870I203J0D01*
G37*
G36*
G01X1165086D02*
X1167906D01*
G02X1168108Y1583667I-1J-203D01*
G01Y1583047D01*
G03X1168158Y1582915I200J0D01*
G02Y1579999I-1661J-1458D01*
G03X1168108Y1579867I150J-132D01*
G01Y1577929D01*
G03X1168158Y1577797I200J0D01*
G02Y1574881I-1661J-1458D01*
G03X1168108Y1574749I150J-132D01*
G01Y1574129D01*
G02X1167906Y1573926I-202J-1D01*
G01X1165086D01*
G02X1164884Y1574129I1J203D01*
G01Y1574749D01*
G03X1164834Y1574881I-200J0D01*
G02Y1577797I1661J1458D01*
G03X1164884Y1577929I-150J132D01*
G01Y1579867D01*
G03X1164834Y1579999I-200J0D01*
G02Y1582915I1661J1458D01*
G03X1164884Y1583047I-150J132D01*
G01Y1583667D01*
G02X1165086Y1583870I202J1D01*
G37*
G36*
G01X1182408D02*
X1185228D01*
G02X1185430Y1583667I-1J-203D01*
G01Y1583047D01*
G03X1185480Y1582915I200J0D01*
G02Y1579999I-1661J-1458D01*
G03X1185430Y1579867I150J-132D01*
G01Y1577929D01*
G03X1185480Y1577797I200J0D01*
G02Y1574881I-1661J-1458D01*
G03X1185430Y1574749I150J-132D01*
G01Y1574129D01*
G02X1185228Y1573926I-202J-1D01*
G01X1182408D01*
G02X1182206Y1574129I1J203D01*
G01Y1574749D01*
G03X1182156Y1574881I-200J0D01*
G02Y1577797I1661J1458D01*
G03X1182206Y1577929I-150J132D01*
G01Y1579867D01*
G03X1182156Y1579999I-200J0D01*
G02Y1582915I1661J1458D01*
G03X1182206Y1583047I-150J132D01*
G01Y1583667D01*
G02X1182408Y1583870I202J1D01*
G37*
G36*
G01X1303669D02*
X1306489D01*
G02X1306692Y1583667I0J-203D01*
G01Y1583045D01*
G03X1306742Y1582913I200J0D01*
G02Y1580001I-1664J-1456D01*
G03X1306692Y1579869I150J-132D01*
G01Y1577927D01*
G03X1306742Y1577795I200J0D01*
G02Y1574883I-1664J-1456D01*
G03X1306692Y1574751I150J-132D01*
G01Y1574129D01*
G02X1306489Y1573926I-203J0D01*
G01X1303669D01*
G02X1303466Y1574129I0J203D01*
G01Y1574751D01*
G03X1303416Y1574883I-200J0D01*
G02Y1577795I1664J1456D01*
G03X1303466Y1577927I-150J132D01*
G01Y1579869D01*
G03X1303416Y1580001I-200J0D01*
G02Y1582913I1664J1456D01*
G03X1303466Y1583045I-150J132D01*
G01Y1583667D01*
G02X1303669Y1583870I203J0D01*
G37*
G36*
G01X1320992D02*
X1323812D01*
G02X1324014Y1583667I-1J-203D01*
G01Y1583047D01*
G03X1324064Y1582915I200J0D01*
G02Y1579999I-1661J-1458D01*
G03X1324014Y1579867I150J-132D01*
G01Y1577929D01*
G03X1324064Y1577797I200J0D01*
G02Y1574881I-1661J-1458D01*
G03X1324014Y1574749I150J-132D01*
G01Y1574129D01*
G02X1323812Y1573926I-202J-1D01*
G01X1320992D01*
G02X1320790Y1574129I1J203D01*
G01Y1574749D01*
G03X1320740Y1574881I-200J0D01*
G02Y1577797I1661J1458D01*
G03X1320790Y1577929I-150J132D01*
G01Y1579867D01*
G03X1320740Y1579999I-200J0D01*
G02Y1582915I1661J1458D01*
G03X1320790Y1583047I-150J132D01*
G01Y1583667D01*
G02X1320992Y1583870I202J1D01*
G37*
G36*
G01X1338315D02*
X1341135D01*
G02X1341338Y1583667I0J-203D01*
G01Y1583045D01*
G03X1341388Y1582913I200J0D01*
G02Y1580001I-1664J-1456D01*
G03X1341338Y1579869I150J-132D01*
G01Y1577927D01*
G03X1341388Y1577795I200J0D01*
G02Y1574883I-1664J-1456D01*
G03X1341338Y1574751I150J-132D01*
G01Y1574129D01*
G02X1341135Y1573926I-203J0D01*
G01X1338315D01*
G02X1338112Y1574129I0J203D01*
G01Y1574751D01*
G03X1338062Y1574883I-200J0D01*
G02Y1577795I1664J1456D01*
G03X1338112Y1577927I-150J132D01*
G01Y1579869D01*
G03X1338062Y1580001I-200J0D01*
G02Y1582913I1664J1456D01*
G03X1338112Y1583045I-150J132D01*
G01Y1583667D01*
G02X1338315Y1583870I203J0D01*
G37*
G36*
G01X1355637D02*
X1358457D01*
G02X1358660Y1583667I0J-203D01*
G01Y1583045D01*
G03X1358710Y1582913I200J0D01*
G02Y1580001I-1664J-1456D01*
G03X1358660Y1579869I150J-132D01*
G01Y1577927D01*
G03X1358710Y1577795I200J0D01*
G02Y1574883I-1664J-1456D01*
G03X1358660Y1574751I150J-132D01*
G01Y1574129D01*
G02X1358457Y1573926I-203J0D01*
G01X1355637D01*
G02X1355434Y1574129I0J203D01*
G01Y1574751D01*
G03X1355384Y1574883I-200J0D01*
G02Y1577795I1664J1456D01*
G03X1355434Y1577927I-150J132D01*
G01Y1579869D01*
G03X1355384Y1580001I-200J0D01*
G02Y1582913I1664J1456D01*
G03X1355434Y1583045I-150J132D01*
G01Y1583667D01*
G02X1355637Y1583870I203J0D01*
G37*
G36*
G01X1476897D02*
X1479717D01*
G02X1479920Y1583667I0J-203D01*
G01Y1583045D01*
G03X1479970Y1582913I200J0D01*
G02Y1580001I-1664J-1456D01*
G03X1479920Y1579869I150J-132D01*
G01Y1577927D01*
G03X1479970Y1577795I200J0D01*
G02Y1574883I-1664J-1456D01*
G03X1479920Y1574751I150J-132D01*
G01Y1574129D01*
G02X1479717Y1573926I-203J0D01*
G01X1476897D01*
G02X1476694Y1574129I0J203D01*
G01Y1574751D01*
G03X1476644Y1574883I-200J0D01*
G02Y1577795I1664J1456D01*
G03X1476694Y1577927I-150J132D01*
G01Y1579869D01*
G03X1476644Y1580001I-200J0D01*
G02Y1582913I1664J1456D01*
G03X1476694Y1583045I-150J132D01*
G01Y1583667D01*
G02X1476897Y1583870I203J0D01*
G37*
G36*
G01X1650125D02*
X1652945D01*
G02X1653148Y1583667I0J-203D01*
G01Y1583045D01*
G03X1653198Y1582913I200J0D01*
G02Y1580001I-1664J-1456D01*
G03X1653148Y1579869I150J-132D01*
G01Y1577927D01*
G03X1653198Y1577795I200J0D01*
G02Y1574883I-1664J-1456D01*
G03X1653148Y1574751I150J-132D01*
G01Y1574129D01*
G02X1652945Y1573926I-203J0D01*
G01X1650125D01*
G02X1649922Y1574129I0J203D01*
G01Y1574751D01*
G03X1649872Y1574883I-200J0D01*
G02Y1577795I1664J1456D01*
G03X1649922Y1577927I-150J132D01*
G01Y1579869D01*
G03X1649872Y1580001I-200J0D01*
G02Y1582913I1664J1456D01*
G03X1649922Y1583045I-150J132D01*
G01Y1583667D01*
G02X1650125Y1583870I203J0D01*
G37*
G36*
G01X1667448D02*
X1670268D01*
G02X1670470Y1583667I-1J-203D01*
G01Y1583047D01*
G03X1670520Y1582915I200J0D01*
G02Y1579999I-1661J-1458D01*
G03X1670470Y1579867I150J-132D01*
G01Y1577929D01*
G03X1670520Y1577797I200J0D01*
G02Y1574881I-1661J-1458D01*
G03X1670470Y1574749I150J-132D01*
G01Y1574129D01*
G02X1670268Y1573926I-202J-1D01*
G01X1667448D01*
G02X1667246Y1574129I1J203D01*
G01Y1574749D01*
G03X1667196Y1574881I-200J0D01*
G02Y1577797I1661J1458D01*
G03X1667246Y1577929I-150J132D01*
G01Y1579867D01*
G03X1667196Y1579999I-200J0D01*
G02Y1582915I1661J1458D01*
G03X1667246Y1583047I-150J132D01*
G01Y1583667D01*
G02X1667448Y1583870I202J1D01*
G37*
G36*
G01X1684771D02*
X1687591D01*
G02X1687794Y1583667I0J-203D01*
G01Y1583045D01*
G03X1687844Y1582913I200J0D01*
G02Y1580001I-1664J-1456D01*
G03X1687794Y1579869I150J-132D01*
G01Y1577927D01*
G03X1687844Y1577795I200J0D01*
G02Y1574883I-1664J-1456D01*
G03X1687794Y1574751I150J-132D01*
G01Y1574129D01*
G02X1687591Y1573926I-203J0D01*
G01X1684771D01*
G02X1684568Y1574129I0J203D01*
G01Y1574751D01*
G03X1684518Y1574883I-200J0D01*
G02Y1577795I1664J1456D01*
G03X1684568Y1577927I-150J132D01*
G01Y1579869D01*
G03X1684518Y1580001I-200J0D01*
G02Y1582913I1664J1456D01*
G03X1684568Y1583045I-150J132D01*
G01Y1583667D01*
G02X1684771Y1583870I203J0D01*
G37*
G36*
G01X1702093D02*
X1704913D01*
G02X1705116Y1583667I0J-203D01*
G01Y1583045D01*
G03X1705166Y1582913I200J0D01*
G02Y1580001I-1664J-1456D01*
G03X1705116Y1579869I150J-132D01*
G01Y1577927D01*
G03X1705166Y1577795I200J0D01*
G02Y1574883I-1664J-1456D01*
G03X1705116Y1574751I150J-132D01*
G01Y1574129D01*
G02X1704913Y1573926I-203J0D01*
G01X1702093D01*
G02X1701890Y1574129I0J203D01*
G01Y1574751D01*
G03X1701840Y1574883I-200J0D01*
G02Y1577795I1664J1456D01*
G03X1701890Y1577927I-150J132D01*
G01Y1579869D01*
G03X1701840Y1580001I-200J0D01*
G02Y1582913I1664J1456D01*
G03X1701890Y1583045I-150J132D01*
G01Y1583667D01*
G02X1702093Y1583870I203J0D01*
G37*
G36*
G01X134456Y1588200D02*
X137276D01*
G02X137478Y1587998I0J-202D01*
G01Y1587378D01*
G03X137528Y1587246I200J0D01*
G02Y1584330I-1661J-1458D01*
G03X137478Y1584198I150J-132D01*
G01Y1582260D01*
G03X137528Y1582128I200J0D01*
G02Y1579212I-1661J-1458D01*
G03X137478Y1579080I150J-132D01*
G01Y1578460D01*
G02X137276Y1578258I-202J0D01*
G01X134456D01*
G02X134254Y1578460I0J202D01*
G01Y1579080D01*
G03X134204Y1579212I-200J0D01*
G02Y1582128I1661J1458D01*
G03X134254Y1582260I-150J132D01*
G01Y1584198D01*
G03X134204Y1584330I-200J0D01*
G02Y1587246I1661J1458D01*
G03X134254Y1587378I-150J132D01*
G01Y1587998D01*
G02X134456Y1588200I202J0D01*
G37*
G36*
G01X169102D02*
X171922D01*
G02X172124Y1587998I0J-202D01*
G01Y1587378D01*
G03X172174Y1587246I200J0D01*
G02Y1584330I-1661J-1458D01*
G03X172124Y1584198I150J-132D01*
G01Y1582260D01*
G03X172174Y1582128I200J0D01*
G02Y1579212I-1661J-1458D01*
G03X172124Y1579080I150J-132D01*
G01Y1578460D01*
G02X171922Y1578258I-202J0D01*
G01X169102D01*
G02X168900Y1578460I0J202D01*
G01Y1579080D01*
G03X168850Y1579212I-200J0D01*
G02Y1582128I1661J1458D01*
G03X168900Y1582260I-150J132D01*
G01Y1584198D01*
G03X168850Y1584330I-200J0D01*
G02Y1587246I1661J1458D01*
G03X168900Y1587378I-150J132D01*
G01Y1587998D01*
G02X169102Y1588200I202J0D01*
G37*
G36*
G01X307684D02*
X310504D01*
G02X310706Y1587998I0J-202D01*
G01Y1587378D01*
G03X310756Y1587246I200J0D01*
G02Y1584330I-1661J-1458D01*
G03X310706Y1584198I150J-132D01*
G01Y1582260D01*
G03X310756Y1582128I200J0D01*
G02Y1579212I-1661J-1458D01*
G03X310706Y1579080I150J-132D01*
G01Y1578460D01*
G02X310504Y1578258I-202J0D01*
G01X307684D01*
G02X307482Y1578460I0J202D01*
G01Y1579080D01*
G03X307432Y1579212I-200J0D01*
G02Y1582128I1661J1458D01*
G03X307482Y1582260I-150J132D01*
G01Y1584198D01*
G03X307432Y1584330I-200J0D01*
G02Y1587246I1661J1458D01*
G03X307482Y1587378I-150J132D01*
G01Y1587998D01*
G02X307684Y1588200I202J0D01*
G37*
G36*
G01X342330D02*
X345150D01*
G02X345352Y1587998I0J-202D01*
G01Y1587378D01*
G03X345402Y1587246I200J0D01*
G02Y1584330I-1661J-1458D01*
G03X345352Y1584198I150J-132D01*
G01Y1582260D01*
G03X345402Y1582128I200J0D01*
G02Y1579212I-1661J-1458D01*
G03X345352Y1579080I150J-132D01*
G01Y1578460D01*
G02X345150Y1578258I-202J0D01*
G01X342330D01*
G02X342128Y1578460I0J202D01*
G01Y1579080D01*
G03X342078Y1579212I-200J0D01*
G02Y1582128I1661J1458D01*
G03X342128Y1582260I-150J132D01*
G01Y1584198D01*
G03X342078Y1584330I-200J0D01*
G02Y1587246I1661J1458D01*
G03X342128Y1587378I-150J132D01*
G01Y1587998D01*
G02X342330Y1588200I202J0D01*
G37*
G36*
G01X636818D02*
X639638D01*
G02X639840Y1587998I0J-202D01*
G01Y1587378D01*
G03X639890Y1587246I200J0D01*
G02Y1584330I-1661J-1458D01*
G03X639840Y1584198I150J-132D01*
G01Y1582260D01*
G03X639890Y1582128I200J0D01*
G02Y1579212I-1661J-1458D01*
G03X639840Y1579080I150J-132D01*
G01Y1578460D01*
G02X639638Y1578258I-202J0D01*
G01X636818D01*
G02X636616Y1578460I0J202D01*
G01Y1579080D01*
G03X636566Y1579212I-200J0D01*
G02Y1582128I1661J1458D01*
G03X636616Y1582260I-150J132D01*
G01Y1584198D01*
G03X636566Y1584330I-200J0D01*
G02Y1587246I1661J1458D01*
G03X636616Y1587378I-150J132D01*
G01Y1587998D01*
G02X636818Y1588200I202J0D01*
G37*
G36*
G01X671464D02*
X674284D01*
G02X674486Y1587998I0J-202D01*
G01Y1587378D01*
G03X674536Y1587246I200J0D01*
G02Y1584330I-1661J-1458D01*
G03X674486Y1584198I150J-132D01*
G01Y1582260D01*
G03X674536Y1582128I200J0D01*
G02Y1579212I-1661J-1458D01*
G03X674486Y1579080I150J-132D01*
G01Y1578460D01*
G02X674284Y1578258I-202J0D01*
G01X671464D01*
G02X671262Y1578460I0J202D01*
G01Y1579080D01*
G03X671212Y1579212I-200J0D01*
G02Y1582128I1661J1458D01*
G03X671262Y1582260I-150J132D01*
G01Y1584198D01*
G03X671212Y1584330I-200J0D01*
G02Y1587246I1661J1458D01*
G03X671262Y1587378I-150J132D01*
G01Y1587998D01*
G02X671464Y1588200I202J0D01*
G37*
G36*
G01X1156424D02*
X1159244D01*
G02X1159446Y1587998I0J-202D01*
G01Y1587378D01*
G03X1159496Y1587246I200J0D01*
G02Y1584330I-1661J-1458D01*
G03X1159446Y1584198I150J-132D01*
G01Y1582260D01*
G03X1159496Y1582128I200J0D01*
G02Y1579212I-1661J-1458D01*
G03X1159446Y1579080I150J-132D01*
G01Y1578460D01*
G02X1159244Y1578258I-202J0D01*
G01X1156424D01*
G02X1156222Y1578460I0J202D01*
G01Y1579080D01*
G03X1156172Y1579212I-200J0D01*
G02Y1582128I1661J1458D01*
G03X1156222Y1582260I-150J132D01*
G01Y1584198D01*
G03X1156172Y1584330I-200J0D01*
G02Y1587246I1661J1458D01*
G03X1156222Y1587378I-150J132D01*
G01Y1587998D01*
G02X1156424Y1588200I202J0D01*
G37*
G36*
G01X1191070D02*
X1193890D01*
G02X1194092Y1587998I0J-202D01*
G01Y1587378D01*
G03X1194142Y1587246I200J0D01*
G02Y1584330I-1661J-1458D01*
G03X1194092Y1584198I150J-132D01*
G01Y1582260D01*
G03X1194142Y1582128I200J0D01*
G02Y1579212I-1661J-1458D01*
G03X1194092Y1579080I150J-132D01*
G01Y1578460D01*
G02X1193890Y1578258I-202J0D01*
G01X1191070D01*
G02X1190868Y1578460I0J202D01*
G01Y1579080D01*
G03X1190818Y1579212I-200J0D01*
G02Y1582128I1661J1458D01*
G03X1190868Y1582260I-150J132D01*
G01Y1584198D01*
G03X1190818Y1584330I-200J0D01*
G02Y1587246I1661J1458D01*
G03X1190868Y1587378I-150J132D01*
G01Y1587998D01*
G02X1191070Y1588200I202J0D01*
G37*
G36*
G01X1312330D02*
X1315150D01*
G02X1315352Y1587998I0J-202D01*
G01Y1587378D01*
G03X1315402Y1587246I200J0D01*
G02Y1584330I-1661J-1458D01*
G03X1315352Y1584198I150J-132D01*
G01Y1582260D01*
G03X1315402Y1582128I200J0D01*
G02Y1579212I-1661J-1458D01*
G03X1315352Y1579080I150J-132D01*
G01Y1578460D01*
G02X1315150Y1578258I-202J0D01*
G01X1312330D01*
G02X1312128Y1578460I0J202D01*
G01Y1579080D01*
G03X1312078Y1579212I-200J0D01*
G02Y1582128I1661J1458D01*
G03X1312128Y1582260I-150J132D01*
G01Y1584198D01*
G03X1312078Y1584330I-200J0D01*
G02Y1587246I1661J1458D01*
G03X1312128Y1587378I-150J132D01*
G01Y1587998D01*
G02X1312330Y1588200I202J0D01*
G37*
G36*
G01X1346976D02*
X1349796D01*
G02X1349998Y1587998I0J-202D01*
G01Y1587378D01*
G03X1350048Y1587246I200J0D01*
G02Y1584330I-1661J-1458D01*
G03X1349998Y1584198I150J-132D01*
G01Y1582260D01*
G03X1350048Y1582128I200J0D01*
G02Y1579212I-1661J-1458D01*
G03X1349998Y1579080I150J-132D01*
G01Y1578460D01*
G02X1349796Y1578258I-202J0D01*
G01X1346976D01*
G02X1346774Y1578460I0J202D01*
G01Y1579080D01*
G03X1346724Y1579212I-200J0D01*
G02Y1582128I1661J1458D01*
G03X1346774Y1582260I-150J132D01*
G01Y1584198D01*
G03X1346724Y1584330I-200J0D01*
G02Y1587246I1661J1458D01*
G03X1346774Y1587378I-150J132D01*
G01Y1587998D01*
G02X1346976Y1588200I202J0D01*
G37*
G36*
G01X1658786D02*
X1661606D01*
G02X1661808Y1587998I0J-202D01*
G01Y1587378D01*
G03X1661858Y1587246I200J0D01*
G02Y1584330I-1661J-1458D01*
G03X1661808Y1584198I150J-132D01*
G01Y1582260D01*
G03X1661858Y1582128I200J0D01*
G02Y1579212I-1661J-1458D01*
G03X1661808Y1579080I150J-132D01*
G01Y1578460D01*
G02X1661606Y1578258I-202J0D01*
G01X1658786D01*
G02X1658584Y1578460I0J202D01*
G01Y1579080D01*
G03X1658534Y1579212I-200J0D01*
G02Y1582128I1661J1458D01*
G03X1658584Y1582260I-150J132D01*
G01Y1584198D01*
G03X1658534Y1584330I-200J0D01*
G02Y1587246I1661J1458D01*
G03X1658584Y1587378I-150J132D01*
G01Y1587998D01*
G02X1658786Y1588200I202J0D01*
G37*
G36*
G01X1693432D02*
X1696252D01*
G02X1696454Y1587998I0J-202D01*
G01Y1587378D01*
G03X1696504Y1587246I200J0D01*
G02Y1584330I-1661J-1458D01*
G03X1696454Y1584198I150J-132D01*
G01Y1582260D01*
G03X1696504Y1582128I200J0D01*
G02Y1579212I-1661J-1458D01*
G03X1696454Y1579080I150J-132D01*
G01Y1578460D01*
G02X1696252Y1578258I-202J0D01*
G01X1693432D01*
G02X1693230Y1578460I0J202D01*
G01Y1579080D01*
G03X1693180Y1579212I-200J0D01*
G02Y1582128I1661J1458D01*
G03X1693230Y1582260I-150J132D01*
G01Y1584198D01*
G03X1693180Y1584330I-200J0D01*
G02Y1587246I1661J1458D01*
G03X1693230Y1587378I-150J132D01*
G01Y1587998D01*
G02X1693432Y1588200I202J0D01*
G37*
G36*
G01X117133D02*
X119953D01*
G02X120156Y1587998I1J-202D01*
G01Y1587376D01*
G03X120206Y1587244I200J0D01*
G02Y1584332I-1664J-1456D01*
G03X120156Y1584200I150J-132D01*
G01Y1582258D01*
G03X120206Y1582126I200J0D01*
G02Y1579214I-1664J-1456D01*
G03X120156Y1579082I150J-132D01*
G01Y1578460D01*
G02X119953Y1578258I-203J1D01*
G01X117133D01*
G02X116930Y1578460I-1J202D01*
G01Y1579082D01*
G03X116880Y1579214I-200J0D01*
G02Y1582126I1664J1456D01*
G03X116930Y1582258I-150J132D01*
G01Y1584200D01*
G03X116880Y1584332I-200J0D01*
G02Y1587244I1664J1456D01*
G03X116930Y1587376I-150J132D01*
G01Y1587998D01*
G02X117133Y1588200I203J-1D01*
G37*
G36*
G01X151779D02*
X154599D01*
G02X154802Y1587998I1J-202D01*
G01Y1587376D01*
G03X154852Y1587244I200J0D01*
G02Y1584332I-1664J-1456D01*
G03X154802Y1584200I150J-132D01*
G01Y1582258D01*
G03X154852Y1582126I200J0D01*
G02Y1579214I-1664J-1456D01*
G03X154802Y1579082I150J-132D01*
G01Y1578460D01*
G02X154599Y1578258I-203J1D01*
G01X151779D01*
G02X151576Y1578460I-1J202D01*
G01Y1579082D01*
G03X151526Y1579214I-200J0D01*
G02Y1582126I1664J1456D01*
G03X151576Y1582258I-150J132D01*
G01Y1584200D01*
G03X151526Y1584332I-200J0D01*
G02Y1587244I1664J1456D01*
G03X151576Y1587376I-150J132D01*
G01Y1587998D01*
G02X151779Y1588200I203J-1D01*
G37*
G36*
G01X290361D02*
X293181D01*
G02X293384Y1587998I1J-202D01*
G01Y1587376D01*
G03X293434Y1587244I200J0D01*
G02Y1584332I-1664J-1456D01*
G03X293384Y1584200I150J-132D01*
G01Y1582258D01*
G03X293434Y1582126I200J0D01*
G02Y1579214I-1664J-1456D01*
G03X293384Y1579082I150J-132D01*
G01Y1578460D01*
G02X293181Y1578258I-203J1D01*
G01X290361D01*
G02X290158Y1578460I-1J202D01*
G01Y1579082D01*
G03X290108Y1579214I-200J0D01*
G02Y1582126I1664J1456D01*
G03X290158Y1582258I-150J132D01*
G01Y1584200D01*
G03X290108Y1584332I-200J0D01*
G02Y1587244I1664J1456D01*
G03X290158Y1587376I-150J132D01*
G01Y1587998D01*
G02X290361Y1588200I203J-1D01*
G37*
G36*
G01X325007D02*
X327827D01*
G02X328030Y1587998I1J-202D01*
G01Y1587376D01*
G03X328080Y1587244I200J0D01*
G02Y1584332I-1664J-1456D01*
G03X328030Y1584200I150J-132D01*
G01Y1582258D01*
G03X328080Y1582126I200J0D01*
G02Y1579214I-1664J-1456D01*
G03X328030Y1579082I150J-132D01*
G01Y1578460D01*
G02X327827Y1578258I-203J1D01*
G01X325007D01*
G02X324804Y1578460I-1J202D01*
G01Y1579082D01*
G03X324754Y1579214I-200J0D01*
G02Y1582126I1664J1456D01*
G03X324804Y1582258I-150J132D01*
G01Y1584200D01*
G03X324754Y1584332I-200J0D01*
G02Y1587244I1664J1456D01*
G03X324804Y1587376I-150J132D01*
G01Y1587998D01*
G02X325007Y1588200I203J-1D01*
G37*
G36*
G01X515559D02*
X518379D01*
G02X518582Y1587998I1J-202D01*
G01Y1587376D01*
G03X518632Y1587244I200J0D01*
G02Y1584332I-1664J-1456D01*
G03X518582Y1584200I150J-132D01*
G01Y1582258D01*
G03X518632Y1582126I200J0D01*
G02Y1579214I-1664J-1456D01*
G03X518582Y1579082I150J-132D01*
G01Y1578460D01*
G02X518379Y1578258I-203J1D01*
G01X515559D01*
G02X515356Y1578460I-1J202D01*
G01Y1579082D01*
G03X515306Y1579214I-200J0D01*
G02Y1582126I1664J1456D01*
G03X515356Y1582258I-150J132D01*
G01Y1584200D01*
G03X515306Y1584332I-200J0D01*
G02Y1587244I1664J1456D01*
G03X515356Y1587376I-150J132D01*
G01Y1587998D01*
G02X515559Y1588200I203J-1D01*
G37*
G36*
G01X654141D02*
X656961D01*
G02X657164Y1587998I1J-202D01*
G01Y1587376D01*
G03X657214Y1587244I200J0D01*
G02Y1584332I-1664J-1456D01*
G03X657164Y1584200I150J-132D01*
G01Y1582258D01*
G03X657214Y1582126I200J0D01*
G02Y1579214I-1664J-1456D01*
G03X657164Y1579082I150J-132D01*
G01Y1578460D01*
G02X656961Y1578258I-203J1D01*
G01X654141D01*
G02X653938Y1578460I-1J202D01*
G01Y1579082D01*
G03X653888Y1579214I-200J0D01*
G02Y1582126I1664J1456D01*
G03X653938Y1582258I-150J132D01*
G01Y1584200D01*
G03X653888Y1584332I-200J0D01*
G02Y1587244I1664J1456D01*
G03X653938Y1587376I-150J132D01*
G01Y1587998D01*
G02X654141Y1588200I203J-1D01*
G37*
G36*
G01X688787D02*
X691607D01*
G02X691810Y1587998I1J-202D01*
G01Y1587376D01*
G03X691860Y1587244I200J0D01*
G02Y1584332I-1664J-1456D01*
G03X691810Y1584200I150J-132D01*
G01Y1582258D01*
G03X691860Y1582126I200J0D01*
G02Y1579214I-1664J-1456D01*
G03X691810Y1579082I150J-132D01*
G01Y1578460D01*
G02X691607Y1578258I-203J1D01*
G01X688787D01*
G02X688584Y1578460I-1J202D01*
G01Y1579082D01*
G03X688534Y1579214I-200J0D01*
G02Y1582126I1664J1456D01*
G03X688584Y1582258I-150J132D01*
G01Y1584200D01*
G03X688534Y1584332I-200J0D01*
G02Y1587244I1664J1456D01*
G03X688584Y1587376I-150J132D01*
G01Y1587998D01*
G02X688787Y1588200I203J-1D01*
G37*
G36*
G01X1139101D02*
X1141921D01*
G02X1142124Y1587998I1J-202D01*
G01Y1587376D01*
G03X1142174Y1587244I200J0D01*
G02Y1584332I-1664J-1456D01*
G03X1142124Y1584200I150J-132D01*
G01Y1582258D01*
G03X1142174Y1582126I200J0D01*
G02Y1579214I-1664J-1456D01*
G03X1142124Y1579082I150J-132D01*
G01Y1578460D01*
G02X1141921Y1578258I-203J1D01*
G01X1139101D01*
G02X1138898Y1578460I-1J202D01*
G01Y1579082D01*
G03X1138848Y1579214I-200J0D01*
G02Y1582126I1664J1456D01*
G03X1138898Y1582258I-150J132D01*
G01Y1584200D01*
G03X1138848Y1584332I-200J0D01*
G02Y1587244I1664J1456D01*
G03X1138898Y1587376I-150J132D01*
G01Y1587998D01*
G02X1139101Y1588200I203J-1D01*
G37*
G36*
G01X1173747D02*
X1176567D01*
G02X1176770Y1587998I1J-202D01*
G01Y1587376D01*
G03X1176820Y1587244I200J0D01*
G02Y1584332I-1664J-1456D01*
G03X1176770Y1584200I150J-132D01*
G01Y1582258D01*
G03X1176820Y1582126I200J0D01*
G02Y1579214I-1664J-1456D01*
G03X1176770Y1579082I150J-132D01*
G01Y1578460D01*
G02X1176567Y1578258I-203J1D01*
G01X1173747D01*
G02X1173544Y1578460I-1J202D01*
G01Y1579082D01*
G03X1173494Y1579214I-200J0D01*
G02Y1582126I1664J1456D01*
G03X1173544Y1582258I-150J132D01*
G01Y1584200D01*
G03X1173494Y1584332I-200J0D01*
G02Y1587244I1664J1456D01*
G03X1173544Y1587376I-150J132D01*
G01Y1587998D01*
G02X1173747Y1588200I203J-1D01*
G37*
G36*
G01X1329653D02*
X1332473D01*
G02X1332676Y1587998I1J-202D01*
G01Y1587376D01*
G03X1332726Y1587244I200J0D01*
G02Y1584332I-1664J-1456D01*
G03X1332676Y1584200I150J-132D01*
G01Y1582258D01*
G03X1332726Y1582126I200J0D01*
G02Y1579214I-1664J-1456D01*
G03X1332676Y1579082I150J-132D01*
G01Y1578460D01*
G02X1332473Y1578258I-203J1D01*
G01X1329653D01*
G02X1329450Y1578460I-1J202D01*
G01Y1579082D01*
G03X1329400Y1579214I-200J0D01*
G02Y1582126I1664J1456D01*
G03X1329450Y1582258I-150J132D01*
G01Y1584200D01*
G03X1329400Y1584332I-200J0D01*
G02Y1587244I1664J1456D01*
G03X1329450Y1587376I-150J132D01*
G01Y1587998D01*
G02X1329653Y1588200I203J-1D01*
G37*
G36*
G01X1364299D02*
X1367119D01*
G02X1367322Y1587998I1J-202D01*
G01Y1587376D01*
G03X1367372Y1587244I200J0D01*
G02Y1584332I-1664J-1456D01*
G03X1367322Y1584200I150J-132D01*
G01Y1582258D01*
G03X1367372Y1582126I200J0D01*
G02Y1579214I-1664J-1456D01*
G03X1367322Y1579082I150J-132D01*
G01Y1578460D01*
G02X1367119Y1578258I-203J1D01*
G01X1364299D01*
G02X1364096Y1578460I-1J202D01*
G01Y1579082D01*
G03X1364046Y1579214I-200J0D01*
G02Y1582126I1664J1456D01*
G03X1364096Y1582258I-150J132D01*
G01Y1584200D01*
G03X1364046Y1584332I-200J0D01*
G02Y1587244I1664J1456D01*
G03X1364096Y1587376I-150J132D01*
G01Y1587998D01*
G02X1364299Y1588200I203J-1D01*
G37*
G36*
G01X1676109D02*
X1678929D01*
G02X1679132Y1587998I1J-202D01*
G01Y1587376D01*
G03X1679182Y1587244I200J0D01*
G02Y1584332I-1664J-1456D01*
G03X1679132Y1584200I150J-132D01*
G01Y1582258D01*
G03X1679182Y1582126I200J0D01*
G02Y1579214I-1664J-1456D01*
G03X1679132Y1579082I150J-132D01*
G01Y1578460D01*
G02X1678929Y1578258I-203J1D01*
G01X1676109D01*
G02X1675906Y1578460I-1J202D01*
G01Y1579082D01*
G03X1675856Y1579214I-200J0D01*
G02Y1582126I1664J1456D01*
G03X1675906Y1582258I-150J132D01*
G01Y1584200D01*
G03X1675856Y1584332I-200J0D01*
G02Y1587244I1664J1456D01*
G03X1675906Y1587376I-150J132D01*
G01Y1587998D01*
G02X1676109Y1588200I203J-1D01*
G37*
G36*
G01X1710755D02*
X1713575D01*
G02X1713778Y1587998I1J-202D01*
G01Y1587376D01*
G03X1713828Y1587244I200J0D01*
G02Y1584332I-1664J-1456D01*
G03X1713778Y1584200I150J-132D01*
G01Y1582258D01*
G03X1713828Y1582126I200J0D01*
G02Y1579214I-1664J-1456D01*
G03X1713778Y1579082I150J-132D01*
G01Y1578460D01*
G02X1713575Y1578258I-203J1D01*
G01X1710755D01*
G02X1710552Y1578460I-1J202D01*
G01Y1579082D01*
G03X1710502Y1579214I-200J0D01*
G02Y1582126I1664J1456D01*
G03X1710552Y1582258I-150J132D01*
G01Y1584200D01*
G03X1710502Y1584332I-200J0D01*
G02Y1587244I1664J1456D01*
G03X1710552Y1587376I-150J132D01*
G01Y1587998D01*
G02X1710755Y1588200I203J-1D01*
G37*
G36*
G01X108472Y1599224D02*
X111292D01*
G02X111494Y1599021I-1J-203D01*
G01Y1598401D01*
G03X111544Y1598269I200J0D01*
G02Y1595353I-1661J-1458D01*
G03X111494Y1595221I150J-132D01*
G01Y1593283D01*
G03X111544Y1593151I200J0D01*
G02Y1590235I-1661J-1458D01*
G03X111494Y1590103I150J-132D01*
G01Y1589483D01*
G02X111292Y1589280I-202J-1D01*
G01X108472D01*
G02X108270Y1589483I1J203D01*
G01Y1590103D01*
G03X108220Y1590235I-200J0D01*
G02Y1593151I1661J1458D01*
G03X108270Y1593283I-150J132D01*
G01Y1595221D01*
G03X108220Y1595353I-200J0D01*
G02Y1598269I1661J1458D01*
G03X108270Y1598401I-150J132D01*
G01Y1599021D01*
G02X108472Y1599224I202J1D01*
G37*
G36*
G01X125795D02*
X128615D01*
G02X128818Y1599021I0J-203D01*
G01Y1598399D01*
G03X128868Y1598267I200J0D01*
G02Y1595355I-1664J-1456D01*
G03X128818Y1595223I150J-132D01*
G01Y1593281D01*
G03X128868Y1593149I200J0D01*
G02Y1590237I-1664J-1456D01*
G03X128818Y1590105I150J-132D01*
G01Y1589483D01*
G02X128615Y1589280I-203J0D01*
G01X125795D01*
G02X125592Y1589483I0J203D01*
G01Y1590105D01*
G03X125542Y1590237I-200J0D01*
G02Y1593149I1664J1456D01*
G03X125592Y1593281I-150J132D01*
G01Y1595223D01*
G03X125542Y1595355I-200J0D01*
G02Y1598267I1664J1456D01*
G03X125592Y1598399I-150J132D01*
G01Y1599021D01*
G02X125795Y1599224I203J0D01*
G37*
G36*
G01X143118D02*
X145938D01*
G02X146140Y1599021I-1J-203D01*
G01Y1598401D01*
G03X146190Y1598269I200J0D01*
G02Y1595353I-1661J-1458D01*
G03X146140Y1595221I150J-132D01*
G01Y1593283D01*
G03X146190Y1593151I200J0D01*
G02Y1590235I-1661J-1458D01*
G03X146140Y1590103I150J-132D01*
G01Y1589483D01*
G02X145938Y1589280I-202J-1D01*
G01X143118D01*
G02X142916Y1589483I1J203D01*
G01Y1590103D01*
G03X142866Y1590235I-200J0D01*
G02Y1593151I1661J1458D01*
G03X142916Y1593283I-150J132D01*
G01Y1595221D01*
G03X142866Y1595353I-200J0D01*
G02Y1598269I1661J1458D01*
G03X142916Y1598401I-150J132D01*
G01Y1599021D01*
G02X143118Y1599224I202J1D01*
G37*
G36*
G01X160440D02*
X163260D01*
G02X163462Y1599021I-1J-203D01*
G01Y1598401D01*
G03X163512Y1598269I200J0D01*
G02Y1595353I-1661J-1458D01*
G03X163462Y1595221I150J-132D01*
G01Y1593283D01*
G03X163512Y1593151I200J0D01*
G02Y1590235I-1661J-1458D01*
G03X163462Y1590103I150J-132D01*
G01Y1589483D01*
G02X163260Y1589280I-202J-1D01*
G01X160440D01*
G02X160238Y1589483I1J203D01*
G01Y1590103D01*
G03X160188Y1590235I-200J0D01*
G02Y1593151I1661J1458D01*
G03X160238Y1593283I-150J132D01*
G01Y1595221D01*
G03X160188Y1595353I-200J0D01*
G02Y1598269I1661J1458D01*
G03X160238Y1598401I-150J132D01*
G01Y1599021D01*
G02X160440Y1599224I202J1D01*
G37*
G36*
G01X281700D02*
X284520D01*
G02X284722Y1599021I-1J-203D01*
G01Y1598401D01*
G03X284772Y1598269I200J0D01*
G02Y1595353I-1661J-1458D01*
G03X284722Y1595221I150J-132D01*
G01Y1593283D01*
G03X284772Y1593151I200J0D01*
G02Y1590235I-1661J-1458D01*
G03X284722Y1590103I150J-132D01*
G01Y1589483D01*
G02X284520Y1589280I-202J-1D01*
G01X281700D01*
G02X281498Y1589483I1J203D01*
G01Y1590103D01*
G03X281448Y1590235I-200J0D01*
G02Y1593151I1661J1458D01*
G03X281498Y1593283I-150J132D01*
G01Y1595221D01*
G03X281448Y1595353I-200J0D01*
G02Y1598269I1661J1458D01*
G03X281498Y1598401I-150J132D01*
G01Y1599021D01*
G02X281700Y1599224I202J1D01*
G37*
G36*
G01X299023D02*
X301843D01*
G02X302046Y1599021I0J-203D01*
G01Y1598399D01*
G03X302096Y1598267I200J0D01*
G02Y1595355I-1664J-1456D01*
G03X302046Y1595223I150J-132D01*
G01Y1593281D01*
G03X302096Y1593149I200J0D01*
G02Y1590237I-1664J-1456D01*
G03X302046Y1590105I150J-132D01*
G01Y1589483D01*
G02X301843Y1589280I-203J0D01*
G01X299023D01*
G02X298820Y1589483I0J203D01*
G01Y1590105D01*
G03X298770Y1590237I-200J0D01*
G02Y1593149I1664J1456D01*
G03X298820Y1593281I-150J132D01*
G01Y1595223D01*
G03X298770Y1595355I-200J0D01*
G02Y1598267I1664J1456D01*
G03X298820Y1598399I-150J132D01*
G01Y1599021D01*
G02X299023Y1599224I203J0D01*
G37*
G36*
G01X316346D02*
X319166D01*
G02X319368Y1599021I-1J-203D01*
G01Y1598401D01*
G03X319418Y1598269I200J0D01*
G02Y1595353I-1661J-1458D01*
G03X319368Y1595221I150J-132D01*
G01Y1593283D01*
G03X319418Y1593151I200J0D01*
G02Y1590235I-1661J-1458D01*
G03X319368Y1590103I150J-132D01*
G01Y1589483D01*
G02X319166Y1589280I-202J-1D01*
G01X316346D01*
G02X316144Y1589483I1J203D01*
G01Y1590103D01*
G03X316094Y1590235I-200J0D01*
G02Y1593151I1661J1458D01*
G03X316144Y1593283I-150J132D01*
G01Y1595221D01*
G03X316094Y1595353I-200J0D01*
G02Y1598269I1661J1458D01*
G03X316144Y1598401I-150J132D01*
G01Y1599021D01*
G02X316346Y1599224I202J1D01*
G37*
G36*
G01X333668D02*
X336488D01*
G02X336690Y1599021I-1J-203D01*
G01Y1598401D01*
G03X336740Y1598269I200J0D01*
G02Y1595353I-1661J-1458D01*
G03X336690Y1595221I150J-132D01*
G01Y1593283D01*
G03X336740Y1593151I200J0D01*
G02Y1590235I-1661J-1458D01*
G03X336690Y1590103I150J-132D01*
G01Y1589483D01*
G02X336488Y1589280I-202J-1D01*
G01X333668D01*
G02X333466Y1589483I1J203D01*
G01Y1590103D01*
G03X333416Y1590235I-200J0D01*
G02Y1593151I1661J1458D01*
G03X333466Y1593283I-150J132D01*
G01Y1595221D01*
G03X333416Y1595353I-200J0D01*
G02Y1598269I1661J1458D01*
G03X333466Y1598401I-150J132D01*
G01Y1599021D01*
G02X333668Y1599224I202J1D01*
G37*
G36*
G01X628157D02*
X630977D01*
G02X631180Y1599021I0J-203D01*
G01Y1598399D01*
G03X631230Y1598267I200J0D01*
G02Y1595355I-1664J-1456D01*
G03X631180Y1595223I150J-132D01*
G01Y1593281D01*
G03X631230Y1593149I200J0D01*
G02Y1590237I-1664J-1456D01*
G03X631180Y1590105I150J-132D01*
G01Y1589483D01*
G02X630977Y1589280I-203J0D01*
G01X628157D01*
G02X627954Y1589483I0J203D01*
G01Y1590105D01*
G03X627904Y1590237I-200J0D01*
G02Y1593149I1664J1456D01*
G03X627954Y1593281I-150J132D01*
G01Y1595223D01*
G03X627904Y1595355I-200J0D01*
G02Y1598267I1664J1456D01*
G03X627954Y1598399I-150J132D01*
G01Y1599021D01*
G02X628157Y1599224I203J0D01*
G37*
G36*
G01X645480D02*
X648300D01*
G02X648502Y1599021I-1J-203D01*
G01Y1598401D01*
G03X648552Y1598269I200J0D01*
G02Y1595353I-1661J-1458D01*
G03X648502Y1595221I150J-132D01*
G01Y1593283D01*
G03X648552Y1593151I200J0D01*
G02Y1590235I-1661J-1458D01*
G03X648502Y1590103I150J-132D01*
G01Y1589483D01*
G02X648300Y1589280I-202J-1D01*
G01X645480D01*
G02X645278Y1589483I1J203D01*
G01Y1590103D01*
G03X645228Y1590235I-200J0D01*
G02Y1593151I1661J1458D01*
G03X645278Y1593283I-150J132D01*
G01Y1595221D01*
G03X645228Y1595353I-200J0D01*
G02Y1598269I1661J1458D01*
G03X645278Y1598401I-150J132D01*
G01Y1599021D01*
G02X645480Y1599224I202J1D01*
G37*
G36*
G01X662803D02*
X665623D01*
G02X665826Y1599021I0J-203D01*
G01Y1598399D01*
G03X665876Y1598267I200J0D01*
G02Y1595355I-1664J-1456D01*
G03X665826Y1595223I150J-132D01*
G01Y1593281D01*
G03X665876Y1593149I200J0D01*
G02Y1590237I-1664J-1456D01*
G03X665826Y1590105I150J-132D01*
G01Y1589483D01*
G02X665623Y1589280I-203J0D01*
G01X662803D01*
G02X662600Y1589483I0J203D01*
G01Y1590105D01*
G03X662550Y1590237I-200J0D01*
G02Y1593149I1664J1456D01*
G03X662600Y1593281I-150J132D01*
G01Y1595223D01*
G03X662550Y1595355I-200J0D01*
G02Y1598267I1664J1456D01*
G03X662600Y1598399I-150J132D01*
G01Y1599021D01*
G02X662803Y1599224I203J0D01*
G37*
G36*
G01X680125D02*
X682945D01*
G02X683148Y1599021I0J-203D01*
G01Y1598399D01*
G03X683198Y1598267I200J0D01*
G02Y1595355I-1664J-1456D01*
G03X683148Y1595223I150J-132D01*
G01Y1593281D01*
G03X683198Y1593149I200J0D01*
G02Y1590237I-1664J-1456D01*
G03X683148Y1590105I150J-132D01*
G01Y1589483D01*
G02X682945Y1589280I-203J0D01*
G01X680125D01*
G02X679922Y1589483I0J203D01*
G01Y1590105D01*
G03X679872Y1590237I-200J0D01*
G02Y1593149I1664J1456D01*
G03X679922Y1593281I-150J132D01*
G01Y1595223D01*
G03X679872Y1595355I-200J0D01*
G02Y1598267I1664J1456D01*
G03X679922Y1598399I-150J132D01*
G01Y1599021D01*
G02X680125Y1599224I203J0D01*
G37*
G36*
G01X1130440D02*
X1133260D01*
G02X1133462Y1599021I-1J-203D01*
G01Y1598401D01*
G03X1133512Y1598269I200J0D01*
G02Y1595353I-1661J-1458D01*
G03X1133462Y1595221I150J-132D01*
G01Y1593283D01*
G03X1133512Y1593151I200J0D01*
G02Y1590235I-1661J-1458D01*
G03X1133462Y1590103I150J-132D01*
G01Y1589483D01*
G02X1133260Y1589280I-202J-1D01*
G01X1130440D01*
G02X1130238Y1589483I1J203D01*
G01Y1590103D01*
G03X1130188Y1590235I-200J0D01*
G02Y1593151I1661J1458D01*
G03X1130238Y1593283I-150J132D01*
G01Y1595221D01*
G03X1130188Y1595353I-200J0D01*
G02Y1598269I1661J1458D01*
G03X1130238Y1598401I-150J132D01*
G01Y1599021D01*
G02X1130440Y1599224I202J1D01*
G37*
G36*
G01X1147763D02*
X1150583D01*
G02X1150786Y1599021I0J-203D01*
G01Y1598399D01*
G03X1150836Y1598267I200J0D01*
G02Y1595355I-1664J-1456D01*
G03X1150786Y1595223I150J-132D01*
G01Y1593281D01*
G03X1150836Y1593149I200J0D01*
G02Y1590237I-1664J-1456D01*
G03X1150786Y1590105I150J-132D01*
G01Y1589483D01*
G02X1150583Y1589280I-203J0D01*
G01X1147763D01*
G02X1147560Y1589483I0J203D01*
G01Y1590105D01*
G03X1147510Y1590237I-200J0D01*
G02Y1593149I1664J1456D01*
G03X1147560Y1593281I-150J132D01*
G01Y1595223D01*
G03X1147510Y1595355I-200J0D01*
G02Y1598267I1664J1456D01*
G03X1147560Y1598399I-150J132D01*
G01Y1599021D01*
G02X1147763Y1599224I203J0D01*
G37*
G36*
G01X1165086D02*
X1167906D01*
G02X1168108Y1599021I-1J-203D01*
G01Y1598401D01*
G03X1168158Y1598269I200J0D01*
G02Y1595353I-1661J-1458D01*
G03X1168108Y1595221I150J-132D01*
G01Y1593283D01*
G03X1168158Y1593151I200J0D01*
G02Y1590235I-1661J-1458D01*
G03X1168108Y1590103I150J-132D01*
G01Y1589483D01*
G02X1167906Y1589280I-202J-1D01*
G01X1165086D01*
G02X1164884Y1589483I1J203D01*
G01Y1590103D01*
G03X1164834Y1590235I-200J0D01*
G02Y1593151I1661J1458D01*
G03X1164884Y1593283I-150J132D01*
G01Y1595221D01*
G03X1164834Y1595353I-200J0D01*
G02Y1598269I1661J1458D01*
G03X1164884Y1598401I-150J132D01*
G01Y1599021D01*
G02X1165086Y1599224I202J1D01*
G37*
G36*
G01X1182408D02*
X1185228D01*
G02X1185430Y1599021I-1J-203D01*
G01Y1598401D01*
G03X1185480Y1598269I200J0D01*
G02Y1595353I-1661J-1458D01*
G03X1185430Y1595221I150J-132D01*
G01Y1593283D01*
G03X1185480Y1593151I200J0D01*
G02Y1590235I-1661J-1458D01*
G03X1185430Y1590103I150J-132D01*
G01Y1589483D01*
G02X1185228Y1589280I-202J-1D01*
G01X1182408D01*
G02X1182206Y1589483I1J203D01*
G01Y1590103D01*
G03X1182156Y1590235I-200J0D01*
G02Y1593151I1661J1458D01*
G03X1182206Y1593283I-150J132D01*
G01Y1595221D01*
G03X1182156Y1595353I-200J0D01*
G02Y1598269I1661J1458D01*
G03X1182206Y1598401I-150J132D01*
G01Y1599021D01*
G02X1182408Y1599224I202J1D01*
G37*
G36*
G01X1303669D02*
X1306489D01*
G02X1306692Y1599021I0J-203D01*
G01Y1598399D01*
G03X1306742Y1598267I200J0D01*
G02Y1595355I-1664J-1456D01*
G03X1306692Y1595223I150J-132D01*
G01Y1593281D01*
G03X1306742Y1593149I200J0D01*
G02Y1590237I-1664J-1456D01*
G03X1306692Y1590105I150J-132D01*
G01Y1589483D01*
G02X1306489Y1589280I-203J0D01*
G01X1303669D01*
G02X1303466Y1589483I0J203D01*
G01Y1590105D01*
G03X1303416Y1590237I-200J0D01*
G02Y1593149I1664J1456D01*
G03X1303466Y1593281I-150J132D01*
G01Y1595223D01*
G03X1303416Y1595355I-200J0D01*
G02Y1598267I1664J1456D01*
G03X1303466Y1598399I-150J132D01*
G01Y1599021D01*
G02X1303669Y1599224I203J0D01*
G37*
G36*
G01X1320992D02*
X1323812D01*
G02X1324014Y1599021I-1J-203D01*
G01Y1598401D01*
G03X1324064Y1598269I200J0D01*
G02Y1595353I-1661J-1458D01*
G03X1324014Y1595221I150J-132D01*
G01Y1593283D01*
G03X1324064Y1593151I200J0D01*
G02Y1590235I-1661J-1458D01*
G03X1324014Y1590103I150J-132D01*
G01Y1589483D01*
G02X1323812Y1589280I-202J-1D01*
G01X1320992D01*
G02X1320790Y1589483I1J203D01*
G01Y1590103D01*
G03X1320740Y1590235I-200J0D01*
G02Y1593151I1661J1458D01*
G03X1320790Y1593283I-150J132D01*
G01Y1595221D01*
G03X1320740Y1595353I-200J0D01*
G02Y1598269I1661J1458D01*
G03X1320790Y1598401I-150J132D01*
G01Y1599021D01*
G02X1320992Y1599224I202J1D01*
G37*
G36*
G01X1338315D02*
X1341135D01*
G02X1341338Y1599021I0J-203D01*
G01Y1598399D01*
G03X1341388Y1598267I200J0D01*
G02Y1595355I-1664J-1456D01*
G03X1341338Y1595223I150J-132D01*
G01Y1593281D01*
G03X1341388Y1593149I200J0D01*
G02Y1590237I-1664J-1456D01*
G03X1341338Y1590105I150J-132D01*
G01Y1589483D01*
G02X1341135Y1589280I-203J0D01*
G01X1338315D01*
G02X1338112Y1589483I0J203D01*
G01Y1590105D01*
G03X1338062Y1590237I-200J0D01*
G02Y1593149I1664J1456D01*
G03X1338112Y1593281I-150J132D01*
G01Y1595223D01*
G03X1338062Y1595355I-200J0D01*
G02Y1598267I1664J1456D01*
G03X1338112Y1598399I-150J132D01*
G01Y1599021D01*
G02X1338315Y1599224I203J0D01*
G37*
G36*
G01X1355637D02*
X1358457D01*
G02X1358660Y1599021I0J-203D01*
G01Y1598399D01*
G03X1358710Y1598267I200J0D01*
G02Y1595355I-1664J-1456D01*
G03X1358660Y1595223I150J-132D01*
G01Y1593281D01*
G03X1358710Y1593149I200J0D01*
G02Y1590237I-1664J-1456D01*
G03X1358660Y1590105I150J-132D01*
G01Y1589483D01*
G02X1358457Y1589280I-203J0D01*
G01X1355637D01*
G02X1355434Y1589483I0J203D01*
G01Y1590105D01*
G03X1355384Y1590237I-200J0D01*
G02Y1593149I1664J1456D01*
G03X1355434Y1593281I-150J132D01*
G01Y1595223D01*
G03X1355384Y1595355I-200J0D01*
G02Y1598267I1664J1456D01*
G03X1355434Y1598399I-150J132D01*
G01Y1599021D01*
G02X1355637Y1599224I203J0D01*
G37*
G36*
G01X1476897D02*
X1479717D01*
G02X1479920Y1599021I0J-203D01*
G01Y1598399D01*
G03X1479970Y1598267I200J0D01*
G02Y1595355I-1664J-1456D01*
G03X1479920Y1595223I150J-132D01*
G01Y1593281D01*
G03X1479970Y1593149I200J0D01*
G02Y1590237I-1664J-1456D01*
G03X1479920Y1590105I150J-132D01*
G01Y1589483D01*
G02X1479717Y1589280I-203J0D01*
G01X1476897D01*
G02X1476694Y1589483I0J203D01*
G01Y1590105D01*
G03X1476644Y1590237I-200J0D01*
G02Y1593149I1664J1456D01*
G03X1476694Y1593281I-150J132D01*
G01Y1595223D01*
G03X1476644Y1595355I-200J0D01*
G02Y1598267I1664J1456D01*
G03X1476694Y1598399I-150J132D01*
G01Y1599021D01*
G02X1476897Y1599224I203J0D01*
G37*
G36*
G01X1650125D02*
X1652945D01*
G02X1653148Y1599021I0J-203D01*
G01Y1598399D01*
G03X1653198Y1598267I200J0D01*
G02Y1595355I-1664J-1456D01*
G03X1653148Y1595223I150J-132D01*
G01Y1593281D01*
G03X1653198Y1593149I200J0D01*
G02Y1590237I-1664J-1456D01*
G03X1653148Y1590105I150J-132D01*
G01Y1589483D01*
G02X1652945Y1589280I-203J0D01*
G01X1650125D01*
G02X1649922Y1589483I0J203D01*
G01Y1590105D01*
G03X1649872Y1590237I-200J0D01*
G02Y1593149I1664J1456D01*
G03X1649922Y1593281I-150J132D01*
G01Y1595223D01*
G03X1649872Y1595355I-200J0D01*
G02Y1598267I1664J1456D01*
G03X1649922Y1598399I-150J132D01*
G01Y1599021D01*
G02X1650125Y1599224I203J0D01*
G37*
G36*
G01X1667448D02*
X1670268D01*
G02X1670470Y1599021I-1J-203D01*
G01Y1598401D01*
G03X1670520Y1598269I200J0D01*
G02Y1595353I-1661J-1458D01*
G03X1670470Y1595221I150J-132D01*
G01Y1593283D01*
G03X1670520Y1593151I200J0D01*
G02Y1590235I-1661J-1458D01*
G03X1670470Y1590103I150J-132D01*
G01Y1589483D01*
G02X1670268Y1589280I-202J-1D01*
G01X1667448D01*
G02X1667246Y1589483I1J203D01*
G01Y1590103D01*
G03X1667196Y1590235I-200J0D01*
G02Y1593151I1661J1458D01*
G03X1667246Y1593283I-150J132D01*
G01Y1595221D01*
G03X1667196Y1595353I-200J0D01*
G02Y1598269I1661J1458D01*
G03X1667246Y1598401I-150J132D01*
G01Y1599021D01*
G02X1667448Y1599224I202J1D01*
G37*
G36*
G01X1684771D02*
X1687591D01*
G02X1687794Y1599021I0J-203D01*
G01Y1598399D01*
G03X1687844Y1598267I200J0D01*
G02Y1595355I-1664J-1456D01*
G03X1687794Y1595223I150J-132D01*
G01Y1593281D01*
G03X1687844Y1593149I200J0D01*
G02Y1590237I-1664J-1456D01*
G03X1687794Y1590105I150J-132D01*
G01Y1589483D01*
G02X1687591Y1589280I-203J0D01*
G01X1684771D01*
G02X1684568Y1589483I0J203D01*
G01Y1590105D01*
G03X1684518Y1590237I-200J0D01*
G02Y1593149I1664J1456D01*
G03X1684568Y1593281I-150J132D01*
G01Y1595223D01*
G03X1684518Y1595355I-200J0D01*
G02Y1598267I1664J1456D01*
G03X1684568Y1598399I-150J132D01*
G01Y1599021D01*
G02X1684771Y1599224I203J0D01*
G37*
G36*
G01X1702093D02*
X1704913D01*
G02X1705116Y1599021I0J-203D01*
G01Y1598399D01*
G03X1705166Y1598267I200J0D01*
G02Y1595355I-1664J-1456D01*
G03X1705116Y1595223I150J-132D01*
G01Y1593281D01*
G03X1705166Y1593149I200J0D01*
G02Y1590237I-1664J-1456D01*
G03X1705116Y1590105I150J-132D01*
G01Y1589483D01*
G02X1704913Y1589280I-203J0D01*
G01X1702093D01*
G02X1701890Y1589483I0J203D01*
G01Y1590105D01*
G03X1701840Y1590237I-200J0D01*
G02Y1593149I1664J1456D01*
G03X1701890Y1593281I-150J132D01*
G01Y1595223D01*
G03X1701840Y1595355I-200J0D01*
G02Y1598267I1664J1456D01*
G03X1701890Y1598399I-150J132D01*
G01Y1599021D01*
G02X1702093Y1599224I203J0D01*
G37*
G36*
G01X134456Y1603554D02*
X137276D01*
G02X137478Y1603352I0J-202D01*
G01Y1602732D01*
G03X137528Y1602600I200J0D01*
G02Y1599684I-1661J-1458D01*
G03X137478Y1599552I150J-132D01*
G01Y1597614D01*
G03X137528Y1597482I200J0D01*
G02Y1594566I-1661J-1458D01*
G03X137478Y1594434I150J-132D01*
G01Y1593814D01*
G02X137276Y1593612I-202J0D01*
G01X134456D01*
G02X134254Y1593814I0J202D01*
G01Y1594434D01*
G03X134204Y1594566I-200J0D01*
G02Y1597482I1661J1458D01*
G03X134254Y1597614I-150J132D01*
G01Y1599552D01*
G03X134204Y1599684I-200J0D01*
G02Y1602600I1661J1458D01*
G03X134254Y1602732I-150J132D01*
G01Y1603352D01*
G02X134456Y1603554I202J0D01*
G37*
G36*
G01X169102D02*
X171922D01*
G02X172124Y1603352I0J-202D01*
G01Y1602732D01*
G03X172174Y1602600I200J0D01*
G02Y1599684I-1661J-1458D01*
G03X172124Y1599552I150J-132D01*
G01Y1597614D01*
G03X172174Y1597482I200J0D01*
G02Y1594566I-1661J-1458D01*
G03X172124Y1594434I150J-132D01*
G01Y1593814D01*
G02X171922Y1593612I-202J0D01*
G01X169102D01*
G02X168900Y1593814I0J202D01*
G01Y1594434D01*
G03X168850Y1594566I-200J0D01*
G02Y1597482I1661J1458D01*
G03X168900Y1597614I-150J132D01*
G01Y1599552D01*
G03X168850Y1599684I-200J0D01*
G02Y1602600I1661J1458D01*
G03X168900Y1602732I-150J132D01*
G01Y1603352D01*
G02X169102Y1603554I202J0D01*
G37*
G36*
G01X307684D02*
X310504D01*
G02X310706Y1603352I0J-202D01*
G01Y1602732D01*
G03X310756Y1602600I200J0D01*
G02Y1599684I-1661J-1458D01*
G03X310706Y1599552I150J-132D01*
G01Y1597614D01*
G03X310756Y1597482I200J0D01*
G02Y1594566I-1661J-1458D01*
G03X310706Y1594434I150J-132D01*
G01Y1593814D01*
G02X310504Y1593612I-202J0D01*
G01X307684D01*
G02X307482Y1593814I0J202D01*
G01Y1594434D01*
G03X307432Y1594566I-200J0D01*
G02Y1597482I1661J1458D01*
G03X307482Y1597614I-150J132D01*
G01Y1599552D01*
G03X307432Y1599684I-200J0D01*
G02Y1602600I1661J1458D01*
G03X307482Y1602732I-150J132D01*
G01Y1603352D01*
G02X307684Y1603554I202J0D01*
G37*
G36*
G01X342330D02*
X345150D01*
G02X345352Y1603352I0J-202D01*
G01Y1602732D01*
G03X345402Y1602600I200J0D01*
G02Y1599684I-1661J-1458D01*
G03X345352Y1599552I150J-132D01*
G01Y1597614D01*
G03X345402Y1597482I200J0D01*
G02Y1594566I-1661J-1458D01*
G03X345352Y1594434I150J-132D01*
G01Y1593814D01*
G02X345150Y1593612I-202J0D01*
G01X342330D01*
G02X342128Y1593814I0J202D01*
G01Y1594434D01*
G03X342078Y1594566I-200J0D01*
G02Y1597482I1661J1458D01*
G03X342128Y1597614I-150J132D01*
G01Y1599552D01*
G03X342078Y1599684I-200J0D01*
G02Y1602600I1661J1458D01*
G03X342128Y1602732I-150J132D01*
G01Y1603352D01*
G02X342330Y1603554I202J0D01*
G37*
G36*
G01X636818D02*
X639638D01*
G02X639840Y1603352I0J-202D01*
G01Y1602732D01*
G03X639890Y1602600I200J0D01*
G02Y1599684I-1661J-1458D01*
G03X639840Y1599552I150J-132D01*
G01Y1597614D01*
G03X639890Y1597482I200J0D01*
G02Y1594566I-1661J-1458D01*
G03X639840Y1594434I150J-132D01*
G01Y1593814D01*
G02X639638Y1593612I-202J0D01*
G01X636818D01*
G02X636616Y1593814I0J202D01*
G01Y1594434D01*
G03X636566Y1594566I-200J0D01*
G02Y1597482I1661J1458D01*
G03X636616Y1597614I-150J132D01*
G01Y1599552D01*
G03X636566Y1599684I-200J0D01*
G02Y1602600I1661J1458D01*
G03X636616Y1602732I-150J132D01*
G01Y1603352D01*
G02X636818Y1603554I202J0D01*
G37*
G36*
G01X671464D02*
X674284D01*
G02X674486Y1603352I0J-202D01*
G01Y1602732D01*
G03X674536Y1602600I200J0D01*
G02Y1599684I-1661J-1458D01*
G03X674486Y1599552I150J-132D01*
G01Y1597614D01*
G03X674536Y1597482I200J0D01*
G02Y1594566I-1661J-1458D01*
G03X674486Y1594434I150J-132D01*
G01Y1593814D01*
G02X674284Y1593612I-202J0D01*
G01X671464D01*
G02X671262Y1593814I0J202D01*
G01Y1594434D01*
G03X671212Y1594566I-200J0D01*
G02Y1597482I1661J1458D01*
G03X671262Y1597614I-150J132D01*
G01Y1599552D01*
G03X671212Y1599684I-200J0D01*
G02Y1602600I1661J1458D01*
G03X671262Y1602732I-150J132D01*
G01Y1603352D01*
G02X671464Y1603554I202J0D01*
G37*
G36*
G01X1156424D02*
X1159244D01*
G02X1159446Y1603352I0J-202D01*
G01Y1602732D01*
G03X1159496Y1602600I200J0D01*
G02Y1599684I-1661J-1458D01*
G03X1159446Y1599552I150J-132D01*
G01Y1597614D01*
G03X1159496Y1597482I200J0D01*
G02Y1594566I-1661J-1458D01*
G03X1159446Y1594434I150J-132D01*
G01Y1593814D01*
G02X1159244Y1593612I-202J0D01*
G01X1156424D01*
G02X1156222Y1593814I0J202D01*
G01Y1594434D01*
G03X1156172Y1594566I-200J0D01*
G02Y1597482I1661J1458D01*
G03X1156222Y1597614I-150J132D01*
G01Y1599552D01*
G03X1156172Y1599684I-200J0D01*
G02Y1602600I1661J1458D01*
G03X1156222Y1602732I-150J132D01*
G01Y1603352D01*
G02X1156424Y1603554I202J0D01*
G37*
G36*
G01X1191070D02*
X1193890D01*
G02X1194092Y1603352I0J-202D01*
G01Y1602732D01*
G03X1194142Y1602600I200J0D01*
G02Y1599684I-1661J-1458D01*
G03X1194092Y1599552I150J-132D01*
G01Y1597614D01*
G03X1194142Y1597482I200J0D01*
G02Y1594566I-1661J-1458D01*
G03X1194092Y1594434I150J-132D01*
G01Y1593814D01*
G02X1193890Y1593612I-202J0D01*
G01X1191070D01*
G02X1190868Y1593814I0J202D01*
G01Y1594434D01*
G03X1190818Y1594566I-200J0D01*
G02Y1597482I1661J1458D01*
G03X1190868Y1597614I-150J132D01*
G01Y1599552D01*
G03X1190818Y1599684I-200J0D01*
G02Y1602600I1661J1458D01*
G03X1190868Y1602732I-150J132D01*
G01Y1603352D01*
G02X1191070Y1603554I202J0D01*
G37*
G36*
G01X1312330D02*
X1315150D01*
G02X1315352Y1603352I0J-202D01*
G01Y1602732D01*
G03X1315402Y1602600I200J0D01*
G02Y1599684I-1661J-1458D01*
G03X1315352Y1599552I150J-132D01*
G01Y1597614D01*
G03X1315402Y1597482I200J0D01*
G02Y1594566I-1661J-1458D01*
G03X1315352Y1594434I150J-132D01*
G01Y1593814D01*
G02X1315150Y1593612I-202J0D01*
G01X1312330D01*
G02X1312128Y1593814I0J202D01*
G01Y1594434D01*
G03X1312078Y1594566I-200J0D01*
G02Y1597482I1661J1458D01*
G03X1312128Y1597614I-150J132D01*
G01Y1599552D01*
G03X1312078Y1599684I-200J0D01*
G02Y1602600I1661J1458D01*
G03X1312128Y1602732I-150J132D01*
G01Y1603352D01*
G02X1312330Y1603554I202J0D01*
G37*
G36*
G01X1346976D02*
X1349796D01*
G02X1349998Y1603352I0J-202D01*
G01Y1602732D01*
G03X1350048Y1602600I200J0D01*
G02Y1599684I-1661J-1458D01*
G03X1349998Y1599552I150J-132D01*
G01Y1597614D01*
G03X1350048Y1597482I200J0D01*
G02Y1594566I-1661J-1458D01*
G03X1349998Y1594434I150J-132D01*
G01Y1593814D01*
G02X1349796Y1593612I-202J0D01*
G01X1346976D01*
G02X1346774Y1593814I0J202D01*
G01Y1594434D01*
G03X1346724Y1594566I-200J0D01*
G02Y1597482I1661J1458D01*
G03X1346774Y1597614I-150J132D01*
G01Y1599552D01*
G03X1346724Y1599684I-200J0D01*
G02Y1602600I1661J1458D01*
G03X1346774Y1602732I-150J132D01*
G01Y1603352D01*
G02X1346976Y1603554I202J0D01*
G37*
G36*
G01X1658786D02*
X1661606D01*
G02X1661808Y1603352I0J-202D01*
G01Y1602732D01*
G03X1661858Y1602600I200J0D01*
G02Y1599684I-1661J-1458D01*
G03X1661808Y1599552I150J-132D01*
G01Y1597614D01*
G03X1661858Y1597482I200J0D01*
G02Y1594566I-1661J-1458D01*
G03X1661808Y1594434I150J-132D01*
G01Y1593814D01*
G02X1661606Y1593612I-202J0D01*
G01X1658786D01*
G02X1658584Y1593814I0J202D01*
G01Y1594434D01*
G03X1658534Y1594566I-200J0D01*
G02Y1597482I1661J1458D01*
G03X1658584Y1597614I-150J132D01*
G01Y1599552D01*
G03X1658534Y1599684I-200J0D01*
G02Y1602600I1661J1458D01*
G03X1658584Y1602732I-150J132D01*
G01Y1603352D01*
G02X1658786Y1603554I202J0D01*
G37*
G36*
G01X1693432D02*
X1696252D01*
G02X1696454Y1603352I0J-202D01*
G01Y1602732D01*
G03X1696504Y1602600I200J0D01*
G02Y1599684I-1661J-1458D01*
G03X1696454Y1599552I150J-132D01*
G01Y1597614D01*
G03X1696504Y1597482I200J0D01*
G02Y1594566I-1661J-1458D01*
G03X1696454Y1594434I150J-132D01*
G01Y1593814D01*
G02X1696252Y1593612I-202J0D01*
G01X1693432D01*
G02X1693230Y1593814I0J202D01*
G01Y1594434D01*
G03X1693180Y1594566I-200J0D01*
G02Y1597482I1661J1458D01*
G03X1693230Y1597614I-150J132D01*
G01Y1599552D01*
G03X1693180Y1599684I-200J0D01*
G02Y1602600I1661J1458D01*
G03X1693230Y1602732I-150J132D01*
G01Y1603352D01*
G02X1693432Y1603554I202J0D01*
G37*
G36*
G01X117133D02*
X119953D01*
G02X120156Y1603352I1J-202D01*
G01Y1602730D01*
G03X120206Y1602598I200J0D01*
G02Y1599686I-1664J-1456D01*
G03X120156Y1599554I150J-132D01*
G01Y1597612D01*
G03X120206Y1597480I200J0D01*
G02Y1594568I-1664J-1456D01*
G03X120156Y1594436I150J-132D01*
G01Y1593814D01*
G02X119953Y1593612I-203J1D01*
G01X117133D01*
G02X116930Y1593814I-1J202D01*
G01Y1594436D01*
G03X116880Y1594568I-200J0D01*
G02Y1597480I1664J1456D01*
G03X116930Y1597612I-150J132D01*
G01Y1599554D01*
G03X116880Y1599686I-200J0D01*
G02Y1602598I1664J1456D01*
G03X116930Y1602730I-150J132D01*
G01Y1603352D01*
G02X117133Y1603554I203J-1D01*
G37*
G36*
G01X151779D02*
X154599D01*
G02X154802Y1603352I1J-202D01*
G01Y1602730D01*
G03X154852Y1602598I200J0D01*
G02Y1599686I-1664J-1456D01*
G03X154802Y1599554I150J-132D01*
G01Y1597612D01*
G03X154852Y1597480I200J0D01*
G02Y1594568I-1664J-1456D01*
G03X154802Y1594436I150J-132D01*
G01Y1593814D01*
G02X154599Y1593612I-203J1D01*
G01X151779D01*
G02X151576Y1593814I-1J202D01*
G01Y1594436D01*
G03X151526Y1594568I-200J0D01*
G02Y1597480I1664J1456D01*
G03X151576Y1597612I-150J132D01*
G01Y1599554D01*
G03X151526Y1599686I-200J0D01*
G02Y1602598I1664J1456D01*
G03X151576Y1602730I-150J132D01*
G01Y1603352D01*
G02X151779Y1603554I203J-1D01*
G37*
G36*
G01X186425D02*
X189245D01*
G02X189448Y1603352I1J-202D01*
G01Y1602730D01*
G03X189498Y1602598I200J0D01*
G02Y1599686I-1664J-1456D01*
G03X189448Y1599554I150J-132D01*
G01Y1597612D01*
G03X189498Y1597480I200J0D01*
G02Y1594568I-1664J-1456D01*
G03X189448Y1594436I150J-132D01*
G01Y1593814D01*
G02X189245Y1593612I-203J1D01*
G01X186425D01*
G02X186222Y1593814I-1J202D01*
G01Y1594436D01*
G03X186172Y1594568I-200J0D01*
G02Y1597480I1664J1456D01*
G03X186222Y1597612I-150J132D01*
G01Y1599554D01*
G03X186172Y1599686I-200J0D01*
G02Y1602598I1664J1456D01*
G03X186222Y1602730I-150J132D01*
G01Y1603352D01*
G02X186425Y1603554I203J-1D01*
G37*
G36*
G01X290361D02*
X293181D01*
G02X293384Y1603352I1J-202D01*
G01Y1602730D01*
G03X293434Y1602598I200J0D01*
G02Y1599686I-1664J-1456D01*
G03X293384Y1599554I150J-132D01*
G01Y1597612D01*
G03X293434Y1597480I200J0D01*
G02Y1594568I-1664J-1456D01*
G03X293384Y1594436I150J-132D01*
G01Y1593814D01*
G02X293181Y1593612I-203J1D01*
G01X290361D01*
G02X290158Y1593814I-1J202D01*
G01Y1594436D01*
G03X290108Y1594568I-200J0D01*
G02Y1597480I1664J1456D01*
G03X290158Y1597612I-150J132D01*
G01Y1599554D01*
G03X290108Y1599686I-200J0D01*
G02Y1602598I1664J1456D01*
G03X290158Y1602730I-150J132D01*
G01Y1603352D01*
G02X290361Y1603554I203J-1D01*
G37*
G36*
G01X325007D02*
X327827D01*
G02X328030Y1603352I1J-202D01*
G01Y1602730D01*
G03X328080Y1602598I200J0D01*
G02Y1599686I-1664J-1456D01*
G03X328030Y1599554I150J-132D01*
G01Y1597612D01*
G03X328080Y1597480I200J0D01*
G02Y1594568I-1664J-1456D01*
G03X328030Y1594436I150J-132D01*
G01Y1593814D01*
G02X327827Y1593612I-203J1D01*
G01X325007D01*
G02X324804Y1593814I-1J202D01*
G01Y1594436D01*
G03X324754Y1594568I-200J0D01*
G02Y1597480I1664J1456D01*
G03X324804Y1597612I-150J132D01*
G01Y1599554D01*
G03X324754Y1599686I-200J0D01*
G02Y1602598I1664J1456D01*
G03X324804Y1602730I-150J132D01*
G01Y1603352D01*
G02X325007Y1603554I203J-1D01*
G37*
G36*
G01X359653D02*
X362473D01*
G02X362676Y1603352I1J-202D01*
G01Y1602730D01*
G03X362726Y1602598I200J0D01*
G02Y1599686I-1664J-1456D01*
G03X362676Y1599554I150J-132D01*
G01Y1597612D01*
G03X362726Y1597480I200J0D01*
G02Y1594568I-1664J-1456D01*
G03X362676Y1594436I150J-132D01*
G01Y1593814D01*
G02X362473Y1593612I-203J1D01*
G01X359653D01*
G02X359450Y1593814I-1J202D01*
G01Y1594436D01*
G03X359400Y1594568I-200J0D01*
G02Y1597480I1664J1456D01*
G03X359450Y1597612I-150J132D01*
G01Y1599554D01*
G03X359400Y1599686I-200J0D01*
G02Y1602598I1664J1456D01*
G03X359450Y1602730I-150J132D01*
G01Y1603352D01*
G02X359653Y1603554I203J-1D01*
G37*
G36*
G01X515559D02*
X518379D01*
G02X518582Y1603352I1J-202D01*
G01Y1602730D01*
G03X518632Y1602598I200J0D01*
G02Y1599686I-1664J-1456D01*
G03X518582Y1599554I150J-132D01*
G01Y1597612D01*
G03X518632Y1597480I200J0D01*
G02Y1594568I-1664J-1456D01*
G03X518582Y1594436I150J-132D01*
G01Y1593814D01*
G02X518379Y1593612I-203J1D01*
G01X515559D01*
G02X515356Y1593814I-1J202D01*
G01Y1594436D01*
G03X515306Y1594568I-200J0D01*
G02Y1597480I1664J1456D01*
G03X515356Y1597612I-150J132D01*
G01Y1599554D01*
G03X515306Y1599686I-200J0D01*
G02Y1602598I1664J1456D01*
G03X515356Y1602730I-150J132D01*
G01Y1603352D01*
G02X515559Y1603554I203J-1D01*
G37*
G36*
G01X654141D02*
X656961D01*
G02X657164Y1603352I1J-202D01*
G01Y1602730D01*
G03X657214Y1602598I200J0D01*
G02Y1599686I-1664J-1456D01*
G03X657164Y1599554I150J-132D01*
G01Y1597612D01*
G03X657214Y1597480I200J0D01*
G02Y1594568I-1664J-1456D01*
G03X657164Y1594436I150J-132D01*
G01Y1593814D01*
G02X656961Y1593612I-203J1D01*
G01X654141D01*
G02X653938Y1593814I-1J202D01*
G01Y1594436D01*
G03X653888Y1594568I-200J0D01*
G02Y1597480I1664J1456D01*
G03X653938Y1597612I-150J132D01*
G01Y1599554D01*
G03X653888Y1599686I-200J0D01*
G02Y1602598I1664J1456D01*
G03X653938Y1602730I-150J132D01*
G01Y1603352D01*
G02X654141Y1603554I203J-1D01*
G37*
G36*
G01X688787D02*
X691607D01*
G02X691810Y1603352I1J-202D01*
G01Y1602730D01*
G03X691860Y1602598I200J0D01*
G02Y1599686I-1664J-1456D01*
G03X691810Y1599554I150J-132D01*
G01Y1597612D01*
G03X691860Y1597480I200J0D01*
G02Y1594568I-1664J-1456D01*
G03X691810Y1594436I150J-132D01*
G01Y1593814D01*
G02X691607Y1593612I-203J1D01*
G01X688787D01*
G02X688584Y1593814I-1J202D01*
G01Y1594436D01*
G03X688534Y1594568I-200J0D01*
G02Y1597480I1664J1456D01*
G03X688584Y1597612I-150J132D01*
G01Y1599554D01*
G03X688534Y1599686I-200J0D01*
G02Y1602598I1664J1456D01*
G03X688584Y1602730I-150J132D01*
G01Y1603352D01*
G02X688787Y1603554I203J-1D01*
G37*
G36*
G01X1139101D02*
X1141921D01*
G02X1142124Y1603352I1J-202D01*
G01Y1602730D01*
G03X1142174Y1602598I200J0D01*
G02Y1599686I-1664J-1456D01*
G03X1142124Y1599554I150J-132D01*
G01Y1597612D01*
G03X1142174Y1597480I200J0D01*
G02Y1594568I-1664J-1456D01*
G03X1142124Y1594436I150J-132D01*
G01Y1593814D01*
G02X1141921Y1593612I-203J1D01*
G01X1139101D01*
G02X1138898Y1593814I-1J202D01*
G01Y1594436D01*
G03X1138848Y1594568I-200J0D01*
G02Y1597480I1664J1456D01*
G03X1138898Y1597612I-150J132D01*
G01Y1599554D01*
G03X1138848Y1599686I-200J0D01*
G02Y1602598I1664J1456D01*
G03X1138898Y1602730I-150J132D01*
G01Y1603352D01*
G02X1139101Y1603554I203J-1D01*
G37*
G36*
G01X1173747D02*
X1176567D01*
G02X1176770Y1603352I1J-202D01*
G01Y1602730D01*
G03X1176820Y1602598I200J0D01*
G02Y1599686I-1664J-1456D01*
G03X1176770Y1599554I150J-132D01*
G01Y1597612D01*
G03X1176820Y1597480I200J0D01*
G02Y1594568I-1664J-1456D01*
G03X1176770Y1594436I150J-132D01*
G01Y1593814D01*
G02X1176567Y1593612I-203J1D01*
G01X1173747D01*
G02X1173544Y1593814I-1J202D01*
G01Y1594436D01*
G03X1173494Y1594568I-200J0D01*
G02Y1597480I1664J1456D01*
G03X1173544Y1597612I-150J132D01*
G01Y1599554D01*
G03X1173494Y1599686I-200J0D01*
G02Y1602598I1664J1456D01*
G03X1173544Y1602730I-150J132D01*
G01Y1603352D01*
G02X1173747Y1603554I203J-1D01*
G37*
G36*
G01X1329653D02*
X1332473D01*
G02X1332676Y1603352I1J-202D01*
G01Y1602730D01*
G03X1332726Y1602598I200J0D01*
G02Y1599686I-1664J-1456D01*
G03X1332676Y1599554I150J-132D01*
G01Y1597612D01*
G03X1332726Y1597480I200J0D01*
G02Y1594568I-1664J-1456D01*
G03X1332676Y1594436I150J-132D01*
G01Y1593814D01*
G02X1332473Y1593612I-203J1D01*
G01X1329653D01*
G02X1329450Y1593814I-1J202D01*
G01Y1594436D01*
G03X1329400Y1594568I-200J0D01*
G02Y1597480I1664J1456D01*
G03X1329450Y1597612I-150J132D01*
G01Y1599554D01*
G03X1329400Y1599686I-200J0D01*
G02Y1602598I1664J1456D01*
G03X1329450Y1602730I-150J132D01*
G01Y1603352D01*
G02X1329653Y1603554I203J-1D01*
G37*
G36*
G01X1364299D02*
X1367119D01*
G02X1367322Y1603352I1J-202D01*
G01Y1602730D01*
G03X1367372Y1602598I200J0D01*
G02Y1599686I-1664J-1456D01*
G03X1367322Y1599554I150J-132D01*
G01Y1597612D01*
G03X1367372Y1597480I200J0D01*
G02Y1594568I-1664J-1456D01*
G03X1367322Y1594436I150J-132D01*
G01Y1593814D01*
G02X1367119Y1593612I-203J1D01*
G01X1364299D01*
G02X1364096Y1593814I-1J202D01*
G01Y1594436D01*
G03X1364046Y1594568I-200J0D01*
G02Y1597480I1664J1456D01*
G03X1364096Y1597612I-150J132D01*
G01Y1599554D01*
G03X1364046Y1599686I-200J0D01*
G02Y1602598I1664J1456D01*
G03X1364096Y1602730I-150J132D01*
G01Y1603352D01*
G02X1364299Y1603554I203J-1D01*
G37*
G36*
G01X1676109D02*
X1678929D01*
G02X1679132Y1603352I1J-202D01*
G01Y1602730D01*
G03X1679182Y1602598I200J0D01*
G02Y1599686I-1664J-1456D01*
G03X1679132Y1599554I150J-132D01*
G01Y1597612D01*
G03X1679182Y1597480I200J0D01*
G02Y1594568I-1664J-1456D01*
G03X1679132Y1594436I150J-132D01*
G01Y1593814D01*
G02X1678929Y1593612I-203J1D01*
G01X1676109D01*
G02X1675906Y1593814I-1J202D01*
G01Y1594436D01*
G03X1675856Y1594568I-200J0D01*
G02Y1597480I1664J1456D01*
G03X1675906Y1597612I-150J132D01*
G01Y1599554D01*
G03X1675856Y1599686I-200J0D01*
G02Y1602598I1664J1456D01*
G03X1675906Y1602730I-150J132D01*
G01Y1603352D01*
G02X1676109Y1603554I203J-1D01*
G37*
G36*
G01X1710755D02*
X1713575D01*
G02X1713778Y1603352I1J-202D01*
G01Y1602730D01*
G03X1713828Y1602598I200J0D01*
G02Y1599686I-1664J-1456D01*
G03X1713778Y1599554I150J-132D01*
G01Y1597612D01*
G03X1713828Y1597480I200J0D01*
G02Y1594568I-1664J-1456D01*
G03X1713778Y1594436I150J-132D01*
G01Y1593814D01*
G02X1713575Y1593612I-203J1D01*
G01X1710755D01*
G02X1710552Y1593814I-1J202D01*
G01Y1594436D01*
G03X1710502Y1594568I-200J0D01*
G02Y1597480I1664J1456D01*
G03X1710552Y1597612I-150J132D01*
G01Y1599554D01*
G03X1710502Y1599686I-200J0D01*
G02Y1602598I1664J1456D01*
G03X1710552Y1602730I-150J132D01*
G01Y1603352D01*
G02X1710755Y1603554I203J-1D01*
G37*
G36*
G01X108472Y1614578D02*
X111292D01*
G02X111494Y1614376I0J-202D01*
G01Y1613756D01*
G03X111544Y1613624I200J0D01*
G02Y1610708I-1661J-1458D01*
G03X111494Y1610576I150J-132D01*
G01Y1608638D01*
G03X111544Y1608506I200J0D01*
G02Y1605590I-1661J-1458D01*
G03X111494Y1605458I150J-132D01*
G01Y1604838D01*
G02X111292Y1604636I-202J0D01*
G01X108472D01*
G02X108270Y1604838I0J202D01*
G01Y1605458D01*
G03X108220Y1605590I-200J0D01*
G02Y1608506I1661J1458D01*
G03X108270Y1608638I-150J132D01*
G01Y1610576D01*
G03X108220Y1610708I-200J0D01*
G02Y1613624I1661J1458D01*
G03X108270Y1613756I-150J132D01*
G01Y1614376D01*
G02X108472Y1614578I202J0D01*
G37*
G36*
G01X143118D02*
X145938D01*
G02X146140Y1614376I0J-202D01*
G01Y1613756D01*
G03X146190Y1613624I200J0D01*
G02Y1610708I-1661J-1458D01*
G03X146140Y1610576I150J-132D01*
G01Y1608638D01*
G03X146190Y1608506I200J0D01*
G02Y1605590I-1661J-1458D01*
G03X146140Y1605458I150J-132D01*
G01Y1604838D01*
G02X145938Y1604636I-202J0D01*
G01X143118D01*
G02X142916Y1604838I0J202D01*
G01Y1605458D01*
G03X142866Y1605590I-200J0D01*
G02Y1608506I1661J1458D01*
G03X142916Y1608638I-150J132D01*
G01Y1610576D01*
G03X142866Y1610708I-200J0D01*
G02Y1613624I1661J1458D01*
G03X142916Y1613756I-150J132D01*
G01Y1614376D01*
G02X143118Y1614578I202J0D01*
G37*
G36*
G01X160440D02*
X163260D01*
G02X163462Y1614376I0J-202D01*
G01Y1613756D01*
G03X163512Y1613624I200J0D01*
G02Y1610708I-1661J-1458D01*
G03X163462Y1610576I150J-132D01*
G01Y1608638D01*
G03X163512Y1608506I200J0D01*
G02Y1605590I-1661J-1458D01*
G03X163462Y1605458I150J-132D01*
G01Y1604838D01*
G02X163260Y1604636I-202J0D01*
G01X160440D01*
G02X160238Y1604838I0J202D01*
G01Y1605458D01*
G03X160188Y1605590I-200J0D01*
G02Y1608506I1661J1458D01*
G03X160238Y1608638I-150J132D01*
G01Y1610576D01*
G03X160188Y1610708I-200J0D01*
G02Y1613624I1661J1458D01*
G03X160238Y1613756I-150J132D01*
G01Y1614376D01*
G02X160440Y1614578I202J0D01*
G37*
G36*
G01X281700D02*
X284520D01*
G02X284722Y1614376I0J-202D01*
G01Y1613756D01*
G03X284772Y1613624I200J0D01*
G02Y1610708I-1661J-1458D01*
G03X284722Y1610576I150J-132D01*
G01Y1608638D01*
G03X284772Y1608506I200J0D01*
G02Y1605590I-1661J-1458D01*
G03X284722Y1605458I150J-132D01*
G01Y1604838D01*
G02X284520Y1604636I-202J0D01*
G01X281700D01*
G02X281498Y1604838I0J202D01*
G01Y1605458D01*
G03X281448Y1605590I-200J0D01*
G02Y1608506I1661J1458D01*
G03X281498Y1608638I-150J132D01*
G01Y1610576D01*
G03X281448Y1610708I-200J0D01*
G02Y1613624I1661J1458D01*
G03X281498Y1613756I-150J132D01*
G01Y1614376D01*
G02X281700Y1614578I202J0D01*
G37*
G36*
G01X316346D02*
X319166D01*
G02X319368Y1614376I0J-202D01*
G01Y1613756D01*
G03X319418Y1613624I200J0D01*
G02Y1610708I-1661J-1458D01*
G03X319368Y1610576I150J-132D01*
G01Y1608638D01*
G03X319418Y1608506I200J0D01*
G02Y1605590I-1661J-1458D01*
G03X319368Y1605458I150J-132D01*
G01Y1604838D01*
G02X319166Y1604636I-202J0D01*
G01X316346D01*
G02X316144Y1604838I0J202D01*
G01Y1605458D01*
G03X316094Y1605590I-200J0D01*
G02Y1608506I1661J1458D01*
G03X316144Y1608638I-150J132D01*
G01Y1610576D01*
G03X316094Y1610708I-200J0D01*
G02Y1613624I1661J1458D01*
G03X316144Y1613756I-150J132D01*
G01Y1614376D01*
G02X316346Y1614578I202J0D01*
G37*
G36*
G01X333668D02*
X336488D01*
G02X336690Y1614376I0J-202D01*
G01Y1613756D01*
G03X336740Y1613624I200J0D01*
G02Y1610708I-1661J-1458D01*
G03X336690Y1610576I150J-132D01*
G01Y1608638D01*
G03X336740Y1608506I200J0D01*
G02Y1605590I-1661J-1458D01*
G03X336690Y1605458I150J-132D01*
G01Y1604838D01*
G02X336488Y1604636I-202J0D01*
G01X333668D01*
G02X333466Y1604838I0J202D01*
G01Y1605458D01*
G03X333416Y1605590I-200J0D01*
G02Y1608506I1661J1458D01*
G03X333466Y1608638I-150J132D01*
G01Y1610576D01*
G03X333416Y1610708I-200J0D01*
G02Y1613624I1661J1458D01*
G03X333466Y1613756I-150J132D01*
G01Y1614376D01*
G02X333668Y1614578I202J0D01*
G37*
G36*
G01X645480D02*
X648300D01*
G02X648502Y1614376I0J-202D01*
G01Y1613756D01*
G03X648552Y1613624I200J0D01*
G02Y1610708I-1661J-1458D01*
G03X648502Y1610576I150J-132D01*
G01Y1608638D01*
G03X648552Y1608506I200J0D01*
G02Y1605590I-1661J-1458D01*
G03X648502Y1605458I150J-132D01*
G01Y1604838D01*
G02X648300Y1604636I-202J0D01*
G01X645480D01*
G02X645278Y1604838I0J202D01*
G01Y1605458D01*
G03X645228Y1605590I-200J0D01*
G02Y1608506I1661J1458D01*
G03X645278Y1608638I-150J132D01*
G01Y1610576D01*
G03X645228Y1610708I-200J0D01*
G02Y1613624I1661J1458D01*
G03X645278Y1613756I-150J132D01*
G01Y1614376D01*
G02X645480Y1614578I202J0D01*
G37*
G36*
G01X1130440D02*
X1133260D01*
G02X1133462Y1614376I0J-202D01*
G01Y1613756D01*
G03X1133512Y1613624I200J0D01*
G02Y1610708I-1661J-1458D01*
G03X1133462Y1610576I150J-132D01*
G01Y1608638D01*
G03X1133512Y1608506I200J0D01*
G02Y1605590I-1661J-1458D01*
G03X1133462Y1605458I150J-132D01*
G01Y1604838D01*
G02X1133260Y1604636I-202J0D01*
G01X1130440D01*
G02X1130238Y1604838I0J202D01*
G01Y1605458D01*
G03X1130188Y1605590I-200J0D01*
G02Y1608506I1661J1458D01*
G03X1130238Y1608638I-150J132D01*
G01Y1610576D01*
G03X1130188Y1610708I-200J0D01*
G02Y1613624I1661J1458D01*
G03X1130238Y1613756I-150J132D01*
G01Y1614376D01*
G02X1130440Y1614578I202J0D01*
G37*
G36*
G01X1165086D02*
X1167906D01*
G02X1168108Y1614376I0J-202D01*
G01Y1613756D01*
G03X1168158Y1613624I200J0D01*
G02Y1610708I-1661J-1458D01*
G03X1168108Y1610576I150J-132D01*
G01Y1608638D01*
G03X1168158Y1608506I200J0D01*
G02Y1605590I-1661J-1458D01*
G03X1168108Y1605458I150J-132D01*
G01Y1604838D01*
G02X1167906Y1604636I-202J0D01*
G01X1165086D01*
G02X1164884Y1604838I0J202D01*
G01Y1605458D01*
G03X1164834Y1605590I-200J0D01*
G02Y1608506I1661J1458D01*
G03X1164884Y1608638I-150J132D01*
G01Y1610576D01*
G03X1164834Y1610708I-200J0D01*
G02Y1613624I1661J1458D01*
G03X1164884Y1613756I-150J132D01*
G01Y1614376D01*
G02X1165086Y1614578I202J0D01*
G37*
G36*
G01X1182408D02*
X1185228D01*
G02X1185430Y1614376I0J-202D01*
G01Y1613756D01*
G03X1185480Y1613624I200J0D01*
G02Y1610708I-1661J-1458D01*
G03X1185430Y1610576I150J-132D01*
G01Y1608638D01*
G03X1185480Y1608506I200J0D01*
G02Y1605590I-1661J-1458D01*
G03X1185430Y1605458I150J-132D01*
G01Y1604838D01*
G02X1185228Y1604636I-202J0D01*
G01X1182408D01*
G02X1182206Y1604838I0J202D01*
G01Y1605458D01*
G03X1182156Y1605590I-200J0D01*
G02Y1608506I1661J1458D01*
G03X1182206Y1608638I-150J132D01*
G01Y1610576D01*
G03X1182156Y1610708I-200J0D01*
G02Y1613624I1661J1458D01*
G03X1182206Y1613756I-150J132D01*
G01Y1614376D01*
G02X1182408Y1614578I202J0D01*
G37*
G36*
G01X1320992D02*
X1323812D01*
G02X1324014Y1614376I0J-202D01*
G01Y1613756D01*
G03X1324064Y1613624I200J0D01*
G02Y1610708I-1661J-1458D01*
G03X1324014Y1610576I150J-132D01*
G01Y1608638D01*
G03X1324064Y1608506I200J0D01*
G02Y1605590I-1661J-1458D01*
G03X1324014Y1605458I150J-132D01*
G01Y1604838D01*
G02X1323812Y1604636I-202J0D01*
G01X1320992D01*
G02X1320790Y1604838I0J202D01*
G01Y1605458D01*
G03X1320740Y1605590I-200J0D01*
G02Y1608506I1661J1458D01*
G03X1320790Y1608638I-150J132D01*
G01Y1610576D01*
G03X1320740Y1610708I-200J0D01*
G02Y1613624I1661J1458D01*
G03X1320790Y1613756I-150J132D01*
G01Y1614376D01*
G02X1320992Y1614578I202J0D01*
G37*
G36*
G01X1667448D02*
X1670268D01*
G02X1670470Y1614376I0J-202D01*
G01Y1613756D01*
G03X1670520Y1613624I200J0D01*
G02Y1610708I-1661J-1458D01*
G03X1670470Y1610576I150J-132D01*
G01Y1608638D01*
G03X1670520Y1608506I200J0D01*
G02Y1605590I-1661J-1458D01*
G03X1670470Y1605458I150J-132D01*
G01Y1604838D01*
G02X1670268Y1604636I-202J0D01*
G01X1667448D01*
G02X1667246Y1604838I0J202D01*
G01Y1605458D01*
G03X1667196Y1605590I-200J0D01*
G02Y1608506I1661J1458D01*
G03X1667246Y1608638I-150J132D01*
G01Y1610576D01*
G03X1667196Y1610708I-200J0D01*
G02Y1613624I1661J1458D01*
G03X1667246Y1613756I-150J132D01*
G01Y1614376D01*
G02X1667448Y1614578I202J0D01*
G37*
G36*
G01X125795D02*
X128615D01*
G02X128818Y1614376I1J-202D01*
G01Y1613754D01*
G03X128868Y1613622I200J0D01*
G02Y1610710I-1664J-1456D01*
G03X128818Y1610578I150J-132D01*
G01Y1608636D01*
G03X128868Y1608504I200J0D01*
G02Y1605592I-1664J-1456D01*
G03X128818Y1605460I150J-132D01*
G01Y1604838D01*
G02X128615Y1604636I-203J1D01*
G01X125795D01*
G02X125592Y1604838I-1J202D01*
G01Y1605460D01*
G03X125542Y1605592I-200J0D01*
G02Y1608504I1664J1456D01*
G03X125592Y1608636I-150J132D01*
G01Y1610578D01*
G03X125542Y1610710I-200J0D01*
G02Y1613622I1664J1456D01*
G03X125592Y1613754I-150J132D01*
G01Y1614376D01*
G02X125795Y1614578I203J-1D01*
G37*
G36*
G01X299023D02*
X301843D01*
G02X302046Y1614376I1J-202D01*
G01Y1613754D01*
G03X302096Y1613622I200J0D01*
G02Y1610710I-1664J-1456D01*
G03X302046Y1610578I150J-132D01*
G01Y1608636D01*
G03X302096Y1608504I200J0D01*
G02Y1605592I-1664J-1456D01*
G03X302046Y1605460I150J-132D01*
G01Y1604838D01*
G02X301843Y1604636I-203J1D01*
G01X299023D01*
G02X298820Y1604838I-1J202D01*
G01Y1605460D01*
G03X298770Y1605592I-200J0D01*
G02Y1608504I1664J1456D01*
G03X298820Y1608636I-150J132D01*
G01Y1610578D01*
G03X298770Y1610710I-200J0D01*
G02Y1613622I1664J1456D01*
G03X298820Y1613754I-150J132D01*
G01Y1614376D01*
G02X299023Y1614578I203J-1D01*
G37*
G36*
G01X628157D02*
X630977D01*
G02X631180Y1614376I1J-202D01*
G01Y1613754D01*
G03X631230Y1613622I200J0D01*
G02Y1610710I-1664J-1456D01*
G03X631180Y1610578I150J-132D01*
G01Y1608636D01*
G03X631230Y1608504I200J0D01*
G02Y1605592I-1664J-1456D01*
G03X631180Y1605460I150J-132D01*
G01Y1604838D01*
G02X630977Y1604636I-203J1D01*
G01X628157D01*
G02X627954Y1604838I-1J202D01*
G01Y1605460D01*
G03X627904Y1605592I-200J0D01*
G02Y1608504I1664J1456D01*
G03X627954Y1608636I-150J132D01*
G01Y1610578D01*
G03X627904Y1610710I-200J0D01*
G02Y1613622I1664J1456D01*
G03X627954Y1613754I-150J132D01*
G01Y1614376D01*
G02X628157Y1614578I203J-1D01*
G37*
G36*
G01X662803D02*
X665623D01*
G02X665826Y1614376I1J-202D01*
G01Y1613754D01*
G03X665876Y1613622I200J0D01*
G02Y1610710I-1664J-1456D01*
G03X665826Y1610578I150J-132D01*
G01Y1608636D01*
G03X665876Y1608504I200J0D01*
G02Y1605592I-1664J-1456D01*
G03X665826Y1605460I150J-132D01*
G01Y1604838D01*
G02X665623Y1604636I-203J1D01*
G01X662803D01*
G02X662600Y1604838I-1J202D01*
G01Y1605460D01*
G03X662550Y1605592I-200J0D01*
G02Y1608504I1664J1456D01*
G03X662600Y1608636I-150J132D01*
G01Y1610578D01*
G03X662550Y1610710I-200J0D01*
G02Y1613622I1664J1456D01*
G03X662600Y1613754I-150J132D01*
G01Y1614376D01*
G02X662803Y1614578I203J-1D01*
G37*
G36*
G01X680125D02*
X682945D01*
G02X683148Y1614376I1J-202D01*
G01Y1613754D01*
G03X683198Y1613622I200J0D01*
G02Y1610710I-1664J-1456D01*
G03X683148Y1610578I150J-132D01*
G01Y1608636D01*
G03X683198Y1608504I200J0D01*
G02Y1605592I-1664J-1456D01*
G03X683148Y1605460I150J-132D01*
G01Y1604838D01*
G02X682945Y1604636I-203J1D01*
G01X680125D01*
G02X679922Y1604838I-1J202D01*
G01Y1605460D01*
G03X679872Y1605592I-200J0D01*
G02Y1608504I1664J1456D01*
G03X679922Y1608636I-150J132D01*
G01Y1610578D01*
G03X679872Y1610710I-200J0D01*
G02Y1613622I1664J1456D01*
G03X679922Y1613754I-150J132D01*
G01Y1614376D01*
G02X680125Y1614578I203J-1D01*
G37*
G36*
G01X1147763D02*
X1150583D01*
G02X1150786Y1614376I1J-202D01*
G01Y1613754D01*
G03X1150836Y1613622I200J0D01*
G02Y1610710I-1664J-1456D01*
G03X1150786Y1610578I150J-132D01*
G01Y1608636D01*
G03X1150836Y1608504I200J0D01*
G02Y1605592I-1664J-1456D01*
G03X1150786Y1605460I150J-132D01*
G01Y1604838D01*
G02X1150583Y1604636I-203J1D01*
G01X1147763D01*
G02X1147560Y1604838I-1J202D01*
G01Y1605460D01*
G03X1147510Y1605592I-200J0D01*
G02Y1608504I1664J1456D01*
G03X1147560Y1608636I-150J132D01*
G01Y1610578D01*
G03X1147510Y1610710I-200J0D01*
G02Y1613622I1664J1456D01*
G03X1147560Y1613754I-150J132D01*
G01Y1614376D01*
G02X1147763Y1614578I203J-1D01*
G37*
G36*
G01X1303669D02*
X1306489D01*
G02X1306692Y1614376I1J-202D01*
G01Y1613754D01*
G03X1306742Y1613622I200J0D01*
G02Y1610710I-1664J-1456D01*
G03X1306692Y1610578I150J-132D01*
G01Y1608636D01*
G03X1306742Y1608504I200J0D01*
G02Y1605592I-1664J-1456D01*
G03X1306692Y1605460I150J-132D01*
G01Y1604838D01*
G02X1306489Y1604636I-203J1D01*
G01X1303669D01*
G02X1303466Y1604838I-1J202D01*
G01Y1605460D01*
G03X1303416Y1605592I-200J0D01*
G02Y1608504I1664J1456D01*
G03X1303466Y1608636I-150J132D01*
G01Y1610578D01*
G03X1303416Y1610710I-200J0D01*
G02Y1613622I1664J1456D01*
G03X1303466Y1613754I-150J132D01*
G01Y1614376D01*
G02X1303669Y1614578I203J-1D01*
G37*
G36*
G01X1338315D02*
X1341135D01*
G02X1341338Y1614376I1J-202D01*
G01Y1613754D01*
G03X1341388Y1613622I200J0D01*
G02Y1610710I-1664J-1456D01*
G03X1341338Y1610578I150J-132D01*
G01Y1608636D01*
G03X1341388Y1608504I200J0D01*
G02Y1605592I-1664J-1456D01*
G03X1341338Y1605460I150J-132D01*
G01Y1604838D01*
G02X1341135Y1604636I-203J1D01*
G01X1338315D01*
G02X1338112Y1604838I-1J202D01*
G01Y1605460D01*
G03X1338062Y1605592I-200J0D01*
G02Y1608504I1664J1456D01*
G03X1338112Y1608636I-150J132D01*
G01Y1610578D01*
G03X1338062Y1610710I-200J0D01*
G02Y1613622I1664J1456D01*
G03X1338112Y1613754I-150J132D01*
G01Y1614376D01*
G02X1338315Y1614578I203J-1D01*
G37*
G36*
G01X1355637D02*
X1358457D01*
G02X1358660Y1614376I1J-202D01*
G01Y1613754D01*
G03X1358710Y1613622I200J0D01*
G02Y1610710I-1664J-1456D01*
G03X1358660Y1610578I150J-132D01*
G01Y1608636D01*
G03X1358710Y1608504I200J0D01*
G02Y1605592I-1664J-1456D01*
G03X1358660Y1605460I150J-132D01*
G01Y1604838D01*
G02X1358457Y1604636I-203J1D01*
G01X1355637D01*
G02X1355434Y1604838I-1J202D01*
G01Y1605460D01*
G03X1355384Y1605592I-200J0D01*
G02Y1608504I1664J1456D01*
G03X1355434Y1608636I-150J132D01*
G01Y1610578D01*
G03X1355384Y1610710I-200J0D01*
G02Y1613622I1664J1456D01*
G03X1355434Y1613754I-150J132D01*
G01Y1614376D01*
G02X1355637Y1614578I203J-1D01*
G37*
G36*
G01X1476897D02*
X1479717D01*
G02X1479920Y1614376I1J-202D01*
G01Y1613754D01*
G03X1479970Y1613622I200J0D01*
G02Y1610710I-1664J-1456D01*
G03X1479920Y1610578I150J-132D01*
G01Y1608636D01*
G03X1479970Y1608504I200J0D01*
G02Y1605592I-1664J-1456D01*
G03X1479920Y1605460I150J-132D01*
G01Y1604838D01*
G02X1479717Y1604636I-203J1D01*
G01X1476897D01*
G02X1476694Y1604838I-1J202D01*
G01Y1605460D01*
G03X1476644Y1605592I-200J0D01*
G02Y1608504I1664J1456D01*
G03X1476694Y1608636I-150J132D01*
G01Y1610578D01*
G03X1476644Y1610710I-200J0D01*
G02Y1613622I1664J1456D01*
G03X1476694Y1613754I-150J132D01*
G01Y1614376D01*
G02X1476897Y1614578I203J-1D01*
G37*
G36*
G01X1650125D02*
X1652945D01*
G02X1653148Y1614376I1J-202D01*
G01Y1613754D01*
G03X1653198Y1613622I200J0D01*
G02Y1610710I-1664J-1456D01*
G03X1653148Y1610578I150J-132D01*
G01Y1608636D01*
G03X1653198Y1608504I200J0D01*
G02Y1605592I-1664J-1456D01*
G03X1653148Y1605460I150J-132D01*
G01Y1604838D01*
G02X1652945Y1604636I-203J1D01*
G01X1650125D01*
G02X1649922Y1604838I-1J202D01*
G01Y1605460D01*
G03X1649872Y1605592I-200J0D01*
G02Y1608504I1664J1456D01*
G03X1649922Y1608636I-150J132D01*
G01Y1610578D01*
G03X1649872Y1610710I-200J0D01*
G02Y1613622I1664J1456D01*
G03X1649922Y1613754I-150J132D01*
G01Y1614376D01*
G02X1650125Y1614578I203J-1D01*
G37*
G36*
G01X1684771D02*
X1687591D01*
G02X1687794Y1614376I1J-202D01*
G01Y1613754D01*
G03X1687844Y1613622I200J0D01*
G02Y1610710I-1664J-1456D01*
G03X1687794Y1610578I150J-132D01*
G01Y1608636D01*
G03X1687844Y1608504I200J0D01*
G02Y1605592I-1664J-1456D01*
G03X1687794Y1605460I150J-132D01*
G01Y1604838D01*
G02X1687591Y1604636I-203J1D01*
G01X1684771D01*
G02X1684568Y1604838I-1J202D01*
G01Y1605460D01*
G03X1684518Y1605592I-200J0D01*
G02Y1608504I1664J1456D01*
G03X1684568Y1608636I-150J132D01*
G01Y1610578D01*
G03X1684518Y1610710I-200J0D01*
G02Y1613622I1664J1456D01*
G03X1684568Y1613754I-150J132D01*
G01Y1614376D01*
G02X1684771Y1614578I203J-1D01*
G37*
G36*
G01X1702093D02*
X1704913D01*
G02X1705116Y1614376I1J-202D01*
G01Y1613754D01*
G03X1705166Y1613622I200J0D01*
G02Y1610710I-1664J-1456D01*
G03X1705116Y1610578I150J-132D01*
G01Y1608636D01*
G03X1705166Y1608504I200J0D01*
G02Y1605592I-1664J-1456D01*
G03X1705116Y1605460I150J-132D01*
G01Y1604838D01*
G02X1704913Y1604636I-203J1D01*
G01X1702093D01*
G02X1701890Y1604838I-1J202D01*
G01Y1605460D01*
G03X1701840Y1605592I-200J0D01*
G02Y1608504I1664J1456D01*
G03X1701890Y1608636I-150J132D01*
G01Y1610578D01*
G03X1701840Y1610710I-200J0D01*
G02Y1613622I1664J1456D01*
G03X1701890Y1613754I-150J132D01*
G01Y1614376D01*
G02X1702093Y1614578I203J-1D01*
G37*
G36*
G01X134456Y1618908D02*
X137276D01*
G02X137478Y1618706I0J-202D01*
G01Y1618086D01*
G03X137528Y1617954I200J0D01*
G02Y1615038I-1661J-1458D01*
G03X137478Y1614906I150J-132D01*
G01Y1612968D01*
G03X137528Y1612836I200J0D01*
G02Y1609920I-1661J-1458D01*
G03X137478Y1609788I150J-132D01*
G01Y1609168D01*
G02X137276Y1608966I-202J0D01*
G01X134456D01*
G02X134254Y1609168I0J202D01*
G01Y1609788D01*
G03X134204Y1609920I-200J0D01*
G02Y1612836I1661J1458D01*
G03X134254Y1612968I-150J132D01*
G01Y1614906D01*
G03X134204Y1615038I-200J0D01*
G02Y1617954I1661J1458D01*
G03X134254Y1618086I-150J132D01*
G01Y1618706D01*
G02X134456Y1618908I202J0D01*
G37*
G36*
G01X169102D02*
X171922D01*
G02X172124Y1618706I0J-202D01*
G01Y1618086D01*
G03X172174Y1617954I200J0D01*
G02Y1615038I-1661J-1458D01*
G03X172124Y1614906I150J-132D01*
G01Y1612968D01*
G03X172174Y1612836I200J0D01*
G02Y1609920I-1661J-1458D01*
G03X172124Y1609788I150J-132D01*
G01Y1609168D01*
G02X171922Y1608966I-202J0D01*
G01X169102D01*
G02X168900Y1609168I0J202D01*
G01Y1609788D01*
G03X168850Y1609920I-200J0D01*
G02Y1612836I1661J1458D01*
G03X168900Y1612968I-150J132D01*
G01Y1614906D01*
G03X168850Y1615038I-200J0D01*
G02Y1617954I1661J1458D01*
G03X168900Y1618086I-150J132D01*
G01Y1618706D01*
G02X169102Y1618908I202J0D01*
G37*
G36*
G01X307684D02*
X310504D01*
G02X310706Y1618706I0J-202D01*
G01Y1618086D01*
G03X310756Y1617954I200J0D01*
G02Y1615038I-1661J-1458D01*
G03X310706Y1614906I150J-132D01*
G01Y1612968D01*
G03X310756Y1612836I200J0D01*
G02Y1609920I-1661J-1458D01*
G03X310706Y1609788I150J-132D01*
G01Y1609168D01*
G02X310504Y1608966I-202J0D01*
G01X307684D01*
G02X307482Y1609168I0J202D01*
G01Y1609788D01*
G03X307432Y1609920I-200J0D01*
G02Y1612836I1661J1458D01*
G03X307482Y1612968I-150J132D01*
G01Y1614906D01*
G03X307432Y1615038I-200J0D01*
G02Y1617954I1661J1458D01*
G03X307482Y1618086I-150J132D01*
G01Y1618706D01*
G02X307684Y1618908I202J0D01*
G37*
G36*
G01X342330D02*
X345150D01*
G02X345352Y1618706I0J-202D01*
G01Y1618086D01*
G03X345402Y1617954I200J0D01*
G02Y1615038I-1661J-1458D01*
G03X345352Y1614906I150J-132D01*
G01Y1612968D01*
G03X345402Y1612836I200J0D01*
G02Y1609920I-1661J-1458D01*
G03X345352Y1609788I150J-132D01*
G01Y1609168D01*
G02X345150Y1608966I-202J0D01*
G01X342330D01*
G02X342128Y1609168I0J202D01*
G01Y1609788D01*
G03X342078Y1609920I-200J0D01*
G02Y1612836I1661J1458D01*
G03X342128Y1612968I-150J132D01*
G01Y1614906D01*
G03X342078Y1615038I-200J0D01*
G02Y1617954I1661J1458D01*
G03X342128Y1618086I-150J132D01*
G01Y1618706D01*
G02X342330Y1618908I202J0D01*
G37*
G36*
G01X636818D02*
X639638D01*
G02X639840Y1618706I0J-202D01*
G01Y1618086D01*
G03X639890Y1617954I200J0D01*
G02Y1615038I-1661J-1458D01*
G03X639840Y1614906I150J-132D01*
G01Y1612968D01*
G03X639890Y1612836I200J0D01*
G02Y1609920I-1661J-1458D01*
G03X639840Y1609788I150J-132D01*
G01Y1609168D01*
G02X639638Y1608966I-202J0D01*
G01X636818D01*
G02X636616Y1609168I0J202D01*
G01Y1609788D01*
G03X636566Y1609920I-200J0D01*
G02Y1612836I1661J1458D01*
G03X636616Y1612968I-150J132D01*
G01Y1614906D01*
G03X636566Y1615038I-200J0D01*
G02Y1617954I1661J1458D01*
G03X636616Y1618086I-150J132D01*
G01Y1618706D01*
G02X636818Y1618908I202J0D01*
G37*
G36*
G01X671464D02*
X674284D01*
G02X674486Y1618706I0J-202D01*
G01Y1618086D01*
G03X674536Y1617954I200J0D01*
G02Y1615038I-1661J-1458D01*
G03X674486Y1614906I150J-132D01*
G01Y1612968D01*
G03X674536Y1612836I200J0D01*
G02Y1609920I-1661J-1458D01*
G03X674486Y1609788I150J-132D01*
G01Y1609168D01*
G02X674284Y1608966I-202J0D01*
G01X671464D01*
G02X671262Y1609168I0J202D01*
G01Y1609788D01*
G03X671212Y1609920I-200J0D01*
G02Y1612836I1661J1458D01*
G03X671262Y1612968I-150J132D01*
G01Y1614906D01*
G03X671212Y1615038I-200J0D01*
G02Y1617954I1661J1458D01*
G03X671262Y1618086I-150J132D01*
G01Y1618706D01*
G02X671464Y1618908I202J0D01*
G37*
G36*
G01X1156424D02*
X1159244D01*
G02X1159446Y1618706I0J-202D01*
G01Y1618086D01*
G03X1159496Y1617954I200J0D01*
G02Y1615038I-1661J-1458D01*
G03X1159446Y1614906I150J-132D01*
G01Y1612968D01*
G03X1159496Y1612836I200J0D01*
G02Y1609920I-1661J-1458D01*
G03X1159446Y1609788I150J-132D01*
G01Y1609168D01*
G02X1159244Y1608966I-202J0D01*
G01X1156424D01*
G02X1156222Y1609168I0J202D01*
G01Y1609788D01*
G03X1156172Y1609920I-200J0D01*
G02Y1612836I1661J1458D01*
G03X1156222Y1612968I-150J132D01*
G01Y1614906D01*
G03X1156172Y1615038I-200J0D01*
G02Y1617954I1661J1458D01*
G03X1156222Y1618086I-150J132D01*
G01Y1618706D01*
G02X1156424Y1618908I202J0D01*
G37*
G36*
G01X1191070D02*
X1193890D01*
G02X1194092Y1618706I0J-202D01*
G01Y1618086D01*
G03X1194142Y1617954I200J0D01*
G02Y1615038I-1661J-1458D01*
G03X1194092Y1614906I150J-132D01*
G01Y1612968D01*
G03X1194142Y1612836I200J0D01*
G02Y1609920I-1661J-1458D01*
G03X1194092Y1609788I150J-132D01*
G01Y1609168D01*
G02X1193890Y1608966I-202J0D01*
G01X1191070D01*
G02X1190868Y1609168I0J202D01*
G01Y1609788D01*
G03X1190818Y1609920I-200J0D01*
G02Y1612836I1661J1458D01*
G03X1190868Y1612968I-150J132D01*
G01Y1614906D01*
G03X1190818Y1615038I-200J0D01*
G02Y1617954I1661J1458D01*
G03X1190868Y1618086I-150J132D01*
G01Y1618706D01*
G02X1191070Y1618908I202J0D01*
G37*
G36*
G01X1312330D02*
X1315150D01*
G02X1315352Y1618706I0J-202D01*
G01Y1618086D01*
G03X1315402Y1617954I200J0D01*
G02Y1615038I-1661J-1458D01*
G03X1315352Y1614906I150J-132D01*
G01Y1612968D01*
G03X1315402Y1612836I200J0D01*
G02Y1609920I-1661J-1458D01*
G03X1315352Y1609788I150J-132D01*
G01Y1609168D01*
G02X1315150Y1608966I-202J0D01*
G01X1312330D01*
G02X1312128Y1609168I0J202D01*
G01Y1609788D01*
G03X1312078Y1609920I-200J0D01*
G02Y1612836I1661J1458D01*
G03X1312128Y1612968I-150J132D01*
G01Y1614906D01*
G03X1312078Y1615038I-200J0D01*
G02Y1617954I1661J1458D01*
G03X1312128Y1618086I-150J132D01*
G01Y1618706D01*
G02X1312330Y1618908I202J0D01*
G37*
G36*
G01X1346976D02*
X1349796D01*
G02X1349998Y1618706I0J-202D01*
G01Y1618086D01*
G03X1350048Y1617954I200J0D01*
G02Y1615038I-1661J-1458D01*
G03X1349998Y1614906I150J-132D01*
G01Y1612968D01*
G03X1350048Y1612836I200J0D01*
G02Y1609920I-1661J-1458D01*
G03X1349998Y1609788I150J-132D01*
G01Y1609168D01*
G02X1349796Y1608966I-202J0D01*
G01X1346976D01*
G02X1346774Y1609168I0J202D01*
G01Y1609788D01*
G03X1346724Y1609920I-200J0D01*
G02Y1612836I1661J1458D01*
G03X1346774Y1612968I-150J132D01*
G01Y1614906D01*
G03X1346724Y1615038I-200J0D01*
G02Y1617954I1661J1458D01*
G03X1346774Y1618086I-150J132D01*
G01Y1618706D01*
G02X1346976Y1618908I202J0D01*
G37*
G36*
G01X1658786D02*
X1661606D01*
G02X1661808Y1618706I0J-202D01*
G01Y1618086D01*
G03X1661858Y1617954I200J0D01*
G02Y1615038I-1661J-1458D01*
G03X1661808Y1614906I150J-132D01*
G01Y1612968D01*
G03X1661858Y1612836I200J0D01*
G02Y1609920I-1661J-1458D01*
G03X1661808Y1609788I150J-132D01*
G01Y1609168D01*
G02X1661606Y1608966I-202J0D01*
G01X1658786D01*
G02X1658584Y1609168I0J202D01*
G01Y1609788D01*
G03X1658534Y1609920I-200J0D01*
G02Y1612836I1661J1458D01*
G03X1658584Y1612968I-150J132D01*
G01Y1614906D01*
G03X1658534Y1615038I-200J0D01*
G02Y1617954I1661J1458D01*
G03X1658584Y1618086I-150J132D01*
G01Y1618706D01*
G02X1658786Y1618908I202J0D01*
G37*
G36*
G01X1693432D02*
X1696252D01*
G02X1696454Y1618706I0J-202D01*
G01Y1618086D01*
G03X1696504Y1617954I200J0D01*
G02Y1615038I-1661J-1458D01*
G03X1696454Y1614906I150J-132D01*
G01Y1612968D01*
G03X1696504Y1612836I200J0D01*
G02Y1609920I-1661J-1458D01*
G03X1696454Y1609788I150J-132D01*
G01Y1609168D01*
G02X1696252Y1608966I-202J0D01*
G01X1693432D01*
G02X1693230Y1609168I0J202D01*
G01Y1609788D01*
G03X1693180Y1609920I-200J0D01*
G02Y1612836I1661J1458D01*
G03X1693230Y1612968I-150J132D01*
G01Y1614906D01*
G03X1693180Y1615038I-200J0D01*
G02Y1617954I1661J1458D01*
G03X1693230Y1618086I-150J132D01*
G01Y1618706D01*
G02X1693432Y1618908I202J0D01*
G37*
G36*
G01X117133D02*
X119953D01*
G02X120156Y1618706I1J-202D01*
G01Y1618084D01*
G03X120206Y1617952I200J0D01*
G02Y1615040I-1664J-1456D01*
G03X120156Y1614908I150J-132D01*
G01Y1612966D01*
G03X120206Y1612834I200J0D01*
G02Y1609922I-1664J-1456D01*
G03X120156Y1609790I150J-132D01*
G01Y1609168D01*
G02X119953Y1608966I-203J1D01*
G01X117133D01*
G02X116930Y1609168I-1J202D01*
G01Y1609790D01*
G03X116880Y1609922I-200J0D01*
G02Y1612834I1664J1456D01*
G03X116930Y1612966I-150J132D01*
G01Y1614908D01*
G03X116880Y1615040I-200J0D01*
G02Y1617952I1664J1456D01*
G03X116930Y1618084I-150J132D01*
G01Y1618706D01*
G02X117133Y1618908I203J-1D01*
G37*
G36*
G01X151779D02*
X154599D01*
G02X154802Y1618706I1J-202D01*
G01Y1618084D01*
G03X154852Y1617952I200J0D01*
G02Y1615040I-1664J-1456D01*
G03X154802Y1614908I150J-132D01*
G01Y1612966D01*
G03X154852Y1612834I200J0D01*
G02Y1609922I-1664J-1456D01*
G03X154802Y1609790I150J-132D01*
G01Y1609168D01*
G02X154599Y1608966I-203J1D01*
G01X151779D01*
G02X151576Y1609168I-1J202D01*
G01Y1609790D01*
G03X151526Y1609922I-200J0D01*
G02Y1612834I1664J1456D01*
G03X151576Y1612966I-150J132D01*
G01Y1614908D01*
G03X151526Y1615040I-200J0D01*
G02Y1617952I1664J1456D01*
G03X151576Y1618084I-150J132D01*
G01Y1618706D01*
G02X151779Y1618908I203J-1D01*
G37*
G36*
G01X186425D02*
X189245D01*
G02X189448Y1618706I1J-202D01*
G01Y1618084D01*
G03X189498Y1617952I200J0D01*
G02Y1615040I-1664J-1456D01*
G03X189448Y1614908I150J-132D01*
G01Y1612966D01*
G03X189498Y1612834I200J0D01*
G02Y1609922I-1664J-1456D01*
G03X189448Y1609790I150J-132D01*
G01Y1609168D01*
G02X189245Y1608966I-203J1D01*
G01X186425D01*
G02X186222Y1609168I-1J202D01*
G01Y1609790D01*
G03X186172Y1609922I-200J0D01*
G02Y1612834I1664J1456D01*
G03X186222Y1612966I-150J132D01*
G01Y1614908D01*
G03X186172Y1615040I-200J0D01*
G02Y1617952I1664J1456D01*
G03X186222Y1618084I-150J132D01*
G01Y1618706D01*
G02X186425Y1618908I203J-1D01*
G37*
G36*
G01X290361D02*
X293181D01*
G02X293384Y1618706I1J-202D01*
G01Y1618084D01*
G03X293434Y1617952I200J0D01*
G02Y1615040I-1664J-1456D01*
G03X293384Y1614908I150J-132D01*
G01Y1612966D01*
G03X293434Y1612834I200J0D01*
G02Y1609922I-1664J-1456D01*
G03X293384Y1609790I150J-132D01*
G01Y1609168D01*
G02X293181Y1608966I-203J1D01*
G01X290361D01*
G02X290158Y1609168I-1J202D01*
G01Y1609790D01*
G03X290108Y1609922I-200J0D01*
G02Y1612834I1664J1456D01*
G03X290158Y1612966I-150J132D01*
G01Y1614908D01*
G03X290108Y1615040I-200J0D01*
G02Y1617952I1664J1456D01*
G03X290158Y1618084I-150J132D01*
G01Y1618706D01*
G02X290361Y1618908I203J-1D01*
G37*
G36*
G01X325007D02*
X327827D01*
G02X328030Y1618706I1J-202D01*
G01Y1618084D01*
G03X328080Y1617952I200J0D01*
G02Y1615040I-1664J-1456D01*
G03X328030Y1614908I150J-132D01*
G01Y1612966D01*
G03X328080Y1612834I200J0D01*
G02Y1609922I-1664J-1456D01*
G03X328030Y1609790I150J-132D01*
G01Y1609168D01*
G02X327827Y1608966I-203J1D01*
G01X325007D01*
G02X324804Y1609168I-1J202D01*
G01Y1609790D01*
G03X324754Y1609922I-200J0D01*
G02Y1612834I1664J1456D01*
G03X324804Y1612966I-150J132D01*
G01Y1614908D01*
G03X324754Y1615040I-200J0D01*
G02Y1617952I1664J1456D01*
G03X324804Y1618084I-150J132D01*
G01Y1618706D01*
G02X325007Y1618908I203J-1D01*
G37*
G36*
G01X359653D02*
X362473D01*
G02X362676Y1618706I1J-202D01*
G01Y1618084D01*
G03X362726Y1617952I200J0D01*
G02Y1615040I-1664J-1456D01*
G03X362676Y1614908I150J-132D01*
G01Y1612966D01*
G03X362726Y1612834I200J0D01*
G02Y1609922I-1664J-1456D01*
G03X362676Y1609790I150J-132D01*
G01Y1609168D01*
G02X362473Y1608966I-203J1D01*
G01X359653D01*
G02X359450Y1609168I-1J202D01*
G01Y1609790D01*
G03X359400Y1609922I-200J0D01*
G02Y1612834I1664J1456D01*
G03X359450Y1612966I-150J132D01*
G01Y1614908D01*
G03X359400Y1615040I-200J0D01*
G02Y1617952I1664J1456D01*
G03X359450Y1618084I-150J132D01*
G01Y1618706D01*
G02X359653Y1618908I203J-1D01*
G37*
G36*
G01X515559D02*
X518379D01*
G02X518582Y1618706I1J-202D01*
G01Y1618084D01*
G03X518632Y1617952I200J0D01*
G02Y1615040I-1664J-1456D01*
G03X518582Y1614908I150J-132D01*
G01Y1612966D01*
G03X518632Y1612834I200J0D01*
G02Y1609922I-1664J-1456D01*
G03X518582Y1609790I150J-132D01*
G01Y1609168D01*
G02X518379Y1608966I-203J1D01*
G01X515559D01*
G02X515356Y1609168I-1J202D01*
G01Y1609790D01*
G03X515306Y1609922I-200J0D01*
G02Y1612834I1664J1456D01*
G03X515356Y1612966I-150J132D01*
G01Y1614908D01*
G03X515306Y1615040I-200J0D01*
G02Y1617952I1664J1456D01*
G03X515356Y1618084I-150J132D01*
G01Y1618706D01*
G02X515559Y1618908I203J-1D01*
G37*
G36*
G01X654141D02*
X656961D01*
G02X657164Y1618706I1J-202D01*
G01Y1618084D01*
G03X657214Y1617952I200J0D01*
G02Y1615040I-1664J-1456D01*
G03X657164Y1614908I150J-132D01*
G01Y1612966D01*
G03X657214Y1612834I200J0D01*
G02Y1609922I-1664J-1456D01*
G03X657164Y1609790I150J-132D01*
G01Y1609168D01*
G02X656961Y1608966I-203J1D01*
G01X654141D01*
G02X653938Y1609168I-1J202D01*
G01Y1609790D01*
G03X653888Y1609922I-200J0D01*
G02Y1612834I1664J1456D01*
G03X653938Y1612966I-150J132D01*
G01Y1614908D01*
G03X653888Y1615040I-200J0D01*
G02Y1617952I1664J1456D01*
G03X653938Y1618084I-150J132D01*
G01Y1618706D01*
G02X654141Y1618908I203J-1D01*
G37*
G36*
G01X688787D02*
X691607D01*
G02X691810Y1618706I1J-202D01*
G01Y1618084D01*
G03X691860Y1617952I200J0D01*
G02Y1615040I-1664J-1456D01*
G03X691810Y1614908I150J-132D01*
G01Y1612966D01*
G03X691860Y1612834I200J0D01*
G02Y1609922I-1664J-1456D01*
G03X691810Y1609790I150J-132D01*
G01Y1609168D01*
G02X691607Y1608966I-203J1D01*
G01X688787D01*
G02X688584Y1609168I-1J202D01*
G01Y1609790D01*
G03X688534Y1609922I-200J0D01*
G02Y1612834I1664J1456D01*
G03X688584Y1612966I-150J132D01*
G01Y1614908D01*
G03X688534Y1615040I-200J0D01*
G02Y1617952I1664J1456D01*
G03X688584Y1618084I-150J132D01*
G01Y1618706D01*
G02X688787Y1618908I203J-1D01*
G37*
G36*
G01X1139101D02*
X1141921D01*
G02X1142124Y1618706I1J-202D01*
G01Y1618084D01*
G03X1142174Y1617952I200J0D01*
G02Y1615040I-1664J-1456D01*
G03X1142124Y1614908I150J-132D01*
G01Y1612966D01*
G03X1142174Y1612834I200J0D01*
G02Y1609922I-1664J-1456D01*
G03X1142124Y1609790I150J-132D01*
G01Y1609168D01*
G02X1141921Y1608966I-203J1D01*
G01X1139101D01*
G02X1138898Y1609168I-1J202D01*
G01Y1609790D01*
G03X1138848Y1609922I-200J0D01*
G02Y1612834I1664J1456D01*
G03X1138898Y1612966I-150J132D01*
G01Y1614908D01*
G03X1138848Y1615040I-200J0D01*
G02Y1617952I1664J1456D01*
G03X1138898Y1618084I-150J132D01*
G01Y1618706D01*
G02X1139101Y1618908I203J-1D01*
G37*
G36*
G01X1173747D02*
X1176567D01*
G02X1176770Y1618706I1J-202D01*
G01Y1618084D01*
G03X1176820Y1617952I200J0D01*
G02Y1615040I-1664J-1456D01*
G03X1176770Y1614908I150J-132D01*
G01Y1612966D01*
G03X1176820Y1612834I200J0D01*
G02Y1609922I-1664J-1456D01*
G03X1176770Y1609790I150J-132D01*
G01Y1609168D01*
G02X1176567Y1608966I-203J1D01*
G01X1173747D01*
G02X1173544Y1609168I-1J202D01*
G01Y1609790D01*
G03X1173494Y1609922I-200J0D01*
G02Y1612834I1664J1456D01*
G03X1173544Y1612966I-150J132D01*
G01Y1614908D01*
G03X1173494Y1615040I-200J0D01*
G02Y1617952I1664J1456D01*
G03X1173544Y1618084I-150J132D01*
G01Y1618706D01*
G02X1173747Y1618908I203J-1D01*
G37*
G36*
G01X1329653D02*
X1332473D01*
G02X1332676Y1618706I1J-202D01*
G01Y1618084D01*
G03X1332726Y1617952I200J0D01*
G02Y1615040I-1664J-1456D01*
G03X1332676Y1614908I150J-132D01*
G01Y1612966D01*
G03X1332726Y1612834I200J0D01*
G02Y1609922I-1664J-1456D01*
G03X1332676Y1609790I150J-132D01*
G01Y1609168D01*
G02X1332473Y1608966I-203J1D01*
G01X1329653D01*
G02X1329450Y1609168I-1J202D01*
G01Y1609790D01*
G03X1329400Y1609922I-200J0D01*
G02Y1612834I1664J1456D01*
G03X1329450Y1612966I-150J132D01*
G01Y1614908D01*
G03X1329400Y1615040I-200J0D01*
G02Y1617952I1664J1456D01*
G03X1329450Y1618084I-150J132D01*
G01Y1618706D01*
G02X1329653Y1618908I203J-1D01*
G37*
G36*
G01X1364299D02*
X1367119D01*
G02X1367322Y1618706I1J-202D01*
G01Y1618084D01*
G03X1367372Y1617952I200J0D01*
G02Y1615040I-1664J-1456D01*
G03X1367322Y1614908I150J-132D01*
G01Y1612966D01*
G03X1367372Y1612834I200J0D01*
G02Y1609922I-1664J-1456D01*
G03X1367322Y1609790I150J-132D01*
G01Y1609168D01*
G02X1367119Y1608966I-203J1D01*
G01X1364299D01*
G02X1364096Y1609168I-1J202D01*
G01Y1609790D01*
G03X1364046Y1609922I-200J0D01*
G02Y1612834I1664J1456D01*
G03X1364096Y1612966I-150J132D01*
G01Y1614908D01*
G03X1364046Y1615040I-200J0D01*
G02Y1617952I1664J1456D01*
G03X1364096Y1618084I-150J132D01*
G01Y1618706D01*
G02X1364299Y1618908I203J-1D01*
G37*
G36*
G01X1676109D02*
X1678929D01*
G02X1679132Y1618706I1J-202D01*
G01Y1618084D01*
G03X1679182Y1617952I200J0D01*
G02Y1615040I-1664J-1456D01*
G03X1679132Y1614908I150J-132D01*
G01Y1612966D01*
G03X1679182Y1612834I200J0D01*
G02Y1609922I-1664J-1456D01*
G03X1679132Y1609790I150J-132D01*
G01Y1609168D01*
G02X1678929Y1608966I-203J1D01*
G01X1676109D01*
G02X1675906Y1609168I-1J202D01*
G01Y1609790D01*
G03X1675856Y1609922I-200J0D01*
G02Y1612834I1664J1456D01*
G03X1675906Y1612966I-150J132D01*
G01Y1614908D01*
G03X1675856Y1615040I-200J0D01*
G02Y1617952I1664J1456D01*
G03X1675906Y1618084I-150J132D01*
G01Y1618706D01*
G02X1676109Y1618908I203J-1D01*
G37*
G36*
G01X1710755D02*
X1713575D01*
G02X1713778Y1618706I1J-202D01*
G01Y1618084D01*
G03X1713828Y1617952I200J0D01*
G02Y1615040I-1664J-1456D01*
G03X1713778Y1614908I150J-132D01*
G01Y1612966D01*
G03X1713828Y1612834I200J0D01*
G02Y1609922I-1664J-1456D01*
G03X1713778Y1609790I150J-132D01*
G01Y1609168D01*
G02X1713575Y1608966I-203J1D01*
G01X1710755D01*
G02X1710552Y1609168I-1J202D01*
G01Y1609790D01*
G03X1710502Y1609922I-200J0D01*
G02Y1612834I1664J1456D01*
G03X1710552Y1612966I-150J132D01*
G01Y1614908D01*
G03X1710502Y1615040I-200J0D01*
G02Y1617952I1664J1456D01*
G03X1710552Y1618084I-150J132D01*
G01Y1618706D01*
G02X1710755Y1618908I203J-1D01*
G37*
G36*
G01X1522570Y1409998D02*
X1525970D01*
G02Y1406992I0J-1503D01*
G01X1522570D01*
G02Y1409998I0J1503D01*
G37*
G36*
G01X1559290Y1349690D02*
X1562690D01*
G02Y1346684I0J-1503D01*
G01X1559290D01*
G02Y1349690I0J1503D01*
G37*
G36*
G01X1522570Y1385800D02*
X1525970D01*
G02Y1382794I0J-1503D01*
G01X1522570D01*
G02Y1385800I0J1503D01*
G37*
G36*
G01Y1373888D02*
X1525970D01*
G02Y1370882I0J-1503D01*
G01X1522570D01*
G02Y1373888I0J1503D01*
G37*
G36*
G01Y1398086D02*
X1525970D01*
G02Y1395080I0J-1503D01*
G01X1522570D01*
G02Y1398086I0J1503D01*
G37*
G36*
G01X1510330Y1373888D02*
X1513730D01*
G02Y1370882I0J-1503D01*
G01X1510330D01*
G02Y1373888I0J1503D01*
G37*
G36*
G01X1547050Y1361602D02*
X1550450D01*
G02Y1358596I0J-1503D01*
G01X1547050D01*
G02Y1361602I0J1503D01*
G37*
G36*
G01X1534810D02*
X1538210D01*
G02Y1358596I0J-1503D01*
G01X1534810D01*
G02Y1361602I0J1503D01*
G37*
G36*
G01X1547050Y1349690D02*
X1550450D01*
G02Y1346684I0J-1503D01*
G01X1547050D01*
G02Y1349690I0J1503D01*
G37*
G36*
G01X1534810D02*
X1538210D01*
G02Y1346684I0J-1503D01*
G01X1534810D01*
G02Y1349690I0J1503D01*
G37*
G36*
G01X241623Y1373888D02*
X245023D01*
G02Y1370882I0J-1503D01*
G01X241623D01*
G02Y1373888I0J1503D01*
G37*
G36*
G01Y1361602D02*
X245023D01*
G02Y1358596I0J-1503D01*
G01X241623D01*
G02Y1361602I0J1503D01*
G37*
G36*
G01X1485850Y1409998D02*
X1489250D01*
G02Y1406992I0J-1503D01*
G01X1485850D01*
G02Y1409998I0J1503D01*
G37*
G36*
G01X1510330Y1349690D02*
X1513730D01*
G02Y1346684I0J-1503D01*
G01X1510330D01*
G02Y1349690I0J1503D01*
G37*
G36*
G01X364023Y1398086D02*
X367423D01*
G02Y1395080I0J-1503D01*
G01X364023D01*
G02Y1398086I0J1503D01*
G37*
G36*
G01X1485850Y1385800D02*
X1489250D01*
G02Y1382794I0J-1503D01*
G01X1485850D01*
G02Y1385800I0J1503D01*
G37*
G36*
G01X1473610D02*
X1477010D01*
G02Y1382794I0J-1503D01*
G01X1473610D01*
G02Y1385800I0J1503D01*
G37*
G36*
G01Y1361602D02*
X1477010D01*
G02Y1358596I0J-1503D01*
G01X1473610D01*
G02Y1361602I0J1503D01*
G37*
G36*
G01Y1349690D02*
X1477010D01*
G02Y1346684I0J-1503D01*
G01X1473610D01*
G02Y1349690I0J1503D01*
G37*
G36*
G01X1461370Y1385800D02*
X1464770D01*
G02Y1382794I0J-1503D01*
G01X1461370D01*
G02Y1385800I0J1503D01*
G37*
G36*
G01Y1373888D02*
X1464770D01*
G02Y1370882I0J-1503D01*
G01X1461370D01*
G02Y1373888I0J1503D01*
G37*
G36*
G01Y1361602D02*
X1464770D01*
G02Y1358596I0J-1503D01*
G01X1461370D01*
G02Y1361602I0J1503D01*
G37*
G36*
G01Y1349690D02*
X1464770D01*
G02Y1346684I0J-1503D01*
G01X1461370D01*
G02Y1349690I0J1503D01*
G37*
G36*
G01X1485850Y1373888D02*
X1489250D01*
G02Y1370882I0J-1503D01*
G01X1485850D01*
G02Y1373888I0J1503D01*
G37*
G36*
G01X1498090Y1361602D02*
X1501490D01*
G02Y1358596I0J-1503D01*
G01X1498090D01*
G02Y1361602I0J1503D01*
G37*
G36*
G01X1485850D02*
X1489250D01*
G02Y1358596I0J-1503D01*
G01X1485850D01*
G02Y1361602I0J1503D01*
G37*
G36*
G01X253863Y1409998D02*
X257263D01*
G02Y1406992I0J-1503D01*
G01X253863D01*
G02Y1409998I0J1503D01*
G37*
G36*
G01X266103Y1373888D02*
X269503D01*
G02Y1370882I0J-1503D01*
G01X266103D01*
G02Y1373888I0J1503D01*
G37*
G36*
G01X290583Y1361602D02*
X293983D01*
G02Y1358596I0J-1503D01*
G01X290583D01*
G02Y1361602I0J1503D01*
G37*
G36*
G01X327303Y1349690D02*
X330703D01*
G02Y1346684I0J-1503D01*
G01X327303D01*
G02Y1349690I0J1503D01*
G37*
G36*
G01X290583Y1385800D02*
X293983D01*
G02Y1382794I0J-1503D01*
G01X290583D01*
G02Y1385800I0J1503D01*
G37*
G36*
G01Y1409998D02*
X293983D01*
G02Y1406992I0J-1503D01*
G01X290583D01*
G02Y1409998I0J1503D01*
G37*
G36*
G01X253863Y1398086D02*
X257263D01*
G02Y1395080I0J-1503D01*
G01X253863D01*
G02Y1398086I0J1503D01*
G37*
G36*
G01X364023Y1361602D02*
X367423D01*
G02Y1358596I0J-1503D01*
G01X364023D01*
G02Y1361602I0J1503D01*
G37*
G36*
G01X339543Y1349690D02*
X342943D01*
G02Y1346684I0J-1503D01*
G01X339543D01*
G02Y1349690I0J1503D01*
G37*
G36*
G01X241623D02*
X245023D01*
G02Y1346684I0J-1503D01*
G01X241623D01*
G02Y1349690I0J1503D01*
G37*
G36*
G01X339543Y1361602D02*
X342943D01*
G02Y1358596I0J-1503D01*
G01X339543D01*
G02Y1361602I0J1503D01*
G37*
G36*
G01X302823Y1409998D02*
X306223D01*
G02Y1406992I0J-1503D01*
G01X302823D01*
G02Y1409998I0J1503D01*
G37*
G36*
G01X364023Y1385800D02*
X367423D01*
G02Y1382794I0J-1503D01*
G01X364023D01*
G02Y1385800I0J1503D01*
G37*
G36*
G01X290583Y1398086D02*
X293983D01*
G02Y1395080I0J-1503D01*
G01X290583D01*
G02Y1398086I0J1503D01*
G37*
G36*
G01X112832D02*
X116232D01*
G02Y1395080I0J-1503D01*
G01X112832D01*
G02Y1398086I0J1503D01*
G37*
G36*
G01X364023Y1373888D02*
X367423D01*
G02Y1370882I0J-1503D01*
G01X364023D01*
G02Y1373888I0J1503D01*
G37*
G36*
G01X302823Y1361602D02*
X306223D01*
G02Y1358596I0J-1503D01*
G01X302823D01*
G02Y1361602I0J1503D01*
G37*
G36*
G01X1534810Y1409998D02*
X1538210D01*
G02Y1406992I0J-1503D01*
G01X1534810D01*
G02Y1409998I0J1503D01*
G37*
G36*
G01X1510330Y1385800D02*
X1513730D01*
G02Y1382794I0J-1503D01*
G01X1510330D01*
G02Y1385800I0J1503D01*
G37*
G36*
G01X1534810Y1398086D02*
X1538210D01*
G02Y1395080I0J-1503D01*
G01X1534810D01*
G02Y1398086I0J1503D01*
G37*
G36*
G01X302823Y1349690D02*
X306223D01*
G02Y1346684I0J-1503D01*
G01X302823D01*
G02Y1349690I0J1503D01*
G37*
G36*
G01X88352Y1373888D02*
X91752D01*
G02Y1370882I0J-1503D01*
G01X88352D01*
G02Y1373888I0J1503D01*
G37*
G36*
G01X339543Y1385800D02*
X342943D01*
G02Y1382794I0J-1503D01*
G01X339543D01*
G02Y1385800I0J1503D01*
G37*
G36*
G01X327303Y1373888D02*
X330703D01*
G02Y1370882I0J-1503D01*
G01X327303D01*
G02Y1373888I0J1503D01*
G37*
G36*
G01Y1409998D02*
X330703D01*
G02Y1406992I0J-1503D01*
G01X327303D01*
G02Y1409998I0J1503D01*
G37*
G36*
G01X278343Y1398086D02*
X281743D01*
G02Y1395080I0J-1503D01*
G01X278343D01*
G02Y1398086I0J1503D01*
G37*
G36*
G01X351783Y1349690D02*
X355183D01*
G02Y1346684I0J-1503D01*
G01X351783D01*
G02Y1349690I0J1503D01*
G37*
G36*
G01X186272Y1385800D02*
X189672D01*
G02Y1382794I0J-1503D01*
G01X186272D01*
G02Y1385800I0J1503D01*
G37*
G36*
G01Y1373888D02*
X189672D01*
G02Y1370882I0J-1503D01*
G01X186272D01*
G02Y1373888I0J1503D01*
G37*
G36*
G01X315063Y1361602D02*
X318463D01*
G02Y1358596I0J-1503D01*
G01X315063D01*
G02Y1361602I0J1503D01*
G37*
G36*
G01X327303D02*
X330703D01*
G02Y1358596I0J-1503D01*
G01X327303D01*
G02Y1361602I0J1503D01*
G37*
G36*
G01X315063Y1349690D02*
X318463D01*
G02Y1346684I0J-1503D01*
G01X315063D01*
G02Y1349690I0J1503D01*
G37*
G36*
G01X174032Y1398086D02*
X177432D01*
G02Y1395080I0J-1503D01*
G01X174032D01*
G02Y1398086I0J1503D01*
G37*
G36*
G01X266103Y1349690D02*
X269503D01*
G02Y1346684I0J-1503D01*
G01X266103D01*
G02Y1349690I0J1503D01*
G37*
G36*
G01X1054713Y1361602D02*
X1058113D01*
G02Y1358596I0J-1503D01*
G01X1054713D01*
G02Y1361602I0J1503D01*
G37*
G36*
G01Y1349690D02*
X1058113D01*
G02Y1346684I0J-1503D01*
G01X1054713D01*
G02Y1349690I0J1503D01*
G37*
G36*
G01Y1385800D02*
X1058113D01*
G02Y1382794I0J-1503D01*
G01X1054713D01*
G02Y1385800I0J1503D01*
G37*
G36*
G01Y1373888D02*
X1058113D01*
G02Y1370882I0J-1503D01*
G01X1054713D01*
G02Y1373888I0J1503D01*
G37*
G36*
G01X1177113Y1409998D02*
X1180513D01*
G02Y1406992I0J-1503D01*
G01X1177113D01*
G02Y1409998I0J1503D01*
G37*
G36*
G01Y1398086D02*
X1180513D01*
G02Y1395080I0J-1503D01*
G01X1177113D01*
G02Y1398086I0J1503D01*
G37*
G36*
G01Y1373888D02*
X1180513D01*
G02Y1370882I0J-1503D01*
G01X1177113D01*
G02Y1373888I0J1503D01*
G37*
G36*
G01Y1385800D02*
X1180513D01*
G02Y1382794I0J-1503D01*
G01X1177113D01*
G02Y1385800I0J1503D01*
G37*
G36*
G01Y1361602D02*
X1180513D01*
G02Y1358596I0J-1503D01*
G01X1177113D01*
G02Y1361602I0J1503D01*
G37*
G36*
G01Y1349690D02*
X1180513D01*
G02Y1346684I0J-1503D01*
G01X1177113D01*
G02Y1349690I0J1503D01*
G37*
G36*
G01X1164873Y1409998D02*
X1168273D01*
G02Y1406992I0J-1503D01*
G01X1164873D01*
G02Y1409998I0J1503D01*
G37*
G36*
G01Y1398086D02*
X1168273D01*
G02Y1395080I0J-1503D01*
G01X1164873D01*
G02Y1398086I0J1503D01*
G37*
G36*
G01Y1385800D02*
X1168273D01*
G02Y1382794I0J-1503D01*
G01X1164873D01*
G02Y1385800I0J1503D01*
G37*
G36*
G01Y1373888D02*
X1168273D01*
G02Y1370882I0J-1503D01*
G01X1164873D01*
G02Y1373888I0J1503D01*
G37*
G36*
G01Y1361602D02*
X1168273D01*
G02Y1358596I0J-1503D01*
G01X1164873D01*
G02Y1361602I0J1503D01*
G37*
G36*
G01Y1349690D02*
X1168273D01*
G02Y1346684I0J-1503D01*
G01X1164873D01*
G02Y1349690I0J1503D01*
G37*
G36*
G01X1152633Y1409998D02*
X1156033D01*
G02Y1406992I0J-1503D01*
G01X1152633D01*
G02Y1409998I0J1503D01*
G37*
G36*
G01Y1398086D02*
X1156033D01*
G02Y1395080I0J-1503D01*
G01X1152633D01*
G02Y1398086I0J1503D01*
G37*
G36*
G01Y1373888D02*
X1156033D01*
G02Y1370882I0J-1503D01*
G01X1152633D01*
G02Y1373888I0J1503D01*
G37*
G36*
G01Y1385800D02*
X1156033D01*
G02Y1382794I0J-1503D01*
G01X1152633D01*
G02Y1385800I0J1503D01*
G37*
G36*
G01Y1361602D02*
X1156033D01*
G02Y1358596I0J-1503D01*
G01X1152633D01*
G02Y1361602I0J1503D01*
G37*
G36*
G01Y1349690D02*
X1156033D01*
G02Y1346684I0J-1503D01*
G01X1152633D01*
G02Y1349690I0J1503D01*
G37*
G36*
G01X1128153Y1409998D02*
X1131553D01*
G02Y1406992I0J-1503D01*
G01X1128153D01*
G02Y1409998I0J1503D01*
G37*
G36*
G01X1140393D02*
X1143793D01*
G02Y1406992I0J-1503D01*
G01X1140393D01*
G02Y1409998I0J1503D01*
G37*
G36*
G01X1128153Y1398086D02*
X1131553D01*
G02Y1395080I0J-1503D01*
G01X1128153D01*
G02Y1398086I0J1503D01*
G37*
G36*
G01X1140393D02*
X1143793D01*
G02Y1395080I0J-1503D01*
G01X1140393D01*
G02Y1398086I0J1503D01*
G37*
G36*
G01X1128153Y1373888D02*
X1131553D01*
G02Y1370882I0J-1503D01*
G01X1128153D01*
G02Y1373888I0J1503D01*
G37*
G36*
G01Y1385800D02*
X1131553D01*
G02Y1382794I0J-1503D01*
G01X1128153D01*
G02Y1385800I0J1503D01*
G37*
G36*
G01X1140393D02*
X1143793D01*
G02Y1382794I0J-1503D01*
G01X1140393D01*
G02Y1385800I0J1503D01*
G37*
G36*
G01Y1373888D02*
X1143793D01*
G02Y1370882I0J-1503D01*
G01X1140393D01*
G02Y1373888I0J1503D01*
G37*
G36*
G01X1128153Y1361602D02*
X1131553D01*
G02Y1358596I0J-1503D01*
G01X1128153D01*
G02Y1361602I0J1503D01*
G37*
G36*
G01X1140393D02*
X1143793D01*
G02Y1358596I0J-1503D01*
G01X1140393D01*
G02Y1361602I0J1503D01*
G37*
G36*
G01X1128153Y1349690D02*
X1131553D01*
G02Y1346684I0J-1503D01*
G01X1128153D01*
G02Y1349690I0J1503D01*
G37*
G36*
G01X1140393D02*
X1143793D01*
G02Y1346684I0J-1503D01*
G01X1140393D01*
G02Y1349690I0J1503D01*
G37*
G36*
G01X1115913Y1409998D02*
X1119313D01*
G02Y1406992I0J-1503D01*
G01X1115913D01*
G02Y1409998I0J1503D01*
G37*
G36*
G01Y1398086D02*
X1119313D01*
G02Y1395080I0J-1503D01*
G01X1115913D01*
G02Y1398086I0J1503D01*
G37*
G36*
G01Y1373888D02*
X1119313D01*
G02Y1370882I0J-1503D01*
G01X1115913D01*
G02Y1373888I0J1503D01*
G37*
G36*
G01Y1385800D02*
X1119313D01*
G02Y1382794I0J-1503D01*
G01X1115913D01*
G02Y1385800I0J1503D01*
G37*
G36*
G01Y1361602D02*
X1119313D01*
G02Y1358596I0J-1503D01*
G01X1115913D01*
G02Y1361602I0J1503D01*
G37*
G36*
G01Y1349690D02*
X1119313D01*
G02Y1346684I0J-1503D01*
G01X1115913D01*
G02Y1349690I0J1503D01*
G37*
G36*
G01X1103673Y1409998D02*
X1107073D01*
G02Y1406992I0J-1503D01*
G01X1103673D01*
G02Y1409998I0J1503D01*
G37*
G36*
G01Y1398086D02*
X1107073D01*
G02Y1395080I0J-1503D01*
G01X1103673D01*
G02Y1398086I0J1503D01*
G37*
G36*
G01Y1385800D02*
X1107073D01*
G02Y1382794I0J-1503D01*
G01X1103673D01*
G02Y1385800I0J1503D01*
G37*
G36*
G01Y1373888D02*
X1107073D01*
G02Y1370882I0J-1503D01*
G01X1103673D01*
G02Y1373888I0J1503D01*
G37*
G36*
G01Y1361602D02*
X1107073D01*
G02Y1358596I0J-1503D01*
G01X1103673D01*
G02Y1361602I0J1503D01*
G37*
G36*
G01Y1349690D02*
X1107073D01*
G02Y1346684I0J-1503D01*
G01X1103673D01*
G02Y1349690I0J1503D01*
G37*
G36*
G01X1079193Y1409998D02*
X1082593D01*
G02Y1406992I0J-1503D01*
G01X1079193D01*
G02Y1409998I0J1503D01*
G37*
G36*
G01X1091433D02*
X1094833D01*
G02Y1406992I0J-1503D01*
G01X1091433D01*
G02Y1409998I0J1503D01*
G37*
G36*
G01X1079193Y1398086D02*
X1082593D01*
G02Y1395080I0J-1503D01*
G01X1079193D01*
G02Y1398086I0J1503D01*
G37*
G36*
G01X1091433D02*
X1094833D01*
G02Y1395080I0J-1503D01*
G01X1091433D01*
G02Y1398086I0J1503D01*
G37*
G36*
G01X1079193Y1385800D02*
X1082593D01*
G02Y1382794I0J-1503D01*
G01X1079193D01*
G02Y1385800I0J1503D01*
G37*
G36*
G01Y1373888D02*
X1082593D01*
G02Y1370882I0J-1503D01*
G01X1079193D01*
G02Y1373888I0J1503D01*
G37*
G36*
G01X1091433Y1385800D02*
X1094833D01*
G02Y1382794I0J-1503D01*
G01X1091433D01*
G02Y1385800I0J1503D01*
G37*
G36*
G01Y1373888D02*
X1094833D01*
G02Y1370882I0J-1503D01*
G01X1091433D01*
G02Y1373888I0J1503D01*
G37*
G36*
G01X1079193Y1361602D02*
X1082593D01*
G02Y1358596I0J-1503D01*
G01X1079193D01*
G02Y1361602I0J1503D01*
G37*
G36*
G01X1091433D02*
X1094833D01*
G02Y1358596I0J-1503D01*
G01X1091433D01*
G02Y1361602I0J1503D01*
G37*
G36*
G01X1079193Y1349690D02*
X1082593D01*
G02Y1346684I0J-1503D01*
G01X1079193D01*
G02Y1349690I0J1503D01*
G37*
G36*
G01X1091433D02*
X1094833D01*
G02Y1346684I0J-1503D01*
G01X1091433D01*
G02Y1349690I0J1503D01*
G37*
G36*
G01X1066953Y1409998D02*
X1070353D01*
G02Y1406992I0J-1503D01*
G01X1066953D01*
G02Y1409998I0J1503D01*
G37*
G36*
G01Y1398086D02*
X1070353D01*
G02Y1395080I0J-1503D01*
G01X1066953D01*
G02Y1398086I0J1503D01*
G37*
G36*
G01X290583Y1349690D02*
X293983D01*
G02Y1346684I0J-1503D01*
G01X290583D01*
G02Y1349690I0J1503D01*
G37*
G36*
G01X241623Y1385800D02*
X245023D01*
G02Y1382794I0J-1503D01*
G01X241623D01*
G02Y1385800I0J1503D01*
G37*
G36*
G01X253863Y1361602D02*
X257263D01*
G02Y1358596I0J-1503D01*
G01X253863D01*
G02Y1361602I0J1503D01*
G37*
G36*
G01Y1349690D02*
X257263D01*
G02Y1346684I0J-1503D01*
G01X253863D01*
G02Y1349690I0J1503D01*
G37*
G36*
G01X1547050Y1409998D02*
X1550450D01*
G02Y1406992I0J-1503D01*
G01X1547050D01*
G02Y1409998I0J1503D01*
G37*
G36*
G01X1559290Y1385800D02*
X1562690D01*
G02Y1382794I0J-1503D01*
G01X1559290D01*
G02Y1385800I0J1503D01*
G37*
G36*
G01X1230326Y1349690D02*
X1233726D01*
G02Y1346684I0J-1503D01*
G01X1230326D01*
G02Y1349690I0J1503D01*
G37*
G36*
G01Y1361602D02*
X1233726D01*
G02Y1358596I0J-1503D01*
G01X1230326D01*
G02Y1361602I0J1503D01*
G37*
G36*
G01Y1373888D02*
X1233726D01*
G02Y1370882I0J-1503D01*
G01X1230326D01*
G02Y1373888I0J1503D01*
G37*
G36*
G01Y1385800D02*
X1233726D01*
G02Y1382794I0J-1503D01*
G01X1230326D01*
G02Y1385800I0J1503D01*
G37*
G36*
G01X1242566Y1349690D02*
X1245966D01*
G02Y1346684I0J-1503D01*
G01X1242566D01*
G02Y1349690I0J1503D01*
G37*
G36*
G01Y1361602D02*
X1245966D01*
G02Y1358596I0J-1503D01*
G01X1242566D01*
G02Y1361602I0J1503D01*
G37*
G36*
G01Y1385800D02*
X1245966D01*
G02Y1382794I0J-1503D01*
G01X1242566D01*
G02Y1385800I0J1503D01*
G37*
G36*
G01Y1373888D02*
X1245966D01*
G02Y1370882I0J-1503D01*
G01X1242566D01*
G02Y1373888I0J1503D01*
G37*
G36*
G01Y1398086D02*
X1245966D01*
G02Y1395080I0J-1503D01*
G01X1242566D01*
G02Y1398086I0J1503D01*
G37*
G36*
G01Y1409998D02*
X1245966D01*
G02Y1406992I0J-1503D01*
G01X1242566D01*
G02Y1409998I0J1503D01*
G37*
G36*
G01X1267046Y1349690D02*
X1270446D01*
G02Y1346684I0J-1503D01*
G01X1267046D01*
G02Y1349690I0J1503D01*
G37*
G36*
G01X1254806D02*
X1258206D01*
G02Y1346684I0J-1503D01*
G01X1254806D01*
G02Y1349690I0J1503D01*
G37*
G36*
G01X1267046Y1361602D02*
X1270446D01*
G02Y1358596I0J-1503D01*
G01X1267046D01*
G02Y1361602I0J1503D01*
G37*
G36*
G01X1254806D02*
X1258206D01*
G02Y1358596I0J-1503D01*
G01X1254806D01*
G02Y1361602I0J1503D01*
G37*
G36*
G01X1267046Y1385800D02*
X1270446D01*
G02Y1382794I0J-1503D01*
G01X1267046D01*
G02Y1385800I0J1503D01*
G37*
G36*
G01Y1373888D02*
X1270446D01*
G02Y1370882I0J-1503D01*
G01X1267046D01*
G02Y1373888I0J1503D01*
G37*
G36*
G01X1254806D02*
X1258206D01*
G02Y1370882I0J-1503D01*
G01X1254806D01*
G02Y1373888I0J1503D01*
G37*
G36*
G01Y1385800D02*
X1258206D01*
G02Y1382794I0J-1503D01*
G01X1254806D01*
G02Y1385800I0J1503D01*
G37*
G36*
G01X1267046Y1398086D02*
X1270446D01*
G02Y1395080I0J-1503D01*
G01X1267046D01*
G02Y1398086I0J1503D01*
G37*
G36*
G01X1254806D02*
X1258206D01*
G02Y1395080I0J-1503D01*
G01X1254806D01*
G02Y1398086I0J1503D01*
G37*
G36*
G01X1267046Y1409998D02*
X1270446D01*
G02Y1406992I0J-1503D01*
G01X1267046D01*
G02Y1409998I0J1503D01*
G37*
G36*
G01X1254806D02*
X1258206D01*
G02Y1406992I0J-1503D01*
G01X1254806D01*
G02Y1409998I0J1503D01*
G37*
G36*
G01X1279286Y1349690D02*
X1282686D01*
G02Y1346684I0J-1503D01*
G01X1279286D01*
G02Y1349690I0J1503D01*
G37*
G36*
G01Y1361602D02*
X1282686D01*
G02Y1358596I0J-1503D01*
G01X1279286D01*
G02Y1361602I0J1503D01*
G37*
G36*
G01X1510330D02*
X1513730D01*
G02Y1358596I0J-1503D01*
G01X1510330D01*
G02Y1361602I0J1503D01*
G37*
G36*
G01X1279286Y1373888D02*
X1282686D01*
G02Y1370882I0J-1503D01*
G01X1279286D01*
G02Y1373888I0J1503D01*
G37*
G36*
G01Y1385800D02*
X1282686D01*
G02Y1382794I0J-1503D01*
G01X1279286D01*
G02Y1385800I0J1503D01*
G37*
G36*
G01X1648118Y1409998D02*
X1651518D01*
G02Y1406992I0J-1503D01*
G01X1648118D01*
G02Y1409998I0J1503D01*
G37*
G36*
G01X1279286Y1398086D02*
X1282686D01*
G02Y1395080I0J-1503D01*
G01X1279286D01*
G02Y1398086I0J1503D01*
G37*
G36*
G01Y1409998D02*
X1282686D01*
G02Y1406992I0J-1503D01*
G01X1279286D01*
G02Y1409998I0J1503D01*
G37*
G36*
G01X1291526Y1349690D02*
X1294926D01*
G02Y1346684I0J-1503D01*
G01X1291526D01*
G02Y1349690I0J1503D01*
G37*
G36*
G01X1559290Y1398086D02*
X1562690D01*
G02Y1395080I0J-1503D01*
G01X1559290D01*
G02Y1398086I0J1503D01*
G37*
G36*
G01X161792Y1409998D02*
X165192D01*
G02Y1406992I0J-1503D01*
G01X161792D01*
G02Y1409998I0J1503D01*
G37*
G36*
G01X186272Y1349690D02*
X189672D01*
G02Y1346684I0J-1503D01*
G01X186272D01*
G02Y1349690I0J1503D01*
G37*
G36*
G01X315063Y1409998D02*
X318463D01*
G02Y1406992I0J-1503D01*
G01X315063D01*
G02Y1409998I0J1503D01*
G37*
G36*
G01X1534810Y1373888D02*
X1538210D01*
G02Y1370882I0J-1503D01*
G01X1534810D01*
G02Y1373888I0J1503D01*
G37*
G36*
G01X1559290Y1409998D02*
X1562690D01*
G02Y1406992I0J-1503D01*
G01X1559290D01*
G02Y1409998I0J1503D01*
G37*
G36*
G01X351783Y1361602D02*
X355183D01*
G02Y1358596I0J-1503D01*
G01X351783D01*
G02Y1361602I0J1503D01*
G37*
G36*
G01X198512Y1385800D02*
X201912D01*
G02Y1382794I0J-1503D01*
G01X198512D01*
G02Y1385800I0J1503D01*
G37*
G36*
G01X1291526Y1361602D02*
X1294926D01*
G02Y1358596I0J-1503D01*
G01X1291526D01*
G02Y1361602I0J1503D01*
G37*
G36*
G01X1635878Y1349690D02*
X1639278D01*
G02Y1346684I0J-1503D01*
G01X1635878D01*
G02Y1349690I0J1503D01*
G37*
G36*
G01Y1361602D02*
X1639278D01*
G02Y1358596I0J-1503D01*
G01X1635878D01*
G02Y1361602I0J1503D01*
G37*
G36*
G01X1291526Y1385800D02*
X1294926D01*
G02Y1382794I0J-1503D01*
G01X1291526D01*
G02Y1385800I0J1503D01*
G37*
G36*
G01Y1373888D02*
X1294926D01*
G02Y1370882I0J-1503D01*
G01X1291526D01*
G02Y1373888I0J1503D01*
G37*
G36*
G01X1635878Y1385800D02*
X1639278D01*
G02Y1382794I0J-1503D01*
G01X1635878D01*
G02Y1385800I0J1503D01*
G37*
G36*
G01Y1373888D02*
X1639278D01*
G02Y1370882I0J-1503D01*
G01X1635878D01*
G02Y1373888I0J1503D01*
G37*
G36*
G01Y1398086D02*
X1639278D01*
G02Y1395080I0J-1503D01*
G01X1635878D01*
G02Y1398086I0J1503D01*
G37*
G36*
G01X1623638Y1349690D02*
X1627038D01*
G02Y1346684I0J-1503D01*
G01X1623638D01*
G02Y1349690I0J1503D01*
G37*
G36*
G01X1611398D02*
X1614798D01*
G02Y1346684I0J-1503D01*
G01X1611398D01*
G02Y1349690I0J1503D01*
G37*
G36*
G01X1623638Y1361602D02*
X1627038D01*
G02Y1358596I0J-1503D01*
G01X1623638D01*
G02Y1361602I0J1503D01*
G37*
G36*
G01X1291526Y1398086D02*
X1294926D01*
G02Y1395080I0J-1503D01*
G01X1291526D01*
G02Y1398086I0J1503D01*
G37*
G36*
G01Y1409998D02*
X1294926D01*
G02Y1406992I0J-1503D01*
G01X1291526D01*
G02Y1409998I0J1503D01*
G37*
G36*
G01X1316006Y1349690D02*
X1319406D01*
G02Y1346684I0J-1503D01*
G01X1316006D01*
G02Y1349690I0J1503D01*
G37*
G36*
G01X1303766D02*
X1307166D01*
G02Y1346684I0J-1503D01*
G01X1303766D01*
G02Y1349690I0J1503D01*
G37*
G36*
G01X1316006Y1361602D02*
X1319406D01*
G02Y1358596I0J-1503D01*
G01X1316006D01*
G02Y1361602I0J1503D01*
G37*
G36*
G01X1303766D02*
X1307166D01*
G02Y1358596I0J-1503D01*
G01X1303766D01*
G02Y1361602I0J1503D01*
G37*
G36*
G01X1316006Y1385800D02*
X1319406D01*
G02Y1382794I0J-1503D01*
G01X1316006D01*
G02Y1385800I0J1503D01*
G37*
G36*
G01X1611398Y1373888D02*
X1614798D01*
G02Y1370882I0J-1503D01*
G01X1611398D01*
G02Y1373888I0J1503D01*
G37*
G36*
G01Y1385800D02*
X1614798D01*
G02Y1382794I0J-1503D01*
G01X1611398D01*
G02Y1385800I0J1503D01*
G37*
G36*
G01X1623638Y1398086D02*
X1627038D01*
G02Y1395080I0J-1503D01*
G01X1623638D01*
G02Y1398086I0J1503D01*
G37*
G36*
G01X1316006Y1373888D02*
X1319406D01*
G02Y1370882I0J-1503D01*
G01X1316006D01*
G02Y1373888I0J1503D01*
G37*
G36*
G01X1303766D02*
X1307166D01*
G02Y1370882I0J-1503D01*
G01X1303766D01*
G02Y1373888I0J1503D01*
G37*
G36*
G01Y1385800D02*
X1307166D01*
G02Y1382794I0J-1503D01*
G01X1303766D01*
G02Y1385800I0J1503D01*
G37*
G36*
G01X1316006Y1398086D02*
X1319406D01*
G02Y1395080I0J-1503D01*
G01X1316006D01*
G02Y1398086I0J1503D01*
G37*
G36*
G01X1303766D02*
X1307166D01*
G02Y1395080I0J-1503D01*
G01X1303766D01*
G02Y1398086I0J1503D01*
G37*
G36*
G01X1316006Y1409998D02*
X1319406D01*
G02Y1406992I0J-1503D01*
G01X1316006D01*
G02Y1409998I0J1503D01*
G37*
G36*
G01X1303766D02*
X1307166D01*
G02Y1406992I0J-1503D01*
G01X1303766D01*
G02Y1409998I0J1503D01*
G37*
G36*
G01X1623638D02*
X1627038D01*
G02Y1406992I0J-1503D01*
G01X1623638D01*
G02Y1409998I0J1503D01*
G37*
G36*
G01X1328246Y1349690D02*
X1331646D01*
G02Y1346684I0J-1503D01*
G01X1328246D01*
G02Y1349690I0J1503D01*
G37*
G36*
G01Y1361602D02*
X1331646D01*
G02Y1358596I0J-1503D01*
G01X1328246D01*
G02Y1361602I0J1503D01*
G37*
G36*
G01X1648118Y1398086D02*
X1651518D01*
G02Y1395080I0J-1503D01*
G01X1648118D01*
G02Y1398086I0J1503D01*
G37*
G36*
G01Y1373888D02*
X1651518D01*
G02Y1370882I0J-1503D01*
G01X1648118D01*
G02Y1373888I0J1503D01*
G37*
G36*
G01Y1385800D02*
X1651518D01*
G02Y1382794I0J-1503D01*
G01X1648118D01*
G02Y1385800I0J1503D01*
G37*
G36*
G01X1328246Y1373888D02*
X1331646D01*
G02Y1370882I0J-1503D01*
G01X1328246D01*
G02Y1373888I0J1503D01*
G37*
G36*
G01X1648118Y1361602D02*
X1651518D01*
G02Y1358596I0J-1503D01*
G01X1648118D01*
G02Y1361602I0J1503D01*
G37*
G36*
G01Y1349690D02*
X1651518D01*
G02Y1346684I0J-1503D01*
G01X1648118D01*
G02Y1349690I0J1503D01*
G37*
G36*
G01X1635878Y1409998D02*
X1639278D01*
G02Y1406992I0J-1503D01*
G01X1635878D01*
G02Y1409998I0J1503D01*
G37*
G36*
G01X1660358D02*
X1663758D01*
G02Y1406992I0J-1503D01*
G01X1660358D01*
G02Y1409998I0J1503D01*
G37*
G36*
G01X1672598D02*
X1675998D01*
G02Y1406992I0J-1503D01*
G01X1672598D01*
G02Y1409998I0J1503D01*
G37*
G36*
G01X1660358Y1398086D02*
X1663758D01*
G02Y1395080I0J-1503D01*
G01X1660358D01*
G02Y1398086I0J1503D01*
G37*
G36*
G01X1672598D02*
X1675998D01*
G02Y1395080I0J-1503D01*
G01X1672598D01*
G02Y1398086I0J1503D01*
G37*
G36*
G01X1660358Y1373888D02*
X1663758D01*
G02Y1370882I0J-1503D01*
G01X1660358D01*
G02Y1373888I0J1503D01*
G37*
G36*
G01Y1385800D02*
X1663758D01*
G02Y1382794I0J-1503D01*
G01X1660358D01*
G02Y1385800I0J1503D01*
G37*
G36*
G01X1672598Y1373888D02*
X1675998D01*
G02Y1370882I0J-1503D01*
G01X1672598D01*
G02Y1373888I0J1503D01*
G37*
G36*
G01X1328246Y1385800D02*
X1331646D01*
G02Y1382794I0J-1503D01*
G01X1328246D01*
G02Y1385800I0J1503D01*
G37*
G36*
G01X1672598D02*
X1675998D01*
G02Y1382794I0J-1503D01*
G01X1672598D01*
G02Y1385800I0J1503D01*
G37*
G36*
G01X174032Y1409998D02*
X177432D01*
G02Y1406992I0J-1503D01*
G01X174032D01*
G02Y1409998I0J1503D01*
G37*
G36*
G01X266103Y1385800D02*
X269503D01*
G02Y1382794I0J-1503D01*
G01X266103D01*
G02Y1385800I0J1503D01*
G37*
G36*
G01X315063D02*
X318463D01*
G02Y1382794I0J-1503D01*
G01X315063D01*
G02Y1385800I0J1503D01*
G37*
G36*
G01X278343Y1409998D02*
X281743D01*
G02Y1406992I0J-1503D01*
G01X278343D01*
G02Y1409998I0J1503D01*
G37*
G36*
G01X1328246Y1398086D02*
X1331646D01*
G02Y1395080I0J-1503D01*
G01X1328246D01*
G02Y1398086I0J1503D01*
G37*
G36*
G01X364023Y1409998D02*
X367423D01*
G02Y1406992I0J-1503D01*
G01X364023D01*
G02Y1409998I0J1503D01*
G37*
G36*
G01X266103D02*
X269503D01*
G02Y1406992I0J-1503D01*
G01X266103D01*
G02Y1409998I0J1503D01*
G37*
G36*
G01X1733798Y1385800D02*
X1737198D01*
G02Y1382794I0J-1503D01*
G01X1733798D01*
G02Y1385800I0J1503D01*
G37*
G36*
G01Y1373888D02*
X1737198D01*
G02Y1370882I0J-1503D01*
G01X1733798D01*
G02Y1373888I0J1503D01*
G37*
G36*
G01Y1398086D02*
X1737198D01*
G02Y1395080I0J-1503D01*
G01X1733798D01*
G02Y1398086I0J1503D01*
G37*
G36*
G01X1721558Y1373888D02*
X1724958D01*
G02Y1370882I0J-1503D01*
G01X1721558D01*
G02Y1373888I0J1503D01*
G37*
G36*
G01X290583D02*
X293983D01*
G02Y1370882I0J-1503D01*
G01X290583D01*
G02Y1373888I0J1503D01*
G37*
G36*
G01X1328246Y1409998D02*
X1331646D01*
G02Y1406992I0J-1503D01*
G01X1328246D01*
G02Y1409998I0J1503D01*
G37*
G36*
G01X1340486Y1349690D02*
X1343886D01*
G02Y1346684I0J-1503D01*
G01X1340486D01*
G02Y1349690I0J1503D01*
G37*
G36*
G01X1583770Y1373888D02*
X1587170D01*
G02Y1370882I0J-1503D01*
G01X1583770D01*
G02Y1373888I0J1503D01*
G37*
G36*
G01X1485850Y1349690D02*
X1489250D01*
G02Y1346684I0J-1503D01*
G01X1485850D01*
G02Y1349690I0J1503D01*
G37*
G36*
G01X1340486Y1361602D02*
X1343886D01*
G02Y1358596I0J-1503D01*
G01X1340486D01*
G02Y1361602I0J1503D01*
G37*
G36*
G01X1733798Y1409998D02*
X1737198D01*
G02Y1406992I0J-1503D01*
G01X1733798D01*
G02Y1409998I0J1503D01*
G37*
G36*
G01X278343Y1373888D02*
X281743D01*
G02Y1370882I0J-1503D01*
G01X278343D01*
G02Y1373888I0J1503D01*
G37*
G36*
G01X266103Y1398086D02*
X269503D01*
G02Y1395080I0J-1503D01*
G01X266103D01*
G02Y1398086I0J1503D01*
G37*
G36*
G01X1733798Y1349690D02*
X1737198D01*
G02Y1346684I0J-1503D01*
G01X1733798D01*
G02Y1349690I0J1503D01*
G37*
G36*
G01X137312Y1385800D02*
X140712D01*
G02Y1382794I0J-1503D01*
G01X137312D01*
G02Y1385800I0J1503D01*
G37*
G36*
G01X1721558Y1398086D02*
X1724958D01*
G02Y1395080I0J-1503D01*
G01X1721558D01*
G02Y1398086I0J1503D01*
G37*
G36*
G01X1340486Y1385800D02*
X1343886D01*
G02Y1382794I0J-1503D01*
G01X1340486D01*
G02Y1385800I0J1503D01*
G37*
G36*
G01Y1373888D02*
X1343886D01*
G02Y1370882I0J-1503D01*
G01X1340486D01*
G02Y1373888I0J1503D01*
G37*
G36*
G01X1721558Y1385800D02*
X1724958D01*
G02Y1382794I0J-1503D01*
G01X1721558D01*
G02Y1385800I0J1503D01*
G37*
G36*
G01X339543Y1398086D02*
X342943D01*
G02Y1395080I0J-1503D01*
G01X339543D01*
G02Y1398086I0J1503D01*
G37*
G36*
G01X327303Y1385800D02*
X330703D01*
G02Y1382794I0J-1503D01*
G01X327303D01*
G02Y1385800I0J1503D01*
G37*
G36*
G01X315063Y1373888D02*
X318463D01*
G02Y1370882I0J-1503D01*
G01X315063D01*
G02Y1373888I0J1503D01*
G37*
G36*
G01X339543D02*
X342943D01*
G02Y1370882I0J-1503D01*
G01X339543D01*
G02Y1373888I0J1503D01*
G37*
G36*
G01X351783Y1385800D02*
X355183D01*
G02Y1382794I0J-1503D01*
G01X351783D01*
G02Y1385800I0J1503D01*
G37*
G36*
G01Y1373888D02*
X355183D01*
G02Y1370882I0J-1503D01*
G01X351783D01*
G02Y1373888I0J1503D01*
G37*
G36*
G01Y1398086D02*
X355183D01*
G02Y1395080I0J-1503D01*
G01X351783D01*
G02Y1398086I0J1503D01*
G37*
G36*
G01Y1409998D02*
X355183D01*
G02Y1406992I0J-1503D01*
G01X351783D01*
G02Y1409998I0J1503D01*
G37*
G36*
G01X315063Y1398086D02*
X318463D01*
G02Y1395080I0J-1503D01*
G01X315063D01*
G02Y1398086I0J1503D01*
G37*
G36*
G01X278343Y1361602D02*
X281743D01*
G02Y1358596I0J-1503D01*
G01X278343D01*
G02Y1361602I0J1503D01*
G37*
G36*
G01X1498090Y1349690D02*
X1501490D01*
G02Y1346684I0J-1503D01*
G01X1498090D01*
G02Y1349690I0J1503D01*
G37*
G36*
G01X266103Y1361602D02*
X269503D01*
G02Y1358596I0J-1503D01*
G01X266103D01*
G02Y1361602I0J1503D01*
G37*
G36*
G01X35825Y1466648D02*
X39225D01*
G02Y1463044I0J-1802D01*
G01X35825D01*
G02Y1466648I0J1802D01*
G37*
G36*
G01X942699Y344560D02*
X939299D01*
G02Y348166I0J1803D01*
G01X942699D01*
G02Y344560I0J-1803D01*
G37*
G36*
G01X942730Y322242D02*
X939330D01*
G02Y325846I0J1802D01*
G01X942730D01*
G02Y322242I0J-1802D01*
G37*
G36*
G01X927963Y342238D02*
X924563D01*
G02Y345844I0J1803D01*
G01X927963D01*
G02Y342238I0J-1803D01*
G37*
G36*
G01X919353Y342348D02*
X915953D01*
G02Y345952I0J1802D01*
G01X919353D01*
G02Y342348I0J-1802D01*
G37*
G36*
G01X302823Y1398086D02*
X306223D01*
G02Y1395080I0J-1503D01*
G01X302823D01*
G02Y1398086I0J1503D01*
G37*
G36*
G01X389015Y794228D02*
X392415D01*
G02Y791222I0J-1503D01*
G01X389015D01*
G02Y794228I0J1503D01*
G37*
G36*
G01X302823Y1373888D02*
X306223D01*
G02Y1370882I0J-1503D01*
G01X302823D01*
G02Y1373888I0J1503D01*
G37*
G36*
G01X1534810Y1385800D02*
X1538210D01*
G02Y1382794I0J-1503D01*
G01X1534810D01*
G02Y1385800I0J1503D01*
G37*
G36*
G01X327303Y1398086D02*
X330703D01*
G02Y1395080I0J-1503D01*
G01X327303D01*
G02Y1398086I0J1503D01*
G37*
G36*
G01X339543Y1409998D02*
X342943D01*
G02Y1406992I0J-1503D01*
G01X339543D01*
G02Y1409998I0J1503D01*
G37*
G36*
G01X302823Y1385800D02*
X306223D01*
G02Y1382794I0J-1503D01*
G01X302823D01*
G02Y1385800I0J1503D01*
G37*
G36*
G01X278343D02*
X281743D01*
G02Y1382794I0J-1503D01*
G01X278343D01*
G02Y1385800I0J1503D01*
G37*
G36*
G01X1340486Y1398086D02*
X1343886D01*
G02Y1395080I0J-1503D01*
G01X1340486D01*
G02Y1398086I0J1503D01*
G37*
G36*
G01Y1409998D02*
X1343886D01*
G02Y1406992I0J-1503D01*
G01X1340486D01*
G02Y1409998I0J1503D01*
G37*
G36*
G01X1583770Y1385800D02*
X1587170D01*
G02Y1382794I0J-1503D01*
G01X1583770D01*
G02Y1385800I0J1503D01*
G37*
G36*
G01X1571530Y1349690D02*
X1574930D01*
G02Y1346684I0J-1503D01*
G01X1571530D01*
G02Y1349690I0J1503D01*
G37*
G36*
G01Y1373888D02*
X1574930D01*
G02Y1370882I0J-1503D01*
G01X1571530D01*
G02Y1373888I0J1503D01*
G37*
G36*
G01Y1385800D02*
X1574930D01*
G02Y1382794I0J-1503D01*
G01X1571530D01*
G02Y1385800I0J1503D01*
G37*
G36*
G01X1473610Y1398086D02*
X1477010D01*
G02Y1395080I0J-1503D01*
G01X1473610D01*
G02Y1398086I0J1503D01*
G37*
G36*
G01Y1409998D02*
X1477010D01*
G02Y1406992I0J-1503D01*
G01X1473610D01*
G02Y1409998I0J1503D01*
G37*
G36*
G01X1583770Y1398086D02*
X1587170D01*
G02Y1395080I0J-1503D01*
G01X1583770D01*
G02Y1398086I0J1503D01*
G37*
G36*
G01Y1409998D02*
X1587170D01*
G02Y1406992I0J-1503D01*
G01X1583770D01*
G02Y1409998I0J1503D01*
G37*
G36*
G01X1485850Y1398086D02*
X1489250D01*
G02Y1395080I0J-1503D01*
G01X1485850D01*
G02Y1398086I0J1503D01*
G37*
G36*
G01X1498090Y1373888D02*
X1501490D01*
G02Y1370882I0J-1503D01*
G01X1498090D01*
G02Y1373888I0J1503D01*
G37*
G36*
G01X1522570Y1361602D02*
X1525970D01*
G02Y1358596I0J-1503D01*
G01X1522570D01*
G02Y1361602I0J1503D01*
G37*
G36*
G01X1498090Y1409998D02*
X1501490D01*
G02Y1406992I0J-1503D01*
G01X1498090D01*
G02Y1409998I0J1503D01*
G37*
G36*
G01X1352726Y1349690D02*
X1356126D01*
G02Y1346684I0J-1503D01*
G01X1352726D01*
G02Y1349690I0J1503D01*
G37*
G36*
G01X1510330Y1398086D02*
X1513730D01*
G02Y1395080I0J-1503D01*
G01X1510330D01*
G02Y1398086I0J1503D01*
G37*
G36*
G01X1611398Y1361602D02*
X1614798D01*
G02Y1358596I0J-1503D01*
G01X1611398D01*
G02Y1361602I0J1503D01*
G37*
G36*
G01X1623638Y1373888D02*
X1627038D01*
G02Y1370882I0J-1503D01*
G01X1623638D01*
G02Y1373888I0J1503D01*
G37*
G36*
G01X1547050D02*
X1550450D01*
G02Y1370882I0J-1503D01*
G01X1547050D01*
G02Y1373888I0J1503D01*
G37*
G36*
G01X1352726Y1361602D02*
X1356126D01*
G02Y1358596I0J-1503D01*
G01X1352726D01*
G02Y1361602I0J1503D01*
G37*
G36*
G01Y1385800D02*
X1356126D01*
G02Y1382794I0J-1503D01*
G01X1352726D01*
G02Y1385800I0J1503D01*
G37*
G36*
G01Y1373888D02*
X1356126D01*
G02Y1370882I0J-1503D01*
G01X1352726D01*
G02Y1373888I0J1503D01*
G37*
G36*
G01X1684838Y1409998D02*
X1688238D01*
G02Y1406992I0J-1503D01*
G01X1684838D01*
G02Y1409998I0J1503D01*
G37*
G36*
G01X1709318Y1373888D02*
X1712718D01*
G02Y1370882I0J-1503D01*
G01X1709318D01*
G02Y1373888I0J1503D01*
G37*
G36*
G01Y1385800D02*
X1712718D01*
G02Y1382794I0J-1503D01*
G01X1709318D01*
G02Y1385800I0J1503D01*
G37*
G36*
G01X1733798Y1361602D02*
X1737198D01*
G02Y1358596I0J-1503D01*
G01X1733798D01*
G02Y1361602I0J1503D01*
G37*
G36*
G01X1697078Y1373888D02*
X1700478D01*
G02Y1370882I0J-1503D01*
G01X1697078D01*
G02Y1373888I0J1503D01*
G37*
G36*
G01X1709318Y1409998D02*
X1712718D01*
G02Y1406992I0J-1503D01*
G01X1709318D01*
G02Y1409998I0J1503D01*
G37*
G36*
G01X1697078Y1398086D02*
X1700478D01*
G02Y1395080I0J-1503D01*
G01X1697078D01*
G02Y1398086I0J1503D01*
G37*
G36*
G01X1709318D02*
X1712718D01*
G02Y1395080I0J-1503D01*
G01X1709318D01*
G02Y1398086I0J1503D01*
G37*
G36*
G01X1721558Y1349690D02*
X1724958D01*
G02Y1346684I0J-1503D01*
G01X1721558D01*
G02Y1349690I0J1503D01*
G37*
G36*
G01Y1361602D02*
X1724958D01*
G02Y1358596I0J-1503D01*
G01X1721558D01*
G02Y1361602I0J1503D01*
G37*
G36*
G01Y1409998D02*
X1724958D01*
G02Y1406992I0J-1503D01*
G01X1721558D01*
G02Y1409998I0J1503D01*
G37*
G36*
G01X1352726Y1398086D02*
X1356126D01*
G02Y1395080I0J-1503D01*
G01X1352726D01*
G02Y1398086I0J1503D01*
G37*
G36*
G01X174032Y1361602D02*
X177432D01*
G02Y1358596I0J-1503D01*
G01X174032D01*
G02Y1361602I0J1503D01*
G37*
G36*
G01X198512Y1349690D02*
X201912D01*
G02Y1346684I0J-1503D01*
G01X198512D01*
G02Y1349690I0J1503D01*
G37*
G36*
G01Y1398086D02*
X201912D01*
G02Y1395080I0J-1503D01*
G01X198512D01*
G02Y1398086I0J1503D01*
G37*
G36*
G01X186272D02*
X189672D01*
G02Y1395080I0J-1503D01*
G01X186272D01*
G02Y1398086I0J1503D01*
G37*
G36*
G01X161792Y1349690D02*
X165192D01*
G02Y1346684I0J-1503D01*
G01X161792D01*
G02Y1349690I0J1503D01*
G37*
G36*
G01X186272Y1361602D02*
X189672D01*
G02Y1358596I0J-1503D01*
G01X186272D01*
G02Y1361602I0J1503D01*
G37*
G36*
G01X100592Y1349690D02*
X103992D01*
G02Y1346684I0J-1503D01*
G01X100592D01*
G02Y1349690I0J1503D01*
G37*
G36*
G01X112832D02*
X116232D01*
G02Y1346684I0J-1503D01*
G01X112832D01*
G02Y1349690I0J1503D01*
G37*
G36*
G01X149552Y1398086D02*
X152952D01*
G02Y1395080I0J-1503D01*
G01X149552D01*
G02Y1398086I0J1503D01*
G37*
G36*
G01X161792D02*
X165192D01*
G02Y1395080I0J-1503D01*
G01X161792D01*
G02Y1398086I0J1503D01*
G37*
G36*
G01Y1373888D02*
X165192D01*
G02Y1370882I0J-1503D01*
G01X161792D01*
G02Y1373888I0J1503D01*
G37*
G36*
G01Y1385800D02*
X165192D01*
G02Y1382794I0J-1503D01*
G01X161792D01*
G02Y1385800I0J1503D01*
G37*
G36*
G01X198512Y1361602D02*
X201912D01*
G02Y1358596I0J-1503D01*
G01X198512D01*
G02Y1361602I0J1503D01*
G37*
G36*
G01X137312D02*
X140712D01*
G02Y1358596I0J-1503D01*
G01X137312D01*
G02Y1361602I0J1503D01*
G37*
G36*
G01X161792D02*
X165192D01*
G02Y1358596I0J-1503D01*
G01X161792D01*
G02Y1361602I0J1503D01*
G37*
G36*
G01X149552Y1349690D02*
X152952D01*
G02Y1346684I0J-1503D01*
G01X149552D01*
G02Y1349690I0J1503D01*
G37*
G36*
G01X137312D02*
X140712D01*
G02Y1346684I0J-1503D01*
G01X137312D01*
G02Y1349690I0J1503D01*
G37*
G36*
G01X76112Y1361602D02*
X79512D01*
G02Y1358596I0J-1503D01*
G01X76112D01*
G02Y1361602I0J1503D01*
G37*
G36*
G01X174032Y1385800D02*
X177432D01*
G02Y1382794I0J-1503D01*
G01X174032D01*
G02Y1385800I0J1503D01*
G37*
G36*
G01X125072Y1409998D02*
X128472D01*
G02Y1406992I0J-1503D01*
G01X125072D01*
G02Y1409998I0J1503D01*
G37*
G36*
G01Y1398086D02*
X128472D01*
G02Y1395080I0J-1503D01*
G01X125072D01*
G02Y1398086I0J1503D01*
G37*
G36*
G01Y1373888D02*
X128472D01*
G02Y1370882I0J-1503D01*
G01X125072D01*
G02Y1373888I0J1503D01*
G37*
G36*
G01Y1385800D02*
X128472D01*
G02Y1382794I0J-1503D01*
G01X125072D01*
G02Y1385800I0J1503D01*
G37*
G36*
G01X1571530Y1361602D02*
X1574930D01*
G02Y1358596I0J-1503D01*
G01X1571530D01*
G02Y1361602I0J1503D01*
G37*
G36*
G01X100592Y1385800D02*
X103992D01*
G02Y1382794I0J-1503D01*
G01X100592D01*
G02Y1385800I0J1503D01*
G37*
G36*
G01X76112Y1373888D02*
X79512D01*
G02Y1370882I0J-1503D01*
G01X76112D01*
G02Y1373888I0J1503D01*
G37*
G36*
G01X88352Y1409998D02*
X91752D01*
G02Y1406992I0J-1503D01*
G01X88352D01*
G02Y1409998I0J1503D01*
G37*
G36*
G01X149552D02*
X152952D01*
G02Y1406992I0J-1503D01*
G01X149552D01*
G02Y1409998I0J1503D01*
G37*
G36*
G01X137312Y1373888D02*
X140712D01*
G02Y1370882I0J-1503D01*
G01X137312D01*
G02Y1373888I0J1503D01*
G37*
G36*
G01X253863Y1385800D02*
X257263D01*
G02Y1382794I0J-1503D01*
G01X253863D01*
G02Y1385800I0J1503D01*
G37*
G36*
G01X186272Y1409998D02*
X189672D01*
G02Y1406992I0J-1503D01*
G01X186272D01*
G02Y1409998I0J1503D01*
G37*
G36*
G01X125072Y1361602D02*
X128472D01*
G02Y1358596I0J-1503D01*
G01X125072D01*
G02Y1361602I0J1503D01*
G37*
G36*
G01Y1349690D02*
X128472D01*
G02Y1346684I0J-1503D01*
G01X125072D01*
G02Y1349690I0J1503D01*
G37*
G36*
G01X149552Y1373888D02*
X152952D01*
G02Y1370882I0J-1503D01*
G01X149552D01*
G02Y1373888I0J1503D01*
G37*
G36*
G01X174032Y1349690D02*
X177432D01*
G02Y1346684I0J-1503D01*
G01X174032D01*
G02Y1349690I0J1503D01*
G37*
G36*
G01Y1373888D02*
X177432D01*
G02Y1370882I0J-1503D01*
G01X174032D01*
G02Y1373888I0J1503D01*
G37*
G36*
G01X76112Y1385800D02*
X79512D01*
G02Y1382794I0J-1503D01*
G01X76112D01*
G02Y1385800I0J1503D01*
G37*
G36*
G01X1583770Y1349690D02*
X1587170D01*
G02Y1346684I0J-1503D01*
G01X1583770D01*
G02Y1349690I0J1503D01*
G37*
G36*
G01X1697078Y1385800D02*
X1700478D01*
G02Y1382794I0J-1503D01*
G01X1697078D01*
G02Y1385800I0J1503D01*
G37*
G36*
G01X88352Y1361602D02*
X91752D01*
G02Y1358596I0J-1503D01*
G01X88352D01*
G02Y1361602I0J1503D01*
G37*
G36*
G01Y1349690D02*
X91752D01*
G02Y1346684I0J-1503D01*
G01X88352D01*
G02Y1349690I0J1503D01*
G37*
G36*
G01X1697078Y1409998D02*
X1700478D01*
G02Y1406992I0J-1503D01*
G01X1697078D01*
G02Y1409998I0J1503D01*
G37*
G36*
G01X112832Y1373888D02*
X116232D01*
G02Y1370882I0J-1503D01*
G01X112832D01*
G02Y1373888I0J1503D01*
G37*
G36*
G01Y1409998D02*
X116232D01*
G02Y1406992I0J-1503D01*
G01X112832D01*
G02Y1409998I0J1503D01*
G37*
G36*
G01X100592D02*
X103992D01*
G02Y1406992I0J-1503D01*
G01X100592D01*
G02Y1409998I0J1503D01*
G37*
G36*
G01X724208Y1385800D02*
X727608D01*
G02Y1382794I0J-1503D01*
G01X724208D01*
G02Y1385800I0J1503D01*
G37*
G36*
G01X88352D02*
X91752D01*
G02Y1382794I0J-1503D01*
G01X88352D01*
G02Y1385800I0J1503D01*
G37*
G36*
G01X760928Y1361602D02*
X764328D01*
G02Y1358596I0J-1503D01*
G01X760928D01*
G02Y1361602I0J1503D01*
G37*
G36*
G01X100592Y1373888D02*
X103992D01*
G02Y1370882I0J-1503D01*
G01X100592D01*
G02Y1373888I0J1503D01*
G37*
G36*
G01X137312Y1398086D02*
X140712D01*
G02Y1395080I0J-1503D01*
G01X137312D01*
G02Y1398086I0J1503D01*
G37*
G36*
G01Y1409998D02*
X140712D01*
G02Y1406992I0J-1503D01*
G01X137312D01*
G02Y1409998I0J1503D01*
G37*
G36*
G01X112832Y1385800D02*
X116232D01*
G02Y1382794I0J-1503D01*
G01X112832D01*
G02Y1385800I0J1503D01*
G37*
G36*
G01X663008Y1361602D02*
X666408D01*
G02Y1358596I0J-1503D01*
G01X663008D01*
G02Y1361602I0J1503D01*
G37*
G36*
G01X100592Y1398086D02*
X103992D01*
G02Y1395080I0J-1503D01*
G01X100592D01*
G02Y1398086I0J1503D01*
G37*
G36*
G01X748688Y1385800D02*
X752088D01*
G02Y1382794I0J-1503D01*
G01X748688D01*
G02Y1385800I0J1503D01*
G37*
G36*
G01X1352726Y1409998D02*
X1356126D01*
G02Y1406992I0J-1503D01*
G01X1352726D01*
G02Y1409998I0J1503D01*
G37*
G36*
G01X100592Y1361602D02*
X103992D01*
G02Y1358596I0J-1503D01*
G01X100592D01*
G02Y1361602I0J1503D01*
G37*
G36*
G01X112832D02*
X116232D01*
G02Y1358596I0J-1503D01*
G01X112832D01*
G02Y1361602I0J1503D01*
G37*
G36*
G01X88352Y1398086D02*
X91752D01*
G02Y1395080I0J-1503D01*
G01X88352D01*
G02Y1398086I0J1503D01*
G37*
G36*
G01X1660358Y1361602D02*
X1663758D01*
G02Y1358596I0J-1503D01*
G01X1660358D01*
G02Y1361602I0J1503D01*
G37*
G36*
G01X1066953Y1349690D02*
X1070353D01*
G02Y1346684I0J-1503D01*
G01X1066953D01*
G02Y1349690I0J1503D01*
G37*
G36*
G01X663008D02*
X666408D01*
G02Y1346684I0J-1503D01*
G01X663008D01*
G02Y1349690I0J1503D01*
G37*
G36*
G01X1583770Y1361602D02*
X1587170D01*
G02Y1358596I0J-1503D01*
G01X1583770D01*
G02Y1361602I0J1503D01*
G37*
G36*
G01X1571530Y1398086D02*
X1574930D01*
G02Y1395080I0J-1503D01*
G01X1571530D01*
G02Y1398086I0J1503D01*
G37*
G36*
G01X1559290Y1361602D02*
X1562690D01*
G02Y1358596I0J-1503D01*
G01X1559290D01*
G02Y1361602I0J1503D01*
G37*
G36*
G01Y1373888D02*
X1562690D01*
G02Y1370882I0J-1503D01*
G01X1559290D01*
G02Y1373888I0J1503D01*
G37*
G36*
G01X1623638Y1385800D02*
X1627038D01*
G02Y1382794I0J-1503D01*
G01X1623638D01*
G02Y1385800I0J1503D01*
G37*
G36*
G01X76112Y1349690D02*
X79512D01*
G02Y1346684I0J-1503D01*
G01X76112D01*
G02Y1349690I0J1503D01*
G37*
G36*
G01X1066953Y1361602D02*
X1070353D01*
G02Y1358596I0J-1503D01*
G01X1066953D01*
G02Y1361602I0J1503D01*
G37*
G36*
G01X1547050Y1385800D02*
X1550450D01*
G02Y1382794I0J-1503D01*
G01X1547050D01*
G02Y1385800I0J1503D01*
G37*
G36*
G01X1672598Y1349690D02*
X1675998D01*
G02Y1346684I0J-1503D01*
G01X1672598D01*
G02Y1349690I0J1503D01*
G37*
G36*
G01X1660358D02*
X1663758D01*
G02Y1346684I0J-1503D01*
G01X1660358D01*
G02Y1349690I0J1503D01*
G37*
G36*
G01X1672598Y1361602D02*
X1675998D01*
G02Y1358596I0J-1503D01*
G01X1672598D01*
G02Y1361602I0J1503D01*
G37*
G36*
G01X1709318Y1349690D02*
X1712718D01*
G02Y1346684I0J-1503D01*
G01X1709318D01*
G02Y1349690I0J1503D01*
G37*
G36*
G01X1697078D02*
X1700478D01*
G02Y1346684I0J-1503D01*
G01X1697078D01*
G02Y1349690I0J1503D01*
G37*
G36*
G01X1684838Y1385800D02*
X1688238D01*
G02Y1382794I0J-1503D01*
G01X1684838D01*
G02Y1385800I0J1503D01*
G37*
G36*
G01X1709318Y1361602D02*
X1712718D01*
G02Y1358596I0J-1503D01*
G01X1709318D01*
G02Y1361602I0J1503D01*
G37*
G36*
G01X1697078D02*
X1700478D01*
G02Y1358596I0J-1503D01*
G01X1697078D01*
G02Y1361602I0J1503D01*
G37*
G36*
G01X1684838D02*
X1688238D01*
G02Y1358596I0J-1503D01*
G01X1684838D01*
G02Y1361602I0J1503D01*
G37*
G36*
G01Y1373888D02*
X1688238D01*
G02Y1370882I0J-1503D01*
G01X1684838D01*
G02Y1373888I0J1503D01*
G37*
G36*
G01Y1398086D02*
X1688238D01*
G02Y1395080I0J-1503D01*
G01X1684838D01*
G02Y1398086I0J1503D01*
G37*
G36*
G01X1066953Y1373888D02*
X1070353D01*
G02Y1370882I0J-1503D01*
G01X1066953D01*
G02Y1373888I0J1503D01*
G37*
G36*
G01Y1385800D02*
X1070353D01*
G02Y1382794I0J-1503D01*
G01X1066953D01*
G02Y1385800I0J1503D01*
G37*
G36*
G01X1547050Y1398086D02*
X1550450D01*
G02Y1395080I0J-1503D01*
G01X1547050D01*
G02Y1398086I0J1503D01*
G37*
G36*
G01X549168Y783102D02*
G02Y780098I0J-1502D01*
G01X545813D01*
X545808D01*
G02X545944Y783092I-38J1502D01*
G01X545956Y783090D01*
X548978D01*
X548990Y783092D01*
G02X549168Y783102I173J-1492D01*
G37*
G36*
G01X278343Y1349690D02*
X281743D01*
G02Y1346684I0J-1503D01*
G01X278343D01*
G02Y1349690I0J1503D01*
G37*
G36*
G01X945982Y888540D02*
X949382D01*
G02Y884936I0J-1802D01*
G01X945982D01*
G02Y888540I0J1802D01*
G37*
G36*
G01X1684838Y1349690D02*
X1688238D01*
G02Y1346684I0J-1503D01*
G01X1684838D01*
G02Y1349690I0J1503D01*
G37*
G36*
G01X1571530Y1409998D02*
X1574930D01*
G02Y1406992I0J-1503D01*
G01X1571530D01*
G02Y1409998I0J1503D01*
G37*
G36*
G01X1473610Y1373888D02*
X1477010D01*
G02Y1370882I0J-1503D01*
G01X1473610D01*
G02Y1373888I0J1503D01*
G37*
G36*
G01X1498090Y1398086D02*
X1501490D01*
G02Y1395080I0J-1503D01*
G01X1498090D01*
G02Y1398086I0J1503D01*
G37*
G36*
G01Y1385800D02*
X1501490D01*
G02Y1382794I0J-1503D01*
G01X1498090D01*
G02Y1385800I0J1503D01*
G37*
G36*
G01X1510330Y1409998D02*
X1513730D01*
G02Y1406992I0J-1503D01*
G01X1510330D01*
G02Y1409998I0J1503D01*
G37*
G36*
G01X1522570Y1349690D02*
X1525970D01*
G02Y1346684I0J-1503D01*
G01X1522570D01*
G02Y1349690I0J1503D01*
G37*
G36*
G01X146948Y1135604D02*
X143208D01*
G02Y1138210I0J1303D01*
G01X146948D01*
G02Y1135604I0J-1303D01*
G37*
G36*
G01X165649Y1131864D02*
X161909D01*
G02Y1134470I0J1303D01*
G01X165649D01*
G02Y1131864I0J-1303D01*
G37*
G36*
G01X154429D02*
X150689D01*
G02Y1134470I0J1303D01*
G01X154429D01*
G02Y1131864I0J-1303D01*
G37*
G36*
G01X173129Y1135604D02*
X169389D01*
G02Y1138210I0J1303D01*
G01X173129D01*
G02Y1135604I0J-1303D01*
G37*
G36*
G01X440402Y1361602D02*
X443802D01*
G02Y1358596I0J-1503D01*
G01X440402D01*
G02Y1361602I0J1503D01*
G37*
G36*
G01Y1349690D02*
X443802D01*
G02Y1346684I0J-1503D01*
G01X440402D01*
G02Y1349690I0J1503D01*
G37*
G36*
G01X452642Y1361602D02*
X456042D01*
G02Y1358596I0J-1503D01*
G01X452642D01*
G02Y1361602I0J1503D01*
G37*
G36*
G01Y1349690D02*
X456042D01*
G02Y1346684I0J-1503D01*
G01X452642D01*
G02Y1349690I0J1503D01*
G37*
G36*
G01X501602Y1385800D02*
X505002D01*
G02Y1382794I0J-1503D01*
G01X501602D01*
G02Y1385800I0J1503D01*
G37*
G36*
G01X513842D02*
X517242D01*
G02Y1382794I0J-1503D01*
G01X513842D01*
G02Y1385800I0J1503D01*
G37*
G36*
G01Y1373888D02*
X517242D01*
G02Y1370882I0J-1503D01*
G01X513842D01*
G02Y1373888I0J1503D01*
G37*
G36*
G01X501602D02*
X505002D01*
G02Y1370882I0J-1503D01*
G01X501602D01*
G02Y1373888I0J1503D01*
G37*
G36*
G01X464882Y1349690D02*
X468282D01*
G02Y1346684I0J-1503D01*
G01X464882D01*
G02Y1349690I0J1503D01*
G37*
G36*
G01X477122D02*
X480522D01*
G02Y1346684I0J-1503D01*
G01X477122D01*
G02Y1349690I0J1503D01*
G37*
G36*
G01X526082Y1385800D02*
X529482D01*
G02Y1382794I0J-1503D01*
G01X526082D01*
G02Y1385800I0J1503D01*
G37*
G36*
G01X538322D02*
X541722D01*
G02Y1382794I0J-1503D01*
G01X538322D01*
G02Y1385800I0J1503D01*
G37*
G36*
G01X526082Y1373888D02*
X529482D01*
G02Y1370882I0J-1503D01*
G01X526082D01*
G02Y1373888I0J1503D01*
G37*
G36*
G01X538322D02*
X541722D01*
G02Y1370882I0J-1503D01*
G01X538322D01*
G02Y1373888I0J1503D01*
G37*
G36*
G01X464882Y1361602D02*
X468282D01*
G02Y1358596I0J-1503D01*
G01X464882D01*
G02Y1361602I0J1503D01*
G37*
G36*
G01X477122D02*
X480522D01*
G02Y1358596I0J-1503D01*
G01X477122D01*
G02Y1361602I0J1503D01*
G37*
G36*
G01X489362Y1349690D02*
X492762D01*
G02Y1346684I0J-1503D01*
G01X489362D01*
G02Y1349690I0J1503D01*
G37*
G36*
G01X440402Y1373888D02*
X443802D01*
G02Y1370882I0J-1503D01*
G01X440402D01*
G02Y1373888I0J1503D01*
G37*
G36*
G01X550562Y1385800D02*
X553962D01*
G02Y1382794I0J-1503D01*
G01X550562D01*
G02Y1385800I0J1503D01*
G37*
G36*
G01Y1373888D02*
X553962D01*
G02Y1370882I0J-1503D01*
G01X550562D01*
G02Y1373888I0J1503D01*
G37*
G36*
G01X489362Y1361602D02*
X492762D01*
G02Y1358596I0J-1503D01*
G01X489362D01*
G02Y1361602I0J1503D01*
G37*
G36*
G01X440402Y1385800D02*
X443802D01*
G02Y1382794I0J-1503D01*
G01X440402D01*
G02Y1385800I0J1503D01*
G37*
G36*
G01X452642Y1373888D02*
X456042D01*
G02Y1370882I0J-1503D01*
G01X452642D01*
G02Y1373888I0J1503D01*
G37*
G36*
G01X562802Y1385800D02*
X566202D01*
G02Y1382794I0J-1503D01*
G01X562802D01*
G02Y1385800I0J1503D01*
G37*
G36*
G01X452642Y1409998D02*
X456042D01*
G02Y1406992I0J-1503D01*
G01X452642D01*
G02Y1409998I0J1503D01*
G37*
G36*
G01Y1398086D02*
X456042D01*
G02Y1395080I0J-1503D01*
G01X452642D01*
G02Y1398086I0J1503D01*
G37*
G36*
G01X562802Y1373888D02*
X566202D01*
G02Y1370882I0J-1503D01*
G01X562802D01*
G02Y1373888I0J1503D01*
G37*
G36*
G01X452642Y1385800D02*
X456042D01*
G02Y1382794I0J-1503D01*
G01X452642D01*
G02Y1385800I0J1503D01*
G37*
G36*
G01X464882Y1409998D02*
X468282D01*
G02Y1406992I0J-1503D01*
G01X464882D01*
G02Y1409998I0J1503D01*
G37*
G36*
G01Y1398086D02*
X468282D01*
G02Y1395080I0J-1503D01*
G01X464882D01*
G02Y1398086I0J1503D01*
G37*
G36*
G01Y1385800D02*
X468282D01*
G02Y1382794I0J-1503D01*
G01X464882D01*
G02Y1385800I0J1503D01*
G37*
G36*
G01X477122D02*
X480522D01*
G02Y1382794I0J-1503D01*
G01X477122D01*
G02Y1385800I0J1503D01*
G37*
G36*
G01Y1373888D02*
X480522D01*
G02Y1370882I0J-1503D01*
G01X477122D01*
G02Y1373888I0J1503D01*
G37*
G36*
G01X464882D02*
X468282D01*
G02Y1370882I0J-1503D01*
G01X464882D01*
G02Y1373888I0J1503D01*
G37*
G36*
G01X489362D02*
X492762D01*
G02Y1370882I0J-1503D01*
G01X489362D01*
G02Y1373888I0J1503D01*
G37*
G36*
G01Y1409998D02*
X492762D01*
G02Y1406992I0J-1503D01*
G01X489362D01*
G02Y1409998I0J1503D01*
G37*
G36*
G01Y1398086D02*
X492762D01*
G02Y1395080I0J-1503D01*
G01X489362D01*
G02Y1398086I0J1503D01*
G37*
G36*
G01X477122Y1409998D02*
X480522D01*
G02Y1406992I0J-1503D01*
G01X477122D01*
G02Y1409998I0J1503D01*
G37*
G36*
G01Y1398086D02*
X480522D01*
G02Y1395080I0J-1503D01*
G01X477122D01*
G02Y1398086I0J1503D01*
G37*
G36*
G01X489362Y1385800D02*
X492762D01*
G02Y1382794I0J-1503D01*
G01X489362D01*
G02Y1385800I0J1503D01*
G37*
G36*
G01X501602Y1361602D02*
X505002D01*
G02Y1358596I0J-1503D01*
G01X501602D01*
G02Y1361602I0J1503D01*
G37*
G36*
G01X513842D02*
X517242D01*
G02Y1358596I0J-1503D01*
G01X513842D01*
G02Y1361602I0J1503D01*
G37*
G36*
G01X501602Y1349690D02*
X505002D01*
G02Y1346684I0J-1503D01*
G01X501602D01*
G02Y1349690I0J1503D01*
G37*
G36*
G01X513842D02*
X517242D01*
G02Y1346684I0J-1503D01*
G01X513842D01*
G02Y1349690I0J1503D01*
G37*
G36*
G01X501602Y1398086D02*
X505002D01*
G02Y1395080I0J-1503D01*
G01X501602D01*
G02Y1398086I0J1503D01*
G37*
G36*
G01Y1409998D02*
X505002D01*
G02Y1406992I0J-1503D01*
G01X501602D01*
G02Y1409998I0J1503D01*
G37*
G36*
G01X526082Y1361602D02*
X529482D01*
G02Y1358596I0J-1503D01*
G01X526082D01*
G02Y1361602I0J1503D01*
G37*
G36*
G01Y1349690D02*
X529482D01*
G02Y1346684I0J-1503D01*
G01X526082D01*
G02Y1349690I0J1503D01*
G37*
G36*
G01X513842Y1398086D02*
X517242D01*
G02Y1395080I0J-1503D01*
G01X513842D01*
G02Y1398086I0J1503D01*
G37*
G36*
G01X526082Y1409998D02*
X529482D01*
G02Y1406992I0J-1503D01*
G01X526082D01*
G02Y1409998I0J1503D01*
G37*
G36*
G01X513842D02*
X517242D01*
G02Y1406992I0J-1503D01*
G01X513842D01*
G02Y1409998I0J1503D01*
G37*
G36*
G01X526082Y1398086D02*
X529482D01*
G02Y1395080I0J-1503D01*
G01X526082D01*
G02Y1398086I0J1503D01*
G37*
G36*
G01X538322Y1361602D02*
X541722D01*
G02Y1358596I0J-1503D01*
G01X538322D01*
G02Y1361602I0J1503D01*
G37*
G36*
G01X550562D02*
X553962D01*
G02Y1358596I0J-1503D01*
G01X550562D01*
G02Y1361602I0J1503D01*
G37*
G36*
G01X538322Y1349690D02*
X541722D01*
G02Y1346684I0J-1503D01*
G01X538322D01*
G02Y1349690I0J1503D01*
G37*
G36*
G01X550562D02*
X553962D01*
G02Y1346684I0J-1503D01*
G01X550562D01*
G02Y1349690I0J1503D01*
G37*
G36*
G01X538322Y1398086D02*
X541722D01*
G02Y1395080I0J-1503D01*
G01X538322D01*
G02Y1398086I0J1503D01*
G37*
G36*
G01Y1409998D02*
X541722D01*
G02Y1406992I0J-1503D01*
G01X538322D01*
G02Y1409998I0J1503D01*
G37*
G36*
G01X562802Y1361602D02*
X566202D01*
G02Y1358596I0J-1503D01*
G01X562802D01*
G02Y1361602I0J1503D01*
G37*
G36*
G01Y1349690D02*
X566202D01*
G02Y1346684I0J-1503D01*
G01X562802D01*
G02Y1349690I0J1503D01*
G37*
G36*
G01X550562Y1398086D02*
X553962D01*
G02Y1395080I0J-1503D01*
G01X550562D01*
G02Y1398086I0J1503D01*
G37*
G36*
G01X562802D02*
X566202D01*
G02Y1395080I0J-1503D01*
G01X562802D01*
G02Y1398086I0J1503D01*
G37*
G36*
G01X550562Y1409998D02*
X553962D01*
G02Y1406992I0J-1503D01*
G01X550562D01*
G02Y1409998I0J1503D01*
G37*
G36*
G01X562802D02*
X566202D01*
G02Y1406992I0J-1503D01*
G01X562802D01*
G02Y1409998I0J1503D01*
G37*
G36*
G01X650768Y1361602D02*
X654168D01*
G02Y1358596I0J-1503D01*
G01X650768D01*
G02Y1361602I0J1503D01*
G37*
G36*
G01Y1349690D02*
X654168D01*
G02Y1346684I0J-1503D01*
G01X650768D01*
G02Y1349690I0J1503D01*
G37*
G36*
G01X626288Y1409998D02*
X629688D01*
G02Y1406992I0J-1503D01*
G01X626288D01*
G02Y1409998I0J1503D01*
G37*
G36*
G01X638528Y1385800D02*
X641928D01*
G02Y1382794I0J-1503D01*
G01X638528D01*
G02Y1385800I0J1503D01*
G37*
G36*
G01Y1373888D02*
X641928D01*
G02Y1370882I0J-1503D01*
G01X638528D01*
G02Y1373888I0J1503D01*
G37*
G36*
G01X626288Y1398086D02*
X629688D01*
G02Y1395080I0J-1503D01*
G01X626288D01*
G02Y1398086I0J1503D01*
G37*
G36*
G01X675248Y1361602D02*
X678648D01*
G02Y1358596I0J-1503D01*
G01X675248D01*
G02Y1361602I0J1503D01*
G37*
G36*
G01X650768Y1385800D02*
X654168D01*
G02Y1382794I0J-1503D01*
G01X650768D01*
G02Y1385800I0J1503D01*
G37*
G36*
G01X675248Y1349690D02*
X678648D01*
G02Y1346684I0J-1503D01*
G01X675248D01*
G02Y1349690I0J1503D01*
G37*
G36*
G01X650768Y1373888D02*
X654168D01*
G02Y1370882I0J-1503D01*
G01X650768D01*
G02Y1373888I0J1503D01*
G37*
G36*
G01X638528Y1409998D02*
X641928D01*
G02Y1406992I0J-1503D01*
G01X638528D01*
G02Y1409998I0J1503D01*
G37*
G36*
G01Y1398086D02*
X641928D01*
G02Y1395080I0J-1503D01*
G01X638528D01*
G02Y1398086I0J1503D01*
G37*
G36*
G01X687488Y1361602D02*
X690888D01*
G02Y1358596I0J-1503D01*
G01X687488D01*
G02Y1361602I0J1503D01*
G37*
G36*
G01Y1349690D02*
X690888D01*
G02Y1346684I0J-1503D01*
G01X687488D01*
G02Y1349690I0J1503D01*
G37*
G36*
G01X663008Y1385800D02*
X666408D01*
G02Y1382794I0J-1503D01*
G01X663008D01*
G02Y1385800I0J1503D01*
G37*
G36*
G01X650768Y1409998D02*
X654168D01*
G02Y1406992I0J-1503D01*
G01X650768D01*
G02Y1409998I0J1503D01*
G37*
G36*
G01X663008Y1373888D02*
X666408D01*
G02Y1370882I0J-1503D01*
G01X663008D01*
G02Y1373888I0J1503D01*
G37*
G36*
G01X650768Y1398086D02*
X654168D01*
G02Y1395080I0J-1503D01*
G01X650768D01*
G02Y1398086I0J1503D01*
G37*
G36*
G01X699728Y1361602D02*
X703128D01*
G02Y1358596I0J-1503D01*
G01X699728D01*
G02Y1361602I0J1503D01*
G37*
G36*
G01X687488Y1385800D02*
X690888D01*
G02Y1382794I0J-1503D01*
G01X687488D01*
G02Y1385800I0J1503D01*
G37*
G36*
G01X699728Y1349690D02*
X703128D01*
G02Y1346684I0J-1503D01*
G01X699728D01*
G02Y1349690I0J1503D01*
G37*
G36*
G01X687488Y1373888D02*
X690888D01*
G02Y1370882I0J-1503D01*
G01X687488D01*
G02Y1373888I0J1503D01*
G37*
G36*
G01X675248Y1385800D02*
X678648D01*
G02Y1382794I0J-1503D01*
G01X675248D01*
G02Y1385800I0J1503D01*
G37*
G36*
G01Y1373888D02*
X678648D01*
G02Y1370882I0J-1503D01*
G01X675248D01*
G02Y1373888I0J1503D01*
G37*
G36*
G01X711968Y1349690D02*
X715368D01*
G02Y1346684I0J-1503D01*
G01X711968D01*
G02Y1349690I0J1503D01*
G37*
G36*
G01Y1361602D02*
X715368D01*
G02Y1358596I0J-1503D01*
G01X711968D01*
G02Y1361602I0J1503D01*
G37*
G36*
G01X663008Y1409998D02*
X666408D01*
G02Y1406992I0J-1503D01*
G01X663008D01*
G02Y1409998I0J1503D01*
G37*
G36*
G01X699728Y1385800D02*
X703128D01*
G02Y1382794I0J-1503D01*
G01X699728D01*
G02Y1385800I0J1503D01*
G37*
G36*
G01Y1373888D02*
X703128D01*
G02Y1370882I0J-1503D01*
G01X699728D01*
G02Y1373888I0J1503D01*
G37*
G36*
G01X663008Y1398086D02*
X666408D01*
G02Y1395080I0J-1503D01*
G01X663008D01*
G02Y1398086I0J1503D01*
G37*
G36*
G01X724208Y1397992D02*
X727608D01*
G02Y1394986I0J-1503D01*
G01X724208D01*
G02Y1397992I0J1503D01*
G37*
G36*
G01Y1349690D02*
X727608D01*
G02Y1346684I0J-1503D01*
G01X724208D01*
G02Y1349690I0J1503D01*
G37*
G36*
G01X675248Y1409998D02*
X678648D01*
G02Y1406992I0J-1503D01*
G01X675248D01*
G02Y1409998I0J1503D01*
G37*
G36*
G01Y1398086D02*
X678648D01*
G02Y1395080I0J-1503D01*
G01X675248D01*
G02Y1398086I0J1503D01*
G37*
G36*
G01X724208Y1361602D02*
X727608D01*
G02Y1358596I0J-1503D01*
G01X724208D01*
G02Y1361602I0J1503D01*
G37*
G36*
G01Y1409904D02*
X727608D01*
G02Y1406898I0J-1503D01*
G01X724208D01*
G02Y1409904I0J1503D01*
G37*
G36*
G01X736448Y1349690D02*
X739848D01*
G02Y1346684I0J-1503D01*
G01X736448D01*
G02Y1349690I0J1503D01*
G37*
G36*
G01X711968Y1373888D02*
X715368D01*
G02Y1370882I0J-1503D01*
G01X711968D01*
G02Y1373888I0J1503D01*
G37*
G36*
G01X736448Y1361602D02*
X739848D01*
G02Y1358596I0J-1503D01*
G01X736448D01*
G02Y1361602I0J1503D01*
G37*
G36*
G01X711968Y1385800D02*
X715368D01*
G02Y1382794I0J-1503D01*
G01X711968D01*
G02Y1385800I0J1503D01*
G37*
G36*
G01X687488Y1409998D02*
X690888D01*
G02Y1406992I0J-1503D01*
G01X687488D01*
G02Y1409998I0J1503D01*
G37*
G36*
G01Y1398086D02*
X690888D01*
G02Y1395080I0J-1503D01*
G01X687488D01*
G02Y1398086I0J1503D01*
G37*
G36*
G01X736448Y1373888D02*
X739848D01*
G02Y1370882I0J-1503D01*
G01X736448D01*
G02Y1373888I0J1503D01*
G37*
G36*
G01X748688Y1349690D02*
X752088D01*
G02Y1346684I0J-1503D01*
G01X748688D01*
G02Y1349690I0J1503D01*
G37*
G36*
G01X724208Y1373888D02*
X727608D01*
G02Y1370882I0J-1503D01*
G01X724208D01*
G02Y1373888I0J1503D01*
G37*
G36*
G01X736448Y1385800D02*
X739848D01*
G02Y1382794I0J-1503D01*
G01X736448D01*
G02Y1385800I0J1503D01*
G37*
G36*
G01X748688Y1361602D02*
X752088D01*
G02Y1358596I0J-1503D01*
G01X748688D01*
G02Y1361602I0J1503D01*
G37*
G36*
G01X736448Y1409904D02*
X739848D01*
G02Y1406898I0J-1503D01*
G01X736448D01*
G02Y1409904I0J1503D01*
G37*
G36*
G01Y1397992D02*
X739848D01*
G02Y1394986I0J-1503D01*
G01X736448D01*
G02Y1397992I0J1503D01*
G37*
G36*
G01X699728Y1409998D02*
X703128D01*
G02Y1406992I0J-1503D01*
G01X699728D01*
G02Y1409998I0J1503D01*
G37*
G36*
G01Y1398086D02*
X703128D01*
G02Y1395080I0J-1503D01*
G01X699728D01*
G02Y1398086I0J1503D01*
G37*
G36*
G01X748688Y1373888D02*
X752088D01*
G02Y1370882I0J-1503D01*
G01X748688D01*
G02Y1373888I0J1503D01*
G37*
G36*
G01X773168Y1349690D02*
X776568D01*
G02Y1346684I0J-1503D01*
G01X773168D01*
G02Y1349690I0J1503D01*
G37*
G36*
G01X760928D02*
X764328D01*
G02Y1346684I0J-1503D01*
G01X760928D01*
G02Y1349690I0J1503D01*
G37*
G36*
G01X711968Y1409998D02*
X715368D01*
G02Y1406992I0J-1503D01*
G01X711968D01*
G02Y1409998I0J1503D01*
G37*
G36*
G01Y1398086D02*
X715368D01*
G02Y1395080I0J-1503D01*
G01X711968D01*
G02Y1398086I0J1503D01*
G37*
G36*
G01X773168Y1361602D02*
X776568D01*
G02Y1358596I0J-1503D01*
G01X773168D01*
G02Y1361602I0J1503D01*
G37*
G36*
G01X760928Y1373888D02*
X764328D01*
G02Y1370882I0J-1503D01*
G01X760928D01*
G02Y1373888I0J1503D01*
G37*
G36*
G01Y1385800D02*
X764328D01*
G02Y1382794I0J-1503D01*
G01X760928D01*
G02Y1385800I0J1503D01*
G37*
G36*
G01X149552D02*
X152952D01*
G02Y1382794I0J-1503D01*
G01X149552D01*
G02Y1385800I0J1503D01*
G37*
G36*
G01Y1361602D02*
X152952D01*
G02Y1358596I0J-1503D01*
G01X149552D01*
G02Y1361602I0J1503D01*
G37*
G36*
G01X253863Y1373888D02*
X257263D01*
G02Y1370882I0J-1503D01*
G01X253863D01*
G02Y1373888I0J1503D01*
G37*
G36*
G01X198512D02*
X201912D01*
G02Y1370882I0J-1503D01*
G01X198512D01*
G02Y1373888I0J1503D01*
G37*
G36*
G01Y1409998D02*
X201912D01*
G02Y1406992I0J-1503D01*
G01X198512D01*
G02Y1409998I0J1503D01*
G37*
G36*
G01X364023Y1349690D02*
X367423D01*
G02Y1346684I0J-1503D01*
G01X364023D01*
G02Y1349690I0J1503D01*
G37*
G54D76*
X978614Y1210568D03*
Y1214838D03*
X914637Y1210568D03*
Y1214838D03*
X70947Y1201565D03*
Y1205835D03*
X1822594Y1211054D03*
Y1215324D03*
G54D82*
X665748Y1101376D03*
X658268D03*
X744290Y1097637D03*
X748031Y1105117D03*
X688189Y1086417D03*
Y1082677D03*
X744290Y1093897D03*
X740551Y1101376D03*
X751771Y1097637D03*
Y1093897D03*
X748031Y1101376D03*
X740551Y1105117D03*
X320866Y1221062D03*
X313385Y1209842D03*
X320866Y1213582D03*
X324606Y1221062D03*
X313385Y1217322D03*
X317125Y1236023D03*
X313385Y1224803D03*
X324606Y1228543D03*
X317125Y1232283D03*
X313385Y1228543D03*
X320866D03*
X324606Y1239763D03*
X313385Y1247243D03*
X320866D03*
X317125Y1250984D03*
X320866Y1239763D03*
X313385Y1243503D03*
X324606Y1247243D03*
X317125Y1254724D03*
X320866Y1198621D03*
X313385Y1202362D03*
X324606Y1198621D03*
X317125Y1202362D03*
X320866Y1206102D03*
X324606D03*
X317125Y1217322D03*
Y1209842D03*
X324606Y1213582D03*
X320866Y1090157D03*
X317125Y1093897D03*
X324606Y1090157D03*
X313385Y1101377D03*
X320866D03*
X324606D03*
X317125Y1097637D03*
X305905Y1224803D03*
X302165Y1236023D03*
X294685Y1250984D03*
X298425Y1247243D03*
X309645Y1250984D03*
X298425Y1243503D03*
X305905D03*
Y1247243D03*
X302165Y1250984D03*
X294685Y1254724D03*
X309645D03*
X302165D03*
X298425Y1213582D03*
X305905Y1209842D03*
Y1217322D03*
X302165Y1209842D03*
X298425Y1206102D03*
X302165Y1217322D03*
Y1232283D03*
X309645D03*
X294685Y1236023D03*
X298425Y1224803D03*
X294685Y1232283D03*
X298425Y1228543D03*
X309645Y1236023D03*
X305905Y1228543D03*
Y1127559D03*
Y1135039D03*
X302165D03*
Y1127559D03*
X298425Y1123818D03*
Y1131299D03*
Y1198621D03*
X305905Y1202362D03*
X302165D03*
X298425Y1105117D03*
Y1101376D03*
X309644Y1097637D03*
X302164D03*
X305905Y1105117D03*
X294684Y1097637D03*
X313385Y1105117D03*
X305905Y1101376D03*
X302165Y1120078D03*
X305905Y1112598D03*
X298425Y1116338D03*
X305905Y1120078D03*
X302165Y1112598D03*
X294684Y1093897D03*
X309644D03*
X302164D03*
X290944Y1247243D03*
Y1243503D03*
X294685Y1213582D03*
Y1206102D03*
X279724Y1232283D03*
Y1236023D03*
X287204Y1232283D03*
X283464Y1224803D03*
Y1228543D03*
X287204Y1236023D03*
X290944Y1224803D03*
Y1228543D03*
X294684Y1123818D03*
Y1131299D03*
X294685Y1198621D03*
X287203Y1093897D03*
X279723D03*
X283464Y1101376D03*
Y1105117D03*
X290944Y1101376D03*
X279723Y1097637D03*
X290944Y1105117D03*
X287203Y1097637D03*
X294684Y1116338D03*
X268503Y1228543D03*
X264763Y1236023D03*
Y1232283D03*
X268503Y1224803D03*
X275984D03*
X272244Y1236023D03*
X275984Y1228543D03*
X272244Y1232283D03*
X264762Y1097637D03*
X268503Y1105117D03*
X272243Y1097637D03*
X275984Y1105117D03*
X268503Y1101376D03*
X275984D03*
X272243Y1093897D03*
X264762D03*
X246062Y1243503D03*
X249803Y1250984D03*
X246062Y1247243D03*
X257283Y1250984D03*
X253543Y1247243D03*
Y1243503D03*
X257283Y1254724D03*
X249803D03*
X261023Y1224803D03*
X253543Y1228543D03*
X249803Y1232283D03*
X246062Y1228543D03*
X257283Y1232283D03*
Y1236023D03*
X246062Y1224803D03*
X261023Y1228543D03*
X253543Y1224803D03*
X249803Y1236023D03*
X249802Y1097637D03*
X257282D03*
X253543Y1105117D03*
Y1101376D03*
X261023Y1105117D03*
Y1101376D03*
X249802Y1093897D03*
X257282D03*
X234842Y1254724D03*
X242322D03*
X238582Y1224803D03*
Y1228543D03*
X242322Y1236023D03*
Y1232283D03*
X234842D03*
Y1236023D03*
X238582Y1247243D03*
X242322Y1250984D03*
X234842D03*
X238582Y1243503D03*
X246062Y1105117D03*
X242321Y1097637D03*
X234841D03*
X238582Y1101376D03*
X246062D03*
X238582Y1105117D03*
X234841Y1093897D03*
X242321D03*
X219881Y1254724D03*
X227362D03*
X231102Y1228543D03*
Y1224803D03*
X219881Y1232283D03*
Y1236023D03*
X223622Y1224803D03*
X227362Y1232283D03*
X223622Y1228543D03*
X227362Y1236023D03*
X231102Y1243503D03*
Y1247243D03*
X223622Y1243503D03*
Y1247243D03*
X219881Y1250984D03*
X227362D03*
Y1093897D03*
X219881D03*
Y1078936D03*
X231102Y1082677D03*
Y1086417D03*
X223622Y1082677D03*
X227362Y1078936D03*
X223622Y1086417D03*
X231102Y1101376D03*
X219881Y1097637D03*
X223621Y1101376D03*
Y1105117D03*
X227362Y1097637D03*
X231102Y1105117D03*
X227362Y1075196D03*
X219881D03*
X216141Y1247243D03*
X208661Y1243503D03*
X216141D03*
X204921Y1250984D03*
X208661Y1247243D03*
X201181Y1243503D03*
X212401Y1250984D03*
X201181Y1247243D03*
X212401Y1254724D03*
X204921D03*
Y1232283D03*
X201181Y1224803D03*
X212401Y1232283D03*
X208661Y1228543D03*
X212401Y1236023D03*
X216141Y1224803D03*
X208661D03*
X201181Y1228543D03*
X216141D03*
X204921Y1236023D03*
X208661Y1082677D03*
X216141Y1086417D03*
X201181Y1082677D03*
X216141D03*
X201181Y1086417D03*
X208661D03*
X204921Y1078936D03*
Y1097637D03*
X216141Y1101376D03*
X208661D03*
X212401Y1097637D03*
X208661Y1105117D03*
X216141D03*
X201181Y1101376D03*
Y1105117D03*
X204921Y1075196D03*
X212401D03*
Y1093897D03*
X204921D03*
X212401Y1078936D03*
X197440Y1236023D03*
X186220Y1224803D03*
X193700Y1228543D03*
X197440Y1232283D03*
X189960Y1236023D03*
X186220Y1228543D03*
X193700Y1224803D03*
X189960Y1232283D03*
X197440Y1093897D03*
X189960D03*
X186220Y1082677D03*
Y1086417D03*
X189960Y1078936D03*
X193700Y1086417D03*
Y1082677D03*
X197440Y1078936D03*
X193700Y1105117D03*
X189960Y1097637D03*
X186220Y1105117D03*
X197440Y1097637D03*
X193700Y1101376D03*
X186220D03*
X189960Y1075196D03*
X197440D03*
X171259Y1198621D03*
X174999Y1206102D03*
X171259Y1213582D03*
X174999D03*
X178740Y1228543D03*
X171259Y1224803D03*
X182480Y1236023D03*
Y1232283D03*
X174999D03*
X171259Y1228543D03*
X178740Y1224803D03*
X174999Y1236023D03*
Y1191141D03*
X171259D03*
X174999Y1198621D03*
X171259Y1206102D03*
X174999Y1093897D03*
X182480D03*
X174999Y1078936D03*
X182480D03*
X178740Y1082677D03*
Y1086417D03*
X182480Y1097637D03*
X174999D03*
X178740Y1101376D03*
Y1105117D03*
X174999Y1075196D03*
X182480D03*
X167519Y1209842D03*
X163779D03*
Y1217322D03*
X167519D03*
X160039Y1236023D03*
X163779Y1224803D03*
X156299D03*
X167519Y1232283D03*
X156299Y1228543D03*
X163779D03*
X167519Y1236023D03*
X160039Y1232283D03*
X152559Y1236023D03*
Y1232283D03*
X163779Y1194881D03*
Y1202362D03*
X167519Y1194881D03*
Y1202362D03*
X163779Y1187401D03*
X167519D03*
X148818Y1239763D03*
X145078D03*
Y1228543D03*
X148818D03*
X1658463Y1097637D03*
X1617322Y1101376D03*
X1639763D03*
X1636022Y1097637D03*
Y1093897D03*
X1662204Y1101376D03*
X1621062Y1093897D03*
X1658463D03*
X1628542Y1097637D03*
X1643503D03*
Y1093897D03*
X1647244Y1101376D03*
X662008Y1078936D03*
X1621062Y1097637D03*
X1632283Y1101376D03*
X1624803D03*
X1654724D03*
X699408Y1093897D03*
X736810D03*
Y1097637D03*
X658268Y1082677D03*
X1059251Y1239763D03*
X658268Y1086417D03*
X669488Y1093897D03*
X639567D03*
X635827Y1101376D03*
Y1105117D03*
X639567Y1097637D03*
X632086D03*
Y1075196D03*
X639567D03*
X774212Y1093897D03*
X729330Y1097637D03*
X721849Y1093897D03*
X781693Y1101377D03*
X669488Y1097637D03*
X1628542Y1093897D03*
X650787Y1082677D03*
Y1101376D03*
X647047Y1097637D03*
X762992Y1120078D03*
X635827Y1082677D03*
X777953Y1101377D03*
X770472D03*
X647047Y1075196D03*
X654527D03*
X770472Y1105117D03*
X669488Y1075196D03*
X774212Y1097637D03*
X643307Y1101376D03*
Y1105117D03*
X647047Y1078936D03*
X654527D03*
X643307Y1082677D03*
Y1086417D03*
X781693Y1090157D03*
X777953D03*
X650787Y1105117D03*
X762992Y1112598D03*
X650787Y1086417D03*
X639567Y1078936D03*
X635827Y1086417D03*
X762992Y1135039D03*
Y1127559D03*
X1647244Y1105116D03*
X662008Y1093897D03*
Y1097637D03*
X658268Y1105117D03*
X676968Y1075196D03*
X632086Y1093897D03*
Y1078936D03*
X1624803Y1105116D03*
X1650983Y1097637D03*
Y1093897D03*
X1677165Y1101376D03*
X1669685D03*
X1680904Y1093897D03*
Y1097637D03*
X1673424Y1093897D03*
Y1097637D03*
X1665944D03*
Y1093897D03*
X1695866Y1090157D03*
X1692126D03*
X1688385Y1097637D03*
Y1093897D03*
X1684645Y1101377D03*
X1695866D03*
X1692126D03*
X1550000Y1105116D03*
X1564960D03*
X1557480D03*
X1572441D03*
X1579921D03*
X1594881D03*
X1587401D03*
X1609842D03*
X1602362D03*
X1516338Y1191141D03*
Y1198621D03*
Y1206102D03*
Y1213582D03*
X1535039Y1187401D03*
X1527559D03*
X1523819D03*
X1535039Y1194881D03*
Y1202362D03*
X1523819Y1194881D03*
X1527559D03*
X1523819Y1202362D03*
X1527559D03*
X1520078Y1191141D03*
Y1198621D03*
Y1206102D03*
X1535039Y1217322D03*
Y1209842D03*
X1527559D03*
X1523819D03*
Y1217322D03*
X1527559D03*
X1520078Y1213582D03*
X1538779Y1187401D03*
Y1194881D03*
Y1202362D03*
Y1217322D03*
Y1209842D03*
X1546259Y1191141D03*
X1542519D03*
Y1198621D03*
X1546259D03*
X1542519Y1206102D03*
X1546259D03*
X602165Y1228543D03*
X613386Y1243503D03*
Y1247243D03*
X609646Y1250984D03*
Y1254724D03*
X617126D03*
Y1250984D03*
X620866Y1247243D03*
Y1243503D03*
X665748Y1105117D03*
X613386Y1202362D03*
X609646D03*
X613386Y1194881D03*
X609646D03*
X613386Y1217322D03*
X609646D03*
Y1209842D03*
X613386D03*
X620866Y1187401D03*
Y1202362D03*
Y1194881D03*
Y1209842D03*
X624606Y1187401D03*
X632086Y1206102D03*
X628346D03*
X632086Y1198621D03*
X628346D03*
X624606Y1202362D03*
Y1194881D03*
X628346Y1191141D03*
X632086D03*
Y1213582D03*
X628346D03*
X624606Y1209842D03*
X620866Y1217322D03*
X624606D03*
X762992Y1105117D03*
X684449Y1075196D03*
X755512Y1101376D03*
X766731Y1097637D03*
X755512Y1105117D03*
X766731Y1093897D03*
X759251Y1097637D03*
X762992Y1101376D03*
X759251Y1093897D03*
X1516338Y1221062D03*
Y1228543D03*
X662008Y1075196D03*
X647047Y1093897D03*
X654527Y1097637D03*
Y1093897D03*
X669488Y1078936D03*
X602165Y1239763D03*
X718110Y1101376D03*
X714369Y1093897D03*
Y1097637D03*
X706889Y1093897D03*
Y1097637D03*
X684449Y1078936D03*
X680709Y1086417D03*
Y1082677D03*
X676968Y1078936D03*
X673228Y1082677D03*
Y1086417D03*
X703149Y1105117D03*
X699408Y1097637D03*
X691928Y1093897D03*
Y1097637D03*
X695669Y1101376D03*
Y1105117D03*
X703149Y1101376D03*
X710630Y1105117D03*
Y1101376D03*
X718110Y1105117D03*
X684449Y1097637D03*
Y1093897D03*
X1527559Y1224803D03*
X676968Y1097637D03*
Y1093897D03*
X688189Y1105117D03*
Y1101376D03*
X1520078Y1221062D03*
X680708Y1105117D03*
Y1101376D03*
X673228Y1105117D03*
Y1101376D03*
X725590Y1105117D03*
X733071Y1101376D03*
Y1105117D03*
X725590Y1101376D03*
X665748Y1082677D03*
Y1086417D03*
X721849Y1097637D03*
X729330Y1093897D03*
X1516338Y1239763D03*
X770472Y1224803D03*
Y1228543D03*
X777953D03*
X781693D03*
X774212Y1232283D03*
Y1236023D03*
X755512Y1224803D03*
Y1228543D03*
X762992Y1224803D03*
Y1228543D03*
X759252Y1232283D03*
Y1236023D03*
X766732D03*
Y1232283D03*
X762992Y1217322D03*
X759252D03*
X755512Y1213582D03*
X759252Y1209842D03*
X762992D03*
Y1202362D03*
X759252D03*
X755512Y1206102D03*
Y1198621D03*
X751772Y1236023D03*
Y1232283D03*
Y1213582D03*
Y1206102D03*
Y1198621D03*
X759252Y1127559D03*
Y1135039D03*
X755512Y1131299D03*
X759252Y1112598D03*
Y1120078D03*
X755512Y1116338D03*
Y1123818D03*
X751771Y1131299D03*
Y1116338D03*
Y1123818D03*
X1632283Y1105116D03*
X1617322D03*
X1639763D03*
X1662204D03*
X1654724D03*
X1677165D03*
X1669685D03*
X1684645Y1105117D03*
X1673425Y1112598D03*
Y1120078D03*
X1669685Y1116338D03*
Y1123818D03*
X1665945Y1116338D03*
Y1123818D03*
X1677165Y1112598D03*
Y1120078D03*
X1673425Y1127559D03*
X1669685Y1131299D03*
X1665945D03*
X1677165Y1127559D03*
X1673425Y1135039D03*
X1677165D03*
X1077952Y1187401D03*
Y1194881D03*
Y1202362D03*
Y1217322D03*
Y1209842D03*
X1081692Y1187401D03*
Y1194881D03*
Y1202362D03*
Y1217322D03*
Y1209842D03*
X1089172Y1191141D03*
X1085432D03*
Y1198621D03*
X1089172D03*
X1085432Y1206102D03*
X1089172D03*
X1059251Y1228543D03*
X1070472Y1224803D03*
Y1228543D03*
X1077952Y1224803D03*
Y1228543D03*
X1066732Y1232283D03*
Y1236023D03*
X1074212D03*
Y1232283D03*
X1062991Y1228543D03*
Y1239763D03*
X1085432Y1213582D03*
X1089172D03*
X1081692Y1232283D03*
Y1236023D03*
X1085432Y1224803D03*
Y1228543D03*
X1089172Y1232283D03*
Y1236023D03*
X1092913Y1224803D03*
Y1228543D03*
X1100393Y1224803D03*
Y1228543D03*
X1104133Y1236023D03*
Y1232283D03*
X1107873Y1228543D03*
Y1224803D03*
X1096653Y1232283D03*
Y1236023D03*
X1115354Y1224803D03*
Y1228543D03*
X1119094Y1236023D03*
Y1232283D03*
X1122834Y1228543D03*
Y1224803D03*
X1126574Y1232283D03*
Y1236023D03*
X1111613Y1232283D03*
Y1236023D03*
X1115354Y1243503D03*
Y1247243D03*
X1119094Y1254724D03*
Y1250984D03*
X1122834Y1247243D03*
Y1243503D03*
X1126574Y1250984D03*
Y1254724D03*
X1130314Y1224803D03*
Y1228543D03*
X1141535Y1236023D03*
Y1232283D03*
X1134054Y1236023D03*
Y1232283D03*
X1137795Y1228543D03*
Y1224803D03*
X1130314Y1243503D03*
Y1247243D03*
X1134054Y1254724D03*
Y1250984D03*
X1137795Y1247243D03*
Y1243503D03*
X1141535Y1250984D03*
Y1254724D03*
X1149015Y1236023D03*
Y1232283D03*
X1152755Y1224803D03*
X1156495Y1232283D03*
Y1236023D03*
X1152755Y1228543D03*
X1145275Y1224803D03*
Y1228543D03*
X1149015Y1254724D03*
Y1250984D03*
X1152755Y1247243D03*
Y1243503D03*
X1156495Y1250984D03*
Y1254724D03*
X1145275Y1243503D03*
Y1247243D03*
X1163976Y1236023D03*
Y1232283D03*
X1167716Y1228543D03*
Y1224803D03*
X1175196D03*
Y1228543D03*
X1171456Y1232283D03*
Y1236023D03*
X1160235Y1224803D03*
Y1228543D03*
X1163976Y1254724D03*
Y1250984D03*
X1167716Y1243503D03*
Y1247243D03*
X1171456Y1250984D03*
Y1254724D03*
X1160235Y1247243D03*
Y1243503D03*
X1178936Y1236023D03*
Y1232283D03*
X1182676Y1224803D03*
Y1228543D03*
X1186417Y1236023D03*
Y1232283D03*
X1190157Y1228543D03*
Y1224803D03*
X1197637D03*
Y1228543D03*
X1201377Y1232283D03*
Y1236023D03*
X1205117Y1228543D03*
Y1224803D03*
X1193897Y1236023D03*
Y1232283D03*
X1205117Y1243503D03*
Y1247243D03*
X1212598Y1224803D03*
Y1228543D03*
X1220078Y1224803D03*
Y1228543D03*
X1216338Y1232283D03*
Y1236023D03*
X1223818D03*
Y1232283D03*
X1208858Y1236023D03*
Y1232283D03*
X1220078Y1243503D03*
Y1247243D03*
X1223818Y1250984D03*
Y1254724D03*
X1216338D03*
Y1250984D03*
X1212598Y1247243D03*
Y1243503D03*
X1208858Y1250984D03*
Y1254724D03*
X1227558Y1224803D03*
Y1228543D03*
X1235039D03*
X1238779D03*
X1231298Y1232283D03*
Y1236023D03*
X1238779Y1239763D03*
X1235039D03*
X1238779Y1247243D03*
X1235039D03*
X1231298Y1250984D03*
Y1254724D03*
X1227558Y1247243D03*
Y1243503D03*
X1220078Y1202362D03*
X1216338D03*
X1212598Y1206102D03*
Y1198621D03*
X1208858Y1206102D03*
Y1198621D03*
X1220078Y1217322D03*
X1216338D03*
X1212598Y1213582D03*
X1216338Y1209842D03*
X1220078D03*
X1208858Y1213582D03*
X1238779Y1198621D03*
X1235039D03*
X1231298Y1202362D03*
X1227558D03*
X1235039Y1206102D03*
X1238779D03*
Y1213582D03*
X1235039D03*
X1238779Y1221062D03*
X1235039D03*
X1231298Y1217322D03*
X1227558D03*
Y1209842D03*
X1231298D03*
X1089172Y1075196D03*
Y1078936D03*
X1092913Y1086417D03*
Y1082677D03*
X1089172Y1097637D03*
Y1093897D03*
X1092913Y1101376D03*
X1104133Y1075196D03*
X1096653D03*
X1104133Y1078936D03*
X1107873Y1082677D03*
Y1086417D03*
X1100393D03*
Y1082677D03*
X1096653Y1078936D03*
X1104133Y1093897D03*
Y1097637D03*
X1107873Y1101376D03*
X1100393D03*
X1096653Y1097637D03*
Y1093897D03*
X1126574Y1075196D03*
X1119094D03*
X1111613D03*
X1126574Y1078936D03*
X1122834Y1086417D03*
Y1082677D03*
X1119094Y1078936D03*
X1115354Y1086417D03*
Y1082677D03*
X1111613Y1078936D03*
X1126574Y1093897D03*
Y1097637D03*
X1119094Y1093897D03*
Y1097637D03*
X1115354Y1101376D03*
X1122834D03*
X1111613Y1097637D03*
Y1093897D03*
X1141535Y1075196D03*
X1134054D03*
X1141535Y1078936D03*
X1137795Y1086417D03*
Y1082677D03*
X1134054Y1078936D03*
X1130314Y1082677D03*
Y1086417D03*
X1141535Y1097637D03*
Y1093897D03*
X1134054Y1097637D03*
Y1093897D03*
X1137794Y1101376D03*
X1130314D03*
X1145275Y1086417D03*
Y1082677D03*
X1152755Y1101376D03*
X1156494Y1093897D03*
Y1097637D03*
X1149014D03*
Y1093897D03*
X1145275Y1101376D03*
X1175196D03*
X1167716D03*
X1171455Y1093897D03*
Y1097637D03*
X1163975Y1093897D03*
Y1097637D03*
X1160235Y1101376D03*
X1190157D03*
X1182676D03*
X1186416Y1093897D03*
Y1097637D03*
X1178935Y1093897D03*
Y1097637D03*
X1205117Y1101376D03*
X1197637D03*
X1201376Y1097637D03*
Y1093897D03*
X1193896Y1097637D03*
Y1093897D03*
X1220078Y1101376D03*
X1212598D03*
X1223817Y1093897D03*
Y1097637D03*
X1216337Y1093897D03*
Y1097637D03*
X1208857D03*
Y1093897D03*
X1238779Y1090157D03*
X1235039D03*
X1231298Y1097637D03*
Y1093897D03*
X1227558Y1101377D03*
X1238779D03*
X1235039D03*
X1092913Y1105116D03*
X1107873D03*
X1100393D03*
X1115354D03*
X1122834D03*
X1137794D03*
X1130314D03*
X1152755D03*
X1145275D03*
X1175196D03*
X1167716D03*
X1160235D03*
X1190157D03*
X1182676D03*
X1205117D03*
X1197637D03*
X1220078D03*
X1212598D03*
X1227558Y1105117D03*
X1216338Y1112598D03*
Y1120078D03*
X1212598Y1116338D03*
Y1123818D03*
X1208858Y1116338D03*
Y1123818D03*
X1220078Y1112598D03*
Y1120078D03*
X1216338Y1127559D03*
X1212598Y1131299D03*
X1208858D03*
X1220078Y1127559D03*
X1216338Y1135039D03*
X1220078D03*
X1557480Y1086417D03*
Y1082677D03*
X1553740Y1078936D03*
X1561220Y1093897D03*
Y1097637D03*
X1564960Y1101376D03*
X1557480D03*
X1553740Y1097637D03*
Y1093897D03*
X1583661Y1075196D03*
X1576181D03*
X1568700D03*
X1583661Y1078936D03*
X1579921Y1086417D03*
Y1082677D03*
X1576181Y1078936D03*
X1572441Y1086417D03*
Y1082677D03*
X1568700Y1078936D03*
X1583661Y1093897D03*
Y1097637D03*
X1576181Y1093897D03*
Y1097637D03*
X1572441Y1101376D03*
X1579921D03*
X1568700Y1097637D03*
Y1093897D03*
X1598622Y1075196D03*
X1591141D03*
X1598622Y1078936D03*
X1594882Y1086417D03*
Y1082677D03*
X1591141Y1078936D03*
X1587401Y1082677D03*
Y1086417D03*
X1598622Y1097637D03*
Y1093897D03*
X1591141Y1097637D03*
Y1093897D03*
X1594881Y1101376D03*
X1587401D03*
X1602362Y1086417D03*
Y1082677D03*
X1609842Y1101376D03*
X1613581Y1093897D03*
Y1097637D03*
X1606101D03*
Y1093897D03*
X1602362Y1101376D03*
X1546259Y1078936D03*
X1550000Y1086417D03*
Y1082677D03*
X1546259Y1097637D03*
Y1093897D03*
X1550000Y1101376D03*
X1561220Y1075196D03*
X1553740D03*
X1561220Y1078936D03*
X1564960Y1082677D03*
Y1086417D03*
X1546259Y1075196D03*
X609646Y1187401D03*
X613386D03*
X1665945Y1198621D03*
X1677165Y1217322D03*
X1673425D03*
X1669685Y1213582D03*
X1673425Y1209842D03*
X1677165D03*
X1665945Y1213582D03*
Y1206102D03*
X1695866Y1239763D03*
X1692126D03*
X1677165Y1202362D03*
X1673425D03*
X1669685Y1206102D03*
Y1198621D03*
X1684645Y1224803D03*
Y1228543D03*
X1692126D03*
X1695866D03*
X1688385Y1232283D03*
Y1236023D03*
X1527559Y1228543D03*
X1535039Y1224803D03*
Y1228543D03*
X1523819Y1232283D03*
Y1236023D03*
X1531299D03*
Y1232283D03*
X1520078Y1228543D03*
X1535039Y1243503D03*
Y1247243D03*
X1531299Y1250984D03*
Y1254724D03*
X1523819D03*
Y1250984D03*
X1527559Y1247243D03*
Y1243503D03*
X1520078Y1247243D03*
Y1239763D03*
X1542519Y1213582D03*
X1546259D03*
X1538779Y1232283D03*
Y1236023D03*
X1542519Y1224803D03*
Y1228543D03*
X1546259Y1232283D03*
Y1236023D03*
Y1250984D03*
Y1254724D03*
X1538779D03*
Y1250984D03*
X1542519Y1247243D03*
Y1243503D03*
X1550000Y1224803D03*
Y1228543D03*
Y1243503D03*
Y1247243D03*
X1557480Y1224803D03*
Y1228543D03*
X1561220Y1236023D03*
Y1232283D03*
X1564960Y1228543D03*
Y1224803D03*
X1553740Y1232283D03*
Y1236023D03*
X1557480Y1243503D03*
Y1247243D03*
X1561220Y1254724D03*
Y1250984D03*
X1564960Y1247243D03*
Y1243503D03*
X1553740Y1250984D03*
Y1254724D03*
X1572441Y1224803D03*
Y1228543D03*
X1576181Y1236023D03*
Y1232283D03*
X1579921Y1228543D03*
Y1224803D03*
X1583661Y1232283D03*
Y1236023D03*
X1568700Y1232283D03*
Y1236023D03*
Y1250984D03*
Y1254724D03*
X1587401Y1224803D03*
Y1228543D03*
X1598622Y1236023D03*
Y1232283D03*
X1591141Y1236023D03*
Y1232283D03*
X1594882Y1228543D03*
Y1224803D03*
X1606102Y1236023D03*
Y1232283D03*
X1609842Y1224803D03*
X1613582Y1232283D03*
Y1236023D03*
X1609842Y1228543D03*
X1602362Y1224803D03*
Y1228543D03*
X1621063Y1236023D03*
Y1232283D03*
X1624803Y1228543D03*
Y1224803D03*
X1632283D03*
Y1228543D03*
X1628543Y1232283D03*
Y1236023D03*
X1617322Y1224803D03*
Y1228543D03*
X1632283Y1247243D03*
Y1243503D03*
X1636023Y1236023D03*
Y1232283D03*
X1639763Y1224803D03*
Y1228543D03*
X1643504Y1236023D03*
Y1232283D03*
X1647244Y1228543D03*
Y1224803D03*
X1636023Y1254724D03*
Y1250984D03*
X1639763Y1243503D03*
Y1247243D03*
X1643504Y1250984D03*
Y1254724D03*
X1647244Y1247243D03*
Y1243503D03*
X1654724Y1224803D03*
Y1228543D03*
X1658464Y1232283D03*
Y1236023D03*
X1662204Y1228543D03*
Y1224803D03*
X1650984Y1236023D03*
Y1232283D03*
X1654724Y1247243D03*
X1658464Y1254724D03*
Y1250984D03*
X1654724Y1243503D03*
X1650984Y1254724D03*
Y1250984D03*
X1669685Y1224803D03*
Y1228543D03*
X1677165Y1224803D03*
Y1228543D03*
X1673425Y1232283D03*
Y1236023D03*
X1680905D03*
Y1232283D03*
X1665945Y1236023D03*
Y1232283D03*
X777953Y1239763D03*
X781693D03*
X605905Y1228543D03*
Y1239763D03*
Y1247243D03*
X617126Y1232283D03*
Y1236023D03*
X609646D03*
Y1232283D03*
X620866Y1228543D03*
Y1224803D03*
X613386Y1228543D03*
Y1224803D03*
X639567Y1236023D03*
Y1232283D03*
X632086Y1236023D03*
Y1232283D03*
X635827Y1228543D03*
Y1224803D03*
X628346Y1228543D03*
Y1224803D03*
X624606Y1236023D03*
Y1232283D03*
X639567Y1254724D03*
Y1250984D03*
X628346Y1243503D03*
Y1247243D03*
X624606Y1250984D03*
Y1254724D03*
X632086D03*
Y1250984D03*
X635827Y1247243D03*
Y1243503D03*
X654527Y1236023D03*
Y1232283D03*
X650787Y1224803D03*
Y1228543D03*
X647047Y1232283D03*
Y1236023D03*
X643307Y1228543D03*
Y1224803D03*
X654527Y1254724D03*
Y1250984D03*
X650787Y1243503D03*
Y1247243D03*
X647047Y1250984D03*
Y1254724D03*
X643307Y1247243D03*
Y1243503D03*
X669488Y1236023D03*
Y1232283D03*
X665748Y1224803D03*
Y1228543D03*
X662008Y1232283D03*
Y1236023D03*
X658268Y1228543D03*
Y1224803D03*
X688189Y1228543D03*
Y1224803D03*
X680709D03*
Y1228543D03*
X676968Y1232283D03*
Y1236023D03*
X684449Y1232283D03*
Y1236023D03*
X673228Y1228543D03*
Y1224803D03*
X695669Y1228543D03*
X699409Y1236023D03*
Y1232283D03*
X703149Y1228543D03*
Y1224803D03*
X695669D03*
X691929Y1232283D03*
Y1236023D03*
X714370D03*
Y1232283D03*
X718110Y1228543D03*
Y1224803D03*
X710630D03*
Y1228543D03*
X706890Y1232283D03*
Y1236023D03*
X718110Y1243503D03*
Y1247243D03*
X733071Y1224803D03*
Y1228543D03*
X736811Y1232283D03*
Y1236023D03*
X729331Y1232283D03*
Y1236023D03*
X725590Y1228543D03*
Y1224803D03*
X721850Y1232283D03*
Y1236023D03*
X733071Y1243503D03*
Y1247243D03*
X736811Y1250984D03*
Y1254724D03*
X729331D03*
Y1250984D03*
X725590Y1247243D03*
Y1243503D03*
X721850Y1250984D03*
Y1254724D03*
X748031Y1224803D03*
Y1228543D03*
X744291Y1236023D03*
Y1232283D03*
X740551Y1228543D03*
Y1224803D03*
Y1243503D03*
X744291Y1250984D03*
Y1254724D03*
X740551Y1247243D03*
X602165Y1206102D03*
X605905D03*
X602165Y1198621D03*
X605905D03*
X602165Y1191141D03*
X605905D03*
X602165Y1221062D03*
X605905D03*
Y1213582D03*
X602165D03*
X1516338Y1247243D03*
X602165D03*
G54D80*
X970071Y1409152D03*
Y1365652D03*
G54D73*
X743337Y374862D03*
G54D66*
X1819042Y-27188D03*
Y-37188D03*
Y-47188D03*
X1753686Y-85978D03*
Y-75978D03*
Y-65978D03*
X1564906Y-27086D03*
Y-47086D03*
Y-37086D03*
X1574906Y-66006D03*
Y-86006D03*
Y-76006D03*
X1534542Y-27058D03*
Y-37058D03*
Y-47058D03*
X1499186Y-65978D03*
Y-75978D03*
Y-85978D03*
X1280406Y-26956D03*
Y-46956D03*
Y-36956D03*
X1320406Y-86006D03*
Y-66006D03*
Y-76006D03*
X1248042Y-26928D03*
X1242686Y-65978D03*
Y-75978D03*
Y-85978D03*
X993906Y-26826D03*
Y-46826D03*
Y-36826D03*
X1063906Y-66006D03*
Y-86006D03*
Y-76006D03*
X964542Y-26798D03*
Y-36798D03*
X939542D03*
Y-26798D03*
X989386Y-65978D03*
Y-75978D03*
X964386D03*
Y-65978D03*
X710406Y-26826D03*
Y-36826D03*
X735406D03*
Y-26826D03*
X830406Y-66006D03*
Y-76006D03*
X855406D03*
Y-66006D03*
X1248042Y-36928D03*
Y-46928D03*
X1018906Y-36826D03*
Y-46826D03*
X1217686Y-65978D03*
Y-75978D03*
X1305406Y-36956D03*
Y-46956D03*
Y-26956D03*
X1018906Y-26826D03*
X1217686Y-85978D03*
X1223042Y-26928D03*
Y-36928D03*
X1088906Y-76006D03*
Y-86006D03*
X1345406D03*
Y-76006D03*
Y-66006D03*
X1088906D03*
X1223042Y-46928D03*
X1474186Y-65978D03*
Y-75978D03*
Y-85978D03*
X1509542Y-27058D03*
Y-37058D03*
Y-47058D03*
X1794042Y-27188D03*
Y-37188D03*
Y-47188D03*
X1728686Y-65978D03*
Y-75978D03*
Y-85978D03*
X1589906Y-37086D03*
Y-47086D03*
Y-27086D03*
X1599906Y-76006D03*
Y-86006D03*
Y-66006D03*
G54D79*
X909360Y230906D03*
Y274606D03*
G54D74*
X1729390Y144095D03*
X1627028D03*
X1169941D03*
X1067579D03*
X965217D03*
X815217D03*
G54D72*
X640522Y630650D03*
X1657510Y374862D03*
X1554695Y630650D03*
X1200423Y374862D03*
X1097608Y630650D03*
X286250Y374862D03*
X183435Y630650D03*
G54D78*
X51043Y144095D03*
X57933Y66811D03*
X153405Y144095D03*
X160295Y66811D03*
X255767Y144095D03*
X262657Y66811D03*
X358129Y144095D03*
X365019Y66811D03*
X508130Y144095D03*
X515020Y66811D03*
X610492Y144095D03*
X617382Y66811D03*
X712854Y144095D03*
X719744Y66811D03*
X822106D03*
X972106D03*
X1074468D03*
X1176830D03*
X1272302Y144095D03*
X1279192Y66811D03*
X1422303Y144095D03*
X1429193Y66811D03*
X1524665Y144095D03*
X1531555Y66811D03*
X1633917D03*
X1736279D03*
G54D71*
X736447Y630650D03*
X1650620D03*
X1561585Y374862D03*
X1193533Y630650D03*
X1104498Y374862D03*
X279360Y630650D03*
X190325Y374862D03*
G54D70*
X1817323Y56693D03*
G54D69*
X924650Y1326119D03*
X370202Y1313064D03*
X559070Y686509D03*
X561570Y694509D03*
X559070Y702509D03*
X561570Y710509D03*
X559070Y718509D03*
X460950Y326485D03*
X463950Y334359D03*
X460950Y342233D03*
X463950Y350107D03*
X937000Y313983D03*
X66856Y105949D03*
X169218D03*
X271580D03*
X373942D03*
X893284Y235040D03*
X899352Y310261D03*
X1079748Y321042D03*
X1209184Y461917D03*
X1302896Y342096D03*
X1438116Y105949D03*
X1540478D03*
X1642840D03*
X1745202D03*
X1089096Y543562D03*
X1754906Y822634D03*
X917882Y326517D03*
X212980Y485254D03*
X205680Y478168D03*
X138290Y485260D03*
X148692Y478199D03*
X788482Y476118D03*
X778080Y483179D03*
X721092Y483210D03*
X713792Y476124D03*
X1245568Y476118D03*
X1235166Y483179D03*
X1178178Y483210D03*
X1170878Y476124D03*
X1584240Y485254D03*
X1576940Y478168D03*
X1519952Y478199D03*
X1509550Y485260D03*
X35688Y127128D03*
X28388Y120042D03*
Y134215D03*
X35688Y112955D03*
X130750Y120042D03*
Y134215D03*
X148692Y421047D03*
X138290Y413987D03*
X140690Y399813D03*
X148692Y406874D03*
Y392701D03*
X138050Y127128D03*
Y112955D03*
X138290Y471087D03*
Y442333D03*
Y428160D03*
X148692Y435221D03*
X205680Y399782D03*
X212980Y406868D03*
Y392695D03*
Y471081D03*
Y435215D03*
X205680Y442302D03*
Y428128D03*
Y413955D03*
X212980Y421041D03*
X233112Y134215D03*
Y120042D03*
X240412Y127128D03*
Y112955D03*
X342774Y127128D03*
X335474Y134215D03*
Y120042D03*
X342774Y112955D03*
X533092Y127096D03*
Y112923D03*
X543494Y134209D03*
Y120035D03*
X635454Y127096D03*
Y112923D03*
X645856Y134209D03*
Y120035D03*
X748218Y134209D03*
X737816Y127096D03*
X748218Y120035D03*
X737816Y112923D03*
X721092Y469037D03*
X778080Y469006D03*
X840178Y127096D03*
Y112923D03*
X850580Y134209D03*
Y120035D03*
X990178Y127096D03*
Y112923D03*
X1000580Y134209D03*
Y120035D03*
X1092540Y127096D03*
Y112923D03*
X1102942Y134209D03*
Y120035D03*
X1178178Y469037D03*
X1205304Y134209D03*
X1194902Y127096D03*
X1205304Y120035D03*
X1194902Y112923D03*
X1235166Y469006D03*
X1297264Y127096D03*
Y112923D03*
X1307666Y134209D03*
Y120035D03*
X1399648Y120042D03*
Y134215D03*
X1406948Y127128D03*
Y112955D03*
X1509310D03*
X1509550Y428160D03*
Y413987D03*
X1511950Y399813D03*
X1502010Y134215D03*
X1509310Y127128D03*
X1502010Y120042D03*
X1519952Y421047D03*
Y406874D03*
Y392701D03*
X1509550Y471087D03*
Y442333D03*
X1519952Y435221D03*
X1576940Y442302D03*
Y428128D03*
Y413955D03*
Y399782D03*
X1584240Y421041D03*
Y406868D03*
Y392695D03*
X1604372Y134215D03*
X1611672Y127128D03*
X1604372Y120042D03*
X1611672Y112955D03*
X1584240Y471081D03*
Y435215D03*
X1706734Y134215D03*
Y120042D03*
X1714034Y127128D03*
Y112955D03*
X148692Y536506D03*
Y522333D03*
X138290Y515221D03*
X148692Y492373D03*
X138290Y529394D03*
X205680Y492341D03*
Y536475D03*
X212980Y529388D03*
Y515215D03*
X205680Y522302D03*
X713792Y612817D03*
Y598644D03*
Y584471D03*
Y570297D03*
Y534431D03*
Y520258D03*
Y490297D03*
X721092Y591557D03*
Y577384D03*
Y563210D03*
Y527344D03*
Y513171D03*
Y605730D03*
X778080Y563179D03*
Y527313D03*
Y513139D03*
Y591525D03*
Y605699D03*
Y577352D03*
X788482Y570291D03*
Y534425D03*
Y520252D03*
Y490291D03*
Y612811D03*
Y598638D03*
Y584465D03*
X1170878Y612817D03*
Y598644D03*
Y584471D03*
Y570297D03*
Y534431D03*
Y520258D03*
Y490297D03*
X1178178Y563210D03*
Y527344D03*
Y513171D03*
Y605730D03*
Y591557D03*
Y577384D03*
X1235166Y527313D03*
Y513139D03*
Y605699D03*
Y591525D03*
Y577352D03*
Y563179D03*
X1245568Y570291D03*
Y534425D03*
Y520252D03*
Y490291D03*
Y612811D03*
Y598638D03*
Y584465D03*
X1509550Y529394D03*
Y515221D03*
X1519952Y536506D03*
Y522333D03*
Y492373D03*
X1576940Y536475D03*
Y522302D03*
Y492341D03*
X1584240Y529388D03*
Y515215D03*
X7982Y1527335D03*
G54D67*
X1592187Y-71006D03*
Y-81006D03*
X1582187Y-32086D03*
Y-42086D03*
X1736405Y-80978D03*
Y-70978D03*
X1801761Y-42188D03*
Y-32188D03*
X1517261Y-42058D03*
Y-32058D03*
X1481905Y-80978D03*
Y-70978D03*
X1230761Y-41928D03*
X1081187Y-71006D03*
X1337687D03*
Y-81006D03*
X1081187D03*
X1230761Y-31928D03*
X1225405Y-80978D03*
X1011187Y-31826D03*
X1297687Y-31956D03*
Y-41956D03*
X1225405Y-70978D03*
X1011187Y-41826D03*
X213969Y1460153D03*
Y1449153D03*
X227249Y1460153D03*
Y1449153D03*
G54D81*
X1817323Y1567323D03*
G54D68*
X1009333Y1344993D03*
X1015659Y681354D03*
X933725Y587636D03*
X933741Y596387D03*
X486837Y703006D03*
X394883Y340077D03*
X217907Y1428752D03*
X415203Y1497818D03*
X397267Y1516347D03*
X295011Y461917D03*
X523943Y105949D03*
X626305D03*
X728667D03*
X752097Y461917D03*
X831029Y105949D03*
X981029D03*
X1083391D03*
X1080351Y329955D03*
X1185753Y105949D03*
X1288115D03*
X1366535Y353200D03*
Y337452D03*
X1363535Y345326D03*
Y329578D03*
X1666271Y461919D03*
X174923Y543562D03*
X632009D03*
X1546183Y543564D03*
X385091Y1299153D03*
X454385Y1303545D03*
X940997Y333613D03*
X256705Y476124D03*
X264005Y483210D03*
X605779Y478199D03*
X595377Y485260D03*
X331395Y476118D03*
X320993Y483179D03*
X670067Y485254D03*
X662767Y478168D03*
X1127153Y485254D03*
X1119853Y478168D03*
X1062865Y478199D03*
X1052463Y485260D03*
X1702655Y476118D03*
X1692253Y483179D03*
X1635265Y483210D03*
X1627965Y476124D03*
X76005Y127096D03*
Y112923D03*
X86407Y120035D03*
Y134209D03*
X178367Y127096D03*
Y112923D03*
X188769Y134209D03*
Y120035D03*
X264005Y469037D03*
X291131Y134209D03*
Y120035D03*
X280729Y127096D03*
Y112923D03*
X320993Y469005D03*
X393493Y134209D03*
X383091Y127096D03*
X393493Y120035D03*
X383091Y112923D03*
X485475Y134215D03*
Y120042D03*
X492775Y127128D03*
Y112955D03*
X587837Y134215D03*
Y120042D03*
X597777Y399813D03*
X595137Y127128D03*
Y112955D03*
X595377Y471087D03*
Y442333D03*
Y428160D03*
Y413987D03*
X605779Y435221D03*
Y421047D03*
Y406874D03*
Y392701D03*
X670067Y435215D03*
X662767Y442302D03*
Y428128D03*
Y413955D03*
X670067Y421041D03*
X662767Y399782D03*
X670067Y406868D03*
Y392695D03*
Y471081D03*
X690199Y120042D03*
X697499Y127128D03*
X690199Y134215D03*
X697499Y112955D03*
X799861D03*
Y127128D03*
X792561Y120042D03*
Y134215D03*
X949861Y112955D03*
X942561Y120042D03*
Y134215D03*
X949861Y127128D03*
X1044923Y134215D03*
X1052223Y127128D03*
X1044923Y120042D03*
X1052223Y112955D03*
X1052463Y471087D03*
Y442333D03*
Y428160D03*
Y413987D03*
X1054863Y399813D03*
X1062865Y435221D03*
Y421047D03*
Y406874D03*
Y392701D03*
X1119853Y399782D03*
Y442302D03*
Y428128D03*
Y413955D03*
X1154585Y112955D03*
X1127153Y471081D03*
Y435215D03*
Y421041D03*
Y406868D03*
Y392695D03*
X1154585Y127128D03*
X1147285Y134215D03*
Y120042D03*
X1249647Y134215D03*
Y120042D03*
X1256947Y127128D03*
Y112955D03*
X1447265Y127096D03*
Y112923D03*
X1457667Y134209D03*
Y120035D03*
X1560029Y134209D03*
X1549627Y127096D03*
X1560029Y120035D03*
X1549627Y112923D03*
X1651989Y127096D03*
Y112923D03*
X1635265Y469037D03*
X1662391Y134209D03*
Y120035D03*
X1692253Y469006D03*
X1754351Y127096D03*
Y112923D03*
X1764753Y134209D03*
Y120035D03*
X264005Y513171D03*
X256705Y520258D03*
Y490297D03*
Y612817D03*
X264005Y591557D03*
Y605730D03*
X256705Y598644D03*
X264005Y577384D03*
X256705Y584471D03*
Y570297D03*
X264005Y563210D03*
X256705Y534431D03*
X264005Y527344D03*
X320993Y513139D03*
Y591525D03*
Y605699D03*
Y577352D03*
Y563179D03*
Y527313D03*
X331395Y490291D03*
Y612811D03*
Y598638D03*
Y584465D03*
Y570291D03*
Y534425D03*
Y520252D03*
X595377Y529394D03*
Y515221D03*
X605779Y536506D03*
Y522333D03*
Y492373D03*
X670067Y529388D03*
X662767Y536475D03*
Y522302D03*
X670067Y515215D03*
X662767Y492341D03*
X1052463Y529394D03*
Y515221D03*
X1062865Y536506D03*
Y522333D03*
Y492373D03*
X1119853Y536475D03*
Y522302D03*
Y492341D03*
X1127153Y529388D03*
Y515215D03*
X1627965Y584471D03*
Y570297D03*
Y534431D03*
Y520258D03*
Y490297D03*
Y612817D03*
Y598644D03*
X1635265Y527344D03*
Y513171D03*
Y605730D03*
Y591557D03*
Y577384D03*
Y563210D03*
X1692253Y605699D03*
Y591525D03*
Y577352D03*
Y563179D03*
Y527313D03*
Y513139D03*
X1702655Y534425D03*
Y520252D03*
Y490291D03*
Y612811D03*
Y598638D03*
Y584465D03*
Y570291D03*
G54D77*
X770472Y1490945D03*
X820079Y388583D03*
X1020866D03*
X1070472Y1490945D03*
G54D65*
X19685Y-83298D03*
X1821260D03*
X26789Y1373669D03*
X1796847Y1517889D03*
X1809883Y120792D03*
X184851Y334492D03*
X19685Y1801195D03*
X1821260D03*
G54D75*
X1030905Y1066535D03*
Y1263386D03*
X810038Y1066535D03*
Y1263386D03*
X573818Y1066535D03*
Y1263386D03*
X352952Y1066535D03*
Y1263386D03*
X116731Y1066535D03*
Y1263386D03*
X1724212Y1066535D03*
Y1263386D03*
X1487991Y1066535D03*
Y1263386D03*
X1267125Y1066535D03*
Y1263386D03*
%LPC*%
G75*
G36*
G01X145878Y1228543D02*
G02I-800J0D01*
G37*
G36*
G01X149618D02*
G02I-800J0D01*
G37*
G36*
G01Y1239763D02*
G02I-800J0D01*
G37*
G36*
G01X145878D02*
G02I-800J0D01*
G37*
G36*
G01X164579Y1187401D02*
G02I-800J0D01*
G37*
G36*
G01Y1194881D02*
G02I-800J0D01*
G37*
G36*
G01Y1202362D02*
G02I-800J0D01*
G37*
G36*
G01Y1209842D02*
G02I-800J0D01*
G37*
G36*
G01Y1217322D02*
G02I-800J0D01*
G37*
G36*
G01X160839Y1236023D02*
G02I-800J0D01*
G37*
G36*
G01X164579Y1224803D02*
G02I-800J0D01*
G37*
G36*
G01X157099D02*
G02I-800J0D01*
G37*
G36*
G01Y1228543D02*
G02I-800J0D01*
G37*
G36*
G01X164579D02*
G02I-800J0D01*
G37*
G36*
G01X160839Y1232283D02*
G02I-800J0D01*
G37*
G36*
G01X153359Y1236023D02*
G02I-800J0D01*
G37*
G36*
G01Y1232283D02*
G02I-800J0D01*
G37*
G36*
G01X175799Y1075196D02*
G02I-800J0D01*
G37*
G36*
G01Y1078936D02*
G02I-800J0D01*
G37*
G36*
G01X179540Y1082677D02*
G02I-800J0D01*
G37*
G36*
G01Y1086417D02*
G02I-800J0D01*
G37*
G36*
G01X175799Y1093897D02*
G02I-800J0D01*
G37*
G36*
G01Y1097637D02*
G02I-800J0D01*
G37*
G36*
G01X179540Y1101376D02*
G02I-800J0D01*
G37*
G36*
G01Y1105117D02*
G02I-800J0D01*
G37*
G36*
G01X168319Y1187401D02*
G02I-800J0D01*
G37*
G36*
G01X175799Y1198621D02*
G02I-800J0D01*
G37*
G36*
G01Y1191141D02*
G02I-800J0D01*
G37*
G36*
G01X168319Y1194881D02*
G02I-800J0D01*
G37*
G36*
G01X172059Y1198621D02*
G02I-800J0D01*
G37*
G36*
G01Y1191141D02*
G02I-800J0D01*
G37*
G36*
G01X168319Y1202362D02*
G02I-800J0D01*
G37*
G36*
G01Y1209842D02*
G02I-800J0D01*
G37*
G36*
G01X172059Y1213582D02*
G02I-800J0D01*
G37*
G36*
G01Y1206102D02*
G02I-800J0D01*
G37*
G36*
G01X175799D02*
G02I-800J0D01*
G37*
G36*
G01X168319Y1217322D02*
G02I-800J0D01*
G37*
G36*
G01X175799Y1213582D02*
G02I-800J0D01*
G37*
G36*
G01X179540Y1228543D02*
G02I-800J0D01*
G37*
G36*
G01X172059Y1224803D02*
G02I-800J0D01*
G37*
G36*
G01X175799Y1232283D02*
G02I-800J0D01*
G37*
G36*
G01X172059Y1228543D02*
G02I-800J0D01*
G37*
G36*
G01X179540Y1224803D02*
G02I-800J0D01*
G37*
G36*
G01X175799Y1236023D02*
G02I-800J0D01*
G37*
G36*
G01X168319Y1232283D02*
G02I-800J0D01*
G37*
G36*
G01Y1236023D02*
G02I-800J0D01*
G37*
G36*
G01X190760Y1075196D02*
G02I-800J0D01*
G37*
G36*
G01X183280D02*
G02I-800J0D01*
G37*
G36*
G01X198240D02*
G02I-800J0D01*
G37*
G36*
G01X187020Y1082677D02*
G02I-800J0D01*
G37*
G36*
G01Y1086417D02*
G02I-800J0D01*
G37*
G36*
G01X183280Y1078936D02*
G02I-800J0D01*
G37*
G36*
G01X190760D02*
G02I-800J0D01*
G37*
G36*
G01X194500Y1086417D02*
G02I-800J0D01*
G37*
G36*
G01Y1082677D02*
G02I-800J0D01*
G37*
G36*
G01X198240Y1078936D02*
G02I-800J0D01*
G37*
G36*
G01X194500Y1105117D02*
G02I-800J0D01*
G37*
G36*
G01X198240Y1093897D02*
G02I-800J0D01*
G37*
G36*
G01X190760Y1097637D02*
G02I-800J0D01*
G37*
G36*
G01X187020Y1105117D02*
G02I-800J0D01*
G37*
G36*
G01X198240Y1097637D02*
G02I-800J0D01*
G37*
G36*
G01X183280Y1093897D02*
G02I-800J0D01*
G37*
G36*
G01Y1097637D02*
G02I-800J0D01*
G37*
G36*
G01X194500Y1101376D02*
G02I-800J0D01*
G37*
G36*
G01X187020D02*
G02I-800J0D01*
G37*
G36*
G01X190760Y1093897D02*
G02I-800J0D01*
G37*
G36*
G01X183280Y1236023D02*
G02I-800J0D01*
G37*
G36*
G01X198240D02*
G02I-800J0D01*
G37*
G36*
G01X187020Y1224803D02*
G02I-800J0D01*
G37*
G36*
G01X183280Y1232283D02*
G02I-800J0D01*
G37*
G36*
G01X194500Y1228543D02*
G02I-800J0D01*
G37*
G36*
G01X198240Y1232283D02*
G02I-800J0D01*
G37*
G36*
G01X190760Y1236023D02*
G02I-800J0D01*
G37*
G36*
G01X187020Y1228543D02*
G02I-800J0D01*
G37*
G36*
G01X194500Y1224803D02*
G02I-800J0D01*
G37*
G36*
G01X190760Y1232283D02*
G02I-800J0D01*
G37*
G36*
G01X205721Y1075196D02*
G02I-800J0D01*
G37*
G36*
G01X213201D02*
G02I-800J0D01*
G37*
G36*
G01Y1078936D02*
G02I-800J0D01*
G37*
G36*
G01X209461Y1082677D02*
G02I-800J0D01*
G37*
G36*
G01X201981D02*
G02I-800J0D01*
G37*
G36*
G01Y1086417D02*
G02I-800J0D01*
G37*
G36*
G01X209461D02*
G02I-800J0D01*
G37*
G36*
G01X205721Y1078936D02*
G02I-800J0D01*
G37*
G36*
G01Y1097637D02*
G02I-800J0D01*
G37*
G36*
G01X209461Y1101376D02*
G02I-800J0D01*
G37*
G36*
G01X213201Y1097637D02*
G02I-800J0D01*
G37*
G36*
G01X209461Y1105117D02*
G02I-800J0D01*
G37*
G36*
G01X213201Y1093897D02*
G02I-800J0D01*
G37*
G36*
G01X201981Y1101376D02*
G02I-800J0D01*
G37*
G36*
G01X205721Y1093897D02*
G02I-800J0D01*
G37*
G36*
G01X201981Y1105117D02*
G02I-800J0D01*
G37*
G36*
G01X205721Y1232283D02*
G02I-800J0D01*
G37*
G36*
G01X201981Y1224803D02*
G02I-800J0D01*
G37*
G36*
G01X213201Y1232283D02*
G02I-800J0D01*
G37*
G36*
G01X209461Y1228543D02*
G02I-800J0D01*
G37*
G36*
G01X213201Y1236023D02*
G02I-800J0D01*
G37*
G36*
G01X209461Y1224803D02*
G02I-800J0D01*
G37*
G36*
G01X201981Y1228543D02*
G02I-800J0D01*
G37*
G36*
G01X205721Y1236023D02*
G02I-800J0D01*
G37*
G36*
G01X209461Y1243503D02*
G02I-800J0D01*
G37*
G36*
G01X205721Y1250984D02*
G02I-800J0D01*
G37*
G36*
G01X209461Y1247243D02*
G02I-800J0D01*
G37*
G36*
G01X201981Y1243503D02*
G02I-800J0D01*
G37*
G36*
G01X213201Y1250984D02*
G02I-800J0D01*
G37*
G36*
G01X201981Y1247243D02*
G02I-800J0D01*
G37*
G36*
G01X213201Y1254724D02*
G02I-800J0D01*
G37*
G36*
G01X205721D02*
G02I-800J0D01*
G37*
G36*
G01X228162Y1075196D02*
G02I-800J0D01*
G37*
G36*
G01X220681D02*
G02I-800J0D01*
G37*
G36*
G01Y1078936D02*
G02I-800J0D01*
G37*
G36*
G01X216941Y1086417D02*
G02I-800J0D01*
G37*
G36*
G01X224422Y1082677D02*
G02I-800J0D01*
G37*
G36*
G01X228162Y1078936D02*
G02I-800J0D01*
G37*
G36*
G01X216941Y1082677D02*
G02I-800J0D01*
G37*
G36*
G01X224422Y1086417D02*
G02I-800J0D01*
G37*
G36*
G01X216941Y1101376D02*
G02I-800J0D01*
G37*
G36*
G01X228162Y1093897D02*
G02I-800J0D01*
G37*
G36*
G01X220681Y1097637D02*
G02I-800J0D01*
G37*
G36*
G01X224421Y1101376D02*
G02I-800J0D01*
G37*
G36*
G01Y1105117D02*
G02I-800J0D01*
G37*
G36*
G01X216941D02*
G02I-800J0D01*
G37*
G36*
G01X220681Y1093897D02*
G02I-800J0D01*
G37*
G36*
G01X228162Y1097637D02*
G02I-800J0D01*
G37*
G36*
G01X220681Y1232283D02*
G02I-800J0D01*
G37*
G36*
G01Y1236023D02*
G02I-800J0D01*
G37*
G36*
G01X216941Y1224803D02*
G02I-800J0D01*
G37*
G36*
G01X224422D02*
G02I-800J0D01*
G37*
G36*
G01X228162Y1232283D02*
G02I-800J0D01*
G37*
G36*
G01X224422Y1228543D02*
G02I-800J0D01*
G37*
G36*
G01X216941D02*
G02I-800J0D01*
G37*
G36*
G01X228162Y1236023D02*
G02I-800J0D01*
G37*
G36*
G01X224422Y1243503D02*
G02I-800J0D01*
G37*
G36*
G01X216941Y1247243D02*
G02I-800J0D01*
G37*
G36*
G01X224422D02*
G02I-800J0D01*
G37*
G36*
G01X216941Y1243503D02*
G02I-800J0D01*
G37*
G36*
G01X220681Y1250984D02*
G02I-800J0D01*
G37*
G36*
G01X228162D02*
G02I-800J0D01*
G37*
G36*
G01X220681Y1254724D02*
G02I-800J0D01*
G37*
G36*
G01X228162D02*
G02I-800J0D01*
G37*
G36*
G01X231902Y1082677D02*
G02I-800J0D01*
G37*
G36*
G01Y1086417D02*
G02I-800J0D01*
G37*
G36*
G01Y1101376D02*
G02I-800J0D01*
G37*
G36*
G01X235641Y1093897D02*
G02I-800J0D01*
G37*
G36*
G01X246862Y1105117D02*
G02I-800J0D01*
G37*
G36*
G01X243121Y1097637D02*
G02I-800J0D01*
G37*
G36*
G01X235641D02*
G02I-800J0D01*
G37*
G36*
G01X239382Y1101376D02*
G02I-800J0D01*
G37*
G36*
G01X246862D02*
G02I-800J0D01*
G37*
G36*
G01X239382Y1105117D02*
G02I-800J0D01*
G37*
G36*
G01X243121Y1093897D02*
G02I-800J0D01*
G37*
G36*
G01X231902Y1105117D02*
G02I-800J0D01*
G37*
G36*
G01X239382Y1224803D02*
G02I-800J0D01*
G37*
G36*
G01Y1228543D02*
G02I-800J0D01*
G37*
G36*
G01X231902D02*
G02I-800J0D01*
G37*
G36*
G01X243122Y1236023D02*
G02I-800J0D01*
G37*
G36*
G01X231902Y1224803D02*
G02I-800J0D01*
G37*
G36*
G01X243122Y1232283D02*
G02I-800J0D01*
G37*
G36*
G01X246862Y1228543D02*
G02I-800J0D01*
G37*
G36*
G01X235642Y1232283D02*
G02I-800J0D01*
G37*
G36*
G01X246862Y1224803D02*
G02I-800J0D01*
G37*
G36*
G01X235642Y1236023D02*
G02I-800J0D01*
G37*
G36*
G01X239382Y1247243D02*
G02I-800J0D01*
G37*
G36*
G01X246862Y1243503D02*
G02I-800J0D01*
G37*
G36*
G01X231902D02*
G02I-800J0D01*
G37*
G36*
G01X243122Y1250984D02*
G02I-800J0D01*
G37*
G36*
G01X235642D02*
G02I-800J0D01*
G37*
G36*
G01X246862Y1247243D02*
G02I-800J0D01*
G37*
G36*
G01X239382Y1243503D02*
G02I-800J0D01*
G37*
G36*
G01X231902Y1247243D02*
G02I-800J0D01*
G37*
G36*
G01X235642Y1254724D02*
G02I-800J0D01*
G37*
G36*
G01X243122D02*
G02I-800J0D01*
G37*
G36*
G01X250602Y1097637D02*
G02I-800J0D01*
G37*
G36*
G01X258082D02*
G02I-800J0D01*
G37*
G36*
G01X250602Y1093897D02*
G02I-800J0D01*
G37*
G36*
G01X254343Y1105117D02*
G02I-800J0D01*
G37*
G36*
G01Y1101376D02*
G02I-800J0D01*
G37*
G36*
G01X258082Y1093897D02*
G02I-800J0D01*
G37*
G36*
G01X261823Y1105117D02*
G02I-800J0D01*
G37*
G36*
G01Y1101376D02*
G02I-800J0D01*
G37*
G36*
G01Y1224803D02*
G02I-800J0D01*
G37*
G36*
G01X254343Y1228543D02*
G02I-800J0D01*
G37*
G36*
G01X250603Y1232283D02*
G02I-800J0D01*
G37*
G36*
G01X258083D02*
G02I-800J0D01*
G37*
G36*
G01Y1236023D02*
G02I-800J0D01*
G37*
G36*
G01X261823Y1228543D02*
G02I-800J0D01*
G37*
G36*
G01X254343Y1224803D02*
G02I-800J0D01*
G37*
G36*
G01X250603Y1236023D02*
G02I-800J0D01*
G37*
G36*
G01Y1250984D02*
G02I-800J0D01*
G37*
G36*
G01X258083D02*
G02I-800J0D01*
G37*
G36*
G01X254343Y1247243D02*
G02I-800J0D01*
G37*
G36*
G01Y1243503D02*
G02I-800J0D01*
G37*
G36*
G01X258083Y1254724D02*
G02I-800J0D01*
G37*
G36*
G01X250603D02*
G02I-800J0D01*
G37*
G36*
G01X265562Y1097637D02*
G02I-800J0D01*
G37*
G36*
G01X269303Y1105117D02*
G02I-800J0D01*
G37*
G36*
G01X273043Y1097637D02*
G02I-800J0D01*
G37*
G36*
G01X276784Y1105117D02*
G02I-800J0D01*
G37*
G36*
G01X280523Y1093897D02*
G02I-800J0D01*
G37*
G36*
G01X273043D02*
G02I-800J0D01*
G37*
G36*
G01X280523Y1097637D02*
G02I-800J0D01*
G37*
G36*
G01X269303Y1101376D02*
G02I-800J0D01*
G37*
G36*
G01X276784D02*
G02I-800J0D01*
G37*
G36*
G01X265562Y1093897D02*
G02I-800J0D01*
G37*
G36*
G01X265563Y1232283D02*
G02I-800J0D01*
G37*
G36*
G01X269303Y1224803D02*
G02I-800J0D01*
G37*
G36*
G01X276784D02*
G02I-800J0D01*
G37*
G36*
G01X273044Y1236023D02*
G02I-800J0D01*
G37*
G36*
G01X280524Y1232283D02*
G02I-800J0D01*
G37*
G36*
G01Y1236023D02*
G02I-800J0D01*
G37*
G36*
G01X276784Y1228543D02*
G02I-800J0D01*
G37*
G36*
G01X273044Y1232283D02*
G02I-800J0D01*
G37*
G36*
G01X269303Y1228543D02*
G02I-800J0D01*
G37*
G36*
G01X265563Y1236023D02*
G02I-800J0D01*
G37*
G36*
G01X284264Y1101376D02*
G02I-800J0D01*
G37*
G36*
G01X295484Y1093897D02*
G02I-800J0D01*
G37*
G36*
G01X288003D02*
G02I-800J0D01*
G37*
G36*
G01X295484Y1097637D02*
G02I-800J0D01*
G37*
G36*
G01X284264Y1105117D02*
G02I-800J0D01*
G37*
G36*
G01X291744Y1101376D02*
G02I-800J0D01*
G37*
G36*
G01Y1105117D02*
G02I-800J0D01*
G37*
G36*
G01X288003Y1097637D02*
G02I-800J0D01*
G37*
G36*
G01X295484Y1123818D02*
G02I-800J0D01*
G37*
G36*
G01Y1116338D02*
G02I-800J0D01*
G37*
G36*
G01Y1131299D02*
G02I-800J0D01*
G37*
G36*
G01X295485Y1198621D02*
G02I-800J0D01*
G37*
G36*
G01Y1213582D02*
G02I-800J0D01*
G37*
G36*
G01Y1206102D02*
G02I-800J0D01*
G37*
G36*
G01X288004Y1232283D02*
G02I-800J0D01*
G37*
G36*
G01X284264Y1224803D02*
G02I-800J0D01*
G37*
G36*
G01Y1228543D02*
G02I-800J0D01*
G37*
G36*
G01X288004Y1236023D02*
G02I-800J0D01*
G37*
G36*
G01X295485D02*
G02I-800J0D01*
G37*
G36*
G01X291744Y1224803D02*
G02I-800J0D01*
G37*
G36*
G01X295485Y1232283D02*
G02I-800J0D01*
G37*
G36*
G01X291744Y1228543D02*
G02I-800J0D01*
G37*
G36*
G01X295485Y1250984D02*
G02I-800J0D01*
G37*
G36*
G01X291744Y1247243D02*
G02I-800J0D01*
G37*
G36*
G01Y1243503D02*
G02I-800J0D01*
G37*
G36*
G01X295485Y1254724D02*
G02I-800J0D01*
G37*
G36*
G01X299225Y1105117D02*
G02I-800J0D01*
G37*
G36*
G01Y1101376D02*
G02I-800J0D01*
G37*
G36*
G01X310444Y1097637D02*
G02I-800J0D01*
G37*
G36*
G01X302964D02*
G02I-800J0D01*
G37*
G36*
G01X306705Y1105117D02*
G02I-800J0D01*
G37*
G36*
G01X310444Y1093897D02*
G02I-800J0D01*
G37*
G36*
G01X306705Y1101376D02*
G02I-800J0D01*
G37*
G36*
G01X302964Y1093897D02*
G02I-800J0D01*
G37*
G36*
G01X302965Y1120078D02*
G02I-800J0D01*
G37*
G36*
G01X306705Y1112598D02*
G02I-800J0D01*
G37*
G36*
G01X299225Y1116338D02*
G02I-800J0D01*
G37*
G36*
G01X306705Y1120078D02*
G02I-800J0D01*
G37*
G36*
G01X302965Y1112598D02*
G02I-800J0D01*
G37*
G36*
G01X299225Y1123818D02*
G02I-800J0D01*
G37*
G36*
G01X306705Y1127559D02*
G02I-800J0D01*
G37*
G36*
G01Y1135039D02*
G02I-800J0D01*
G37*
G36*
G01X302965D02*
G02I-800J0D01*
G37*
G36*
G01Y1127559D02*
G02I-800J0D01*
G37*
G36*
G01X299225Y1131299D02*
G02I-800J0D01*
G37*
G36*
G01Y1198621D02*
G02I-800J0D01*
G37*
G36*
G01X306705Y1202362D02*
G02I-800J0D01*
G37*
G36*
G01X302965D02*
G02I-800J0D01*
G37*
G36*
G01X299225Y1213582D02*
G02I-800J0D01*
G37*
G36*
G01X306705Y1209842D02*
G02I-800J0D01*
G37*
G36*
G01Y1217322D02*
G02I-800J0D01*
G37*
G36*
G01X302965Y1209842D02*
G02I-800J0D01*
G37*
G36*
G01X299225Y1206102D02*
G02I-800J0D01*
G37*
G36*
G01X302965Y1217322D02*
G02I-800J0D01*
G37*
G36*
G01Y1232283D02*
G02I-800J0D01*
G37*
G36*
G01X310445D02*
G02I-800J0D01*
G37*
G36*
G01X299225Y1224803D02*
G02I-800J0D01*
G37*
G36*
G01Y1228543D02*
G02I-800J0D01*
G37*
G36*
G01X310445Y1236023D02*
G02I-800J0D01*
G37*
G36*
G01X306705Y1228543D02*
G02I-800J0D01*
G37*
G36*
G01Y1224803D02*
G02I-800J0D01*
G37*
G36*
G01X302965Y1236023D02*
G02I-800J0D01*
G37*
G36*
G01X299225Y1247243D02*
G02I-800J0D01*
G37*
G36*
G01X310445Y1250984D02*
G02I-800J0D01*
G37*
G36*
G01X299225Y1243503D02*
G02I-800J0D01*
G37*
G36*
G01X306705D02*
G02I-800J0D01*
G37*
G36*
G01Y1247243D02*
G02I-800J0D01*
G37*
G36*
G01X302965Y1250984D02*
G02I-800J0D01*
G37*
G36*
G01X310445Y1254724D02*
G02I-800J0D01*
G37*
G36*
G01X302965D02*
G02I-800J0D01*
G37*
G36*
G01X321666Y1090157D02*
G02I-800J0D01*
G37*
G36*
G01X325406D02*
G02I-800J0D01*
G37*
G36*
G01X314185Y1101377D02*
G02I-800J0D01*
G37*
G36*
G01X317925Y1093897D02*
G02I-800J0D01*
G37*
G36*
G01X321666Y1101377D02*
G02I-800J0D01*
G37*
G36*
G01X314185Y1105117D02*
G02I-800J0D01*
G37*
G36*
G01X325406Y1101377D02*
G02I-800J0D01*
G37*
G36*
G01X317925Y1097637D02*
G02I-800J0D01*
G37*
G36*
G01X321666Y1198621D02*
G02I-800J0D01*
G37*
G36*
G01X314185Y1202362D02*
G02I-800J0D01*
G37*
G36*
G01X325406Y1198621D02*
G02I-800J0D01*
G37*
G36*
G01X317925Y1202362D02*
G02I-800J0D01*
G37*
G36*
G01Y1217322D02*
G02I-800J0D01*
G37*
G36*
G01Y1209842D02*
G02I-800J0D01*
G37*
G36*
G01X325406Y1213582D02*
G02I-800J0D01*
G37*
G36*
G01X321666Y1221062D02*
G02I-800J0D01*
G37*
G36*
G01X314185Y1209842D02*
G02I-800J0D01*
G37*
G36*
G01X321666Y1206102D02*
G02I-800J0D01*
G37*
G36*
G01Y1213582D02*
G02I-800J0D01*
G37*
G36*
G01X325406Y1221062D02*
G02I-800J0D01*
G37*
G36*
G01Y1206102D02*
G02I-800J0D01*
G37*
G36*
G01X314185Y1217322D02*
G02I-800J0D01*
G37*
G36*
G01X317925Y1236023D02*
G02I-800J0D01*
G37*
G36*
G01X314185Y1224803D02*
G02I-800J0D01*
G37*
G36*
G01X325406Y1228543D02*
G02I-800J0D01*
G37*
G36*
G01X317925Y1232283D02*
G02I-800J0D01*
G37*
G36*
G01X314185Y1228543D02*
G02I-800J0D01*
G37*
G36*
G01X321666D02*
G02I-800J0D01*
G37*
G36*
G01X325406Y1239763D02*
G02I-800J0D01*
G37*
G36*
G01X314185Y1247243D02*
G02I-800J0D01*
G37*
G36*
G01X321666D02*
G02I-800J0D01*
G37*
G36*
G01X317925Y1250984D02*
G02I-800J0D01*
G37*
G36*
G01X321666Y1239763D02*
G02I-800J0D01*
G37*
G36*
G01X314185Y1243503D02*
G02I-800J0D01*
G37*
G36*
G01X325406Y1247243D02*
G02I-800J0D01*
G37*
G36*
G01X317925Y1254724D02*
G02I-800J0D01*
G37*
G36*
G01X602965Y1191141D02*
G02I-800J0D01*
G37*
G36*
G01Y1198621D02*
G02I-800J0D01*
G37*
G36*
G01Y1221062D02*
G02I-800J0D01*
G37*
G36*
G01Y1206102D02*
G02I-800J0D01*
G37*
G36*
G01Y1213582D02*
G02I-800J0D01*
G37*
G36*
G01Y1228543D02*
G02I-800J0D01*
G37*
G36*
G01Y1247243D02*
G02I-800J0D01*
G37*
G36*
G01Y1239763D02*
G02I-800J0D01*
G37*
G36*
G01X614186Y1187401D02*
G02I-800J0D01*
G37*
G36*
G01X610446D02*
G02I-800J0D01*
G37*
G36*
G01X621666D02*
G02I-800J0D01*
G37*
G36*
G01X606705Y1191141D02*
G02I-800J0D01*
G37*
G36*
G01X614186Y1194881D02*
G02I-800J0D01*
G37*
G36*
G01X606705Y1198621D02*
G02I-800J0D01*
G37*
G36*
G01X610446Y1194881D02*
G02I-800J0D01*
G37*
G36*
G01Y1202362D02*
G02I-800J0D01*
G37*
G36*
G01X614186D02*
G02I-800J0D01*
G37*
G36*
G01X621666D02*
G02I-800J0D01*
G37*
G36*
G01Y1194881D02*
G02I-800J0D01*
G37*
G36*
G01X614186Y1217322D02*
G02I-800J0D01*
G37*
G36*
G01X606705Y1221062D02*
G02I-800J0D01*
G37*
G36*
G01X610446Y1217322D02*
G02I-800J0D01*
G37*
G36*
G01Y1209842D02*
G02I-800J0D01*
G37*
G36*
G01X606705Y1206102D02*
G02I-800J0D01*
G37*
G36*
G01Y1213582D02*
G02I-800J0D01*
G37*
G36*
G01X621666Y1209842D02*
G02I-800J0D01*
G37*
G36*
G01X614186D02*
G02I-800J0D01*
G37*
G36*
G01X621666Y1217322D02*
G02I-800J0D01*
G37*
G36*
G01X606705Y1228543D02*
G02I-800J0D01*
G37*
G36*
G01X621666D02*
G02I-800J0D01*
G37*
G36*
G01Y1224803D02*
G02I-800J0D01*
G37*
G36*
G01X610446Y1232283D02*
G02I-800J0D01*
G37*
G36*
G01X617926Y1236023D02*
G02I-800J0D01*
G37*
G36*
G01X614186Y1228543D02*
G02I-800J0D01*
G37*
G36*
G01X617926Y1232283D02*
G02I-800J0D01*
G37*
G36*
G01X610446Y1236023D02*
G02I-800J0D01*
G37*
G36*
G01X614186Y1224803D02*
G02I-800J0D01*
G37*
G36*
G01X606705Y1247243D02*
G02I-800J0D01*
G37*
G36*
G01X617926Y1250984D02*
G02I-800J0D01*
G37*
G36*
G01X621666Y1243503D02*
G02I-800J0D01*
G37*
G36*
G01Y1247243D02*
G02I-800J0D01*
G37*
G36*
G01X614186D02*
G02I-800J0D01*
G37*
G36*
G01Y1243503D02*
G02I-800J0D01*
G37*
G36*
G01X610446Y1250984D02*
G02I-800J0D01*
G37*
G36*
G01X606705Y1239763D02*
G02I-800J0D01*
G37*
G36*
G01X610446Y1254724D02*
G02I-800J0D01*
G37*
G36*
G01X617926D02*
G02I-800J0D01*
G37*
G36*
G01X632886Y1075196D02*
G02I-800J0D01*
G37*
G36*
G01Y1078936D02*
G02I-800J0D01*
G37*
G36*
G01X636627Y1086417D02*
G02I-800J0D01*
G37*
G36*
G01Y1082677D02*
G02I-800J0D01*
G37*
G36*
G01X632886Y1097637D02*
G02I-800J0D01*
G37*
G36*
G01X636627Y1105117D02*
G02I-800J0D01*
G37*
G36*
G01X632886Y1093897D02*
G02I-800J0D01*
G37*
G36*
G01X636627Y1101376D02*
G02I-800J0D01*
G37*
G36*
G01X625406Y1187401D02*
G02I-800J0D01*
G37*
G36*
G01X629146Y1191141D02*
G02I-800J0D01*
G37*
G36*
G01X625406Y1194881D02*
G02I-800J0D01*
G37*
G36*
G01X632886Y1191141D02*
G02I-800J0D01*
G37*
G36*
G01X629146Y1198621D02*
G02I-800J0D01*
G37*
G36*
G01X625406Y1202362D02*
G02I-800J0D01*
G37*
G36*
G01X632886Y1198621D02*
G02I-800J0D01*
G37*
G36*
G01X629146Y1206102D02*
G02I-800J0D01*
G37*
G36*
G01X632886D02*
G02I-800J0D01*
G37*
G36*
G01X625406Y1217322D02*
G02I-800J0D01*
G37*
G36*
G01X629146Y1213582D02*
G02I-800J0D01*
G37*
G36*
G01X632886D02*
G02I-800J0D01*
G37*
G36*
G01X625406Y1209842D02*
G02I-800J0D01*
G37*
G36*
G01X629146Y1224803D02*
G02I-800J0D01*
G37*
G36*
G01Y1228543D02*
G02I-800J0D01*
G37*
G36*
G01X636627D02*
G02I-800J0D01*
G37*
G36*
G01X632886Y1232283D02*
G02I-800J0D01*
G37*
G36*
G01Y1236023D02*
G02I-800J0D01*
G37*
G36*
G01X625406Y1232283D02*
G02I-800J0D01*
G37*
G36*
G01Y1236023D02*
G02I-800J0D01*
G37*
G36*
G01X636627Y1224803D02*
G02I-800J0D01*
G37*
G36*
G01X625406Y1250984D02*
G02I-800J0D01*
G37*
G36*
G01X636627Y1243503D02*
G02I-800J0D01*
G37*
G36*
G01X632886Y1250984D02*
G02I-800J0D01*
G37*
G36*
G01X636627Y1247243D02*
G02I-800J0D01*
G37*
G36*
G01X629146Y1243503D02*
G02I-800J0D01*
G37*
G36*
G01Y1247243D02*
G02I-800J0D01*
G37*
G36*
G01X625406Y1254724D02*
G02I-800J0D01*
G37*
G36*
G01X632886D02*
G02I-800J0D01*
G37*
G36*
G01X640367Y1075196D02*
G02I-800J0D01*
G37*
G36*
G01X647847D02*
G02I-800J0D01*
G37*
G36*
G01X644107Y1086417D02*
G02I-800J0D01*
G37*
G36*
G01Y1082677D02*
G02I-800J0D01*
G37*
G36*
G01X647847Y1078936D02*
G02I-800J0D01*
G37*
G36*
G01X640367D02*
G02I-800J0D01*
G37*
G36*
G01X651587Y1082677D02*
G02I-800J0D01*
G37*
G36*
G01Y1086417D02*
G02I-800J0D01*
G37*
G36*
G01Y1105117D02*
G02I-800J0D01*
G37*
G36*
G01X647847Y1093897D02*
G02I-800J0D01*
G37*
G36*
G01X640367Y1097637D02*
G02I-800J0D01*
G37*
G36*
G01X644107Y1105117D02*
G02I-800J0D01*
G37*
G36*
G01X647847Y1097637D02*
G02I-800J0D01*
G37*
G36*
G01X640367Y1093897D02*
G02I-800J0D01*
G37*
G36*
G01X644107Y1101376D02*
G02I-800J0D01*
G37*
G36*
G01X651587D02*
G02I-800J0D01*
G37*
G36*
G01X640367Y1236023D02*
G02I-800J0D01*
G37*
G36*
G01X647847D02*
G02I-800J0D01*
G37*
G36*
G01X640367Y1232283D02*
G02I-800J0D01*
G37*
G36*
G01X644107Y1224803D02*
G02I-800J0D01*
G37*
G36*
G01X647847Y1232283D02*
G02I-800J0D01*
G37*
G36*
G01X644107Y1228543D02*
G02I-800J0D01*
G37*
G36*
G01X651587D02*
G02I-800J0D01*
G37*
G36*
G01Y1224803D02*
G02I-800J0D01*
G37*
G36*
G01X640367Y1250984D02*
G02I-800J0D01*
G37*
G36*
G01X651587Y1247243D02*
G02I-800J0D01*
G37*
G36*
G01Y1243503D02*
G02I-800J0D01*
G37*
G36*
G01X647847Y1250984D02*
G02I-800J0D01*
G37*
G36*
G01X644107Y1247243D02*
G02I-800J0D01*
G37*
G36*
G01Y1243503D02*
G02I-800J0D01*
G37*
G36*
G01X640367Y1254724D02*
G02I-800J0D01*
G37*
G36*
G01X647847D02*
G02I-800J0D01*
G37*
G36*
G01X662808Y1075196D02*
G02I-800J0D01*
G37*
G36*
G01X655327D02*
G02I-800J0D01*
G37*
G36*
G01X670288D02*
G02I-800J0D01*
G37*
G36*
G01X662808Y1078936D02*
G02I-800J0D01*
G37*
G36*
G01X666548Y1082677D02*
G02I-800J0D01*
G37*
G36*
G01X659068D02*
G02I-800J0D01*
G37*
G36*
G01X655327Y1078936D02*
G02I-800J0D01*
G37*
G36*
G01X666548Y1086417D02*
G02I-800J0D01*
G37*
G36*
G01X659068D02*
G02I-800J0D01*
G37*
G36*
G01X670288Y1078936D02*
G02I-800J0D01*
G37*
G36*
G01X662808Y1097637D02*
G02I-800J0D01*
G37*
G36*
G01X655327Y1093897D02*
G02I-800J0D01*
G37*
G36*
G01X670288D02*
G02I-800J0D01*
G37*
G36*
G01X666548Y1105117D02*
G02I-800J0D01*
G37*
G36*
G01X655327Y1097637D02*
G02I-800J0D01*
G37*
G36*
G01X662808Y1093897D02*
G02I-800J0D01*
G37*
G36*
G01X670288Y1097637D02*
G02I-800J0D01*
G37*
G36*
G01X666548Y1101376D02*
G02I-800J0D01*
G37*
G36*
G01X659068Y1105117D02*
G02I-800J0D01*
G37*
G36*
G01Y1101376D02*
G02I-800J0D01*
G37*
G36*
G01X670288Y1232283D02*
G02I-800J0D01*
G37*
G36*
G01X655327Y1236023D02*
G02I-800J0D01*
G37*
G36*
G01X662808Y1232283D02*
G02I-800J0D01*
G37*
G36*
G01X666548Y1224803D02*
G02I-800J0D01*
G37*
G36*
G01X662808Y1236023D02*
G02I-800J0D01*
G37*
G36*
G01X659068Y1224803D02*
G02I-800J0D01*
G37*
G36*
G01X666548Y1228543D02*
G02I-800J0D01*
G37*
G36*
G01X659068D02*
G02I-800J0D01*
G37*
G36*
G01X670288Y1236023D02*
G02I-800J0D01*
G37*
G36*
G01X655327Y1232283D02*
G02I-800J0D01*
G37*
G36*
G01Y1250984D02*
G02I-800J0D01*
G37*
G36*
G01Y1254724D02*
G02I-800J0D01*
G37*
G36*
G01X677768Y1075196D02*
G02I-800J0D01*
G37*
G36*
G01X685249D02*
G02I-800J0D01*
G37*
G36*
G01X677768Y1078936D02*
G02I-800J0D01*
G37*
G36*
G01X681509Y1086417D02*
G02I-800J0D01*
G37*
G36*
G01X685249Y1078936D02*
G02I-800J0D01*
G37*
G36*
G01X674028Y1086417D02*
G02I-800J0D01*
G37*
G36*
G01Y1082677D02*
G02I-800J0D01*
G37*
G36*
G01X681509D02*
G02I-800J0D01*
G37*
G36*
G01X674028Y1105117D02*
G02I-800J0D01*
G37*
G36*
G01X685249Y1093897D02*
G02I-800J0D01*
G37*
G36*
G01X677768D02*
G02I-800J0D01*
G37*
G36*
G01X685249Y1097637D02*
G02I-800J0D01*
G37*
G36*
G01X677768D02*
G02I-800J0D01*
G37*
G36*
G01X681508Y1105117D02*
G02I-800J0D01*
G37*
G36*
G01X674028Y1101376D02*
G02I-800J0D01*
G37*
G36*
G01X681508D02*
G02I-800J0D01*
G37*
G36*
G01X677768Y1236023D02*
G02I-800J0D01*
G37*
G36*
G01X685249Y1232283D02*
G02I-800J0D01*
G37*
G36*
G01X674028Y1228543D02*
G02I-800J0D01*
G37*
G36*
G01X681509Y1224803D02*
G02I-800J0D01*
G37*
G36*
G01X685249Y1236023D02*
G02I-800J0D01*
G37*
G36*
G01X677768Y1232283D02*
G02I-800J0D01*
G37*
G36*
G01X674028Y1224803D02*
G02I-800J0D01*
G37*
G36*
G01X681509Y1228543D02*
G02I-800J0D01*
G37*
G36*
G01X688989Y1086417D02*
G02I-800J0D01*
G37*
G36*
G01Y1082677D02*
G02I-800J0D01*
G37*
G36*
G01Y1105117D02*
G02I-800J0D01*
G37*
G36*
G01X696469Y1101376D02*
G02I-800J0D01*
G37*
G36*
G01X700208Y1097637D02*
G02I-800J0D01*
G37*
G36*
G01X696469Y1105117D02*
G02I-800J0D01*
G37*
G36*
G01X692728Y1093897D02*
G02I-800J0D01*
G37*
G36*
G01Y1097637D02*
G02I-800J0D01*
G37*
G36*
G01X700208Y1093897D02*
G02I-800J0D01*
G37*
G36*
G01X688989Y1101376D02*
G02I-800J0D01*
G37*
G36*
G01Y1228543D02*
G02I-800J0D01*
G37*
G36*
G01X692729Y1236023D02*
G02I-800J0D01*
G37*
G36*
G01X700209Y1232283D02*
G02I-800J0D01*
G37*
G36*
G01X688989Y1224803D02*
G02I-800J0D01*
G37*
G36*
G01X700209Y1236023D02*
G02I-800J0D01*
G37*
G36*
G01X692729Y1232283D02*
G02I-800J0D01*
G37*
G36*
G01X696469Y1228543D02*
G02I-800J0D01*
G37*
G36*
G01Y1224803D02*
G02I-800J0D01*
G37*
G36*
G01X715169Y1097637D02*
G02I-800J0D01*
G37*
G36*
G01X707689Y1093897D02*
G02I-800J0D01*
G37*
G36*
G01X703949Y1105117D02*
G02I-800J0D01*
G37*
G36*
G01X718910D02*
G02I-800J0D01*
G37*
G36*
G01Y1101376D02*
G02I-800J0D01*
G37*
G36*
G01X711430Y1105117D02*
G02I-800J0D01*
G37*
G36*
G01X715169Y1093897D02*
G02I-800J0D01*
G37*
G36*
G01X707689Y1097637D02*
G02I-800J0D01*
G37*
G36*
G01X703949Y1101376D02*
G02I-800J0D01*
G37*
G36*
G01X711430D02*
G02I-800J0D01*
G37*
G36*
G01X707690Y1236023D02*
G02I-800J0D01*
G37*
G36*
G01X718910Y1228543D02*
G02I-800J0D01*
G37*
G36*
G01X715170Y1236023D02*
G02I-800J0D01*
G37*
G36*
G01X711430Y1228543D02*
G02I-800J0D01*
G37*
G36*
G01X703949D02*
G02I-800J0D01*
G37*
G36*
G01X715170Y1232283D02*
G02I-800J0D01*
G37*
G36*
G01X703949Y1224803D02*
G02I-800J0D01*
G37*
G36*
G01X718910D02*
G02I-800J0D01*
G37*
G36*
G01X711430D02*
G02I-800J0D01*
G37*
G36*
G01X707690Y1232283D02*
G02I-800J0D01*
G37*
G36*
G01X718910Y1243503D02*
G02I-800J0D01*
G37*
G36*
G01Y1247243D02*
G02I-800J0D01*
G37*
G36*
G01X726390Y1101376D02*
G02I-800J0D01*
G37*
G36*
G01X733871Y1105117D02*
G02I-800J0D01*
G37*
G36*
G01X726390D02*
G02I-800J0D01*
G37*
G36*
G01X722649Y1097637D02*
G02I-800J0D01*
G37*
G36*
G01Y1093897D02*
G02I-800J0D01*
G37*
G36*
G01X730130Y1097637D02*
G02I-800J0D01*
G37*
G36*
G01X733871Y1101376D02*
G02I-800J0D01*
G37*
G36*
G01X730130Y1093897D02*
G02I-800J0D01*
G37*
G36*
G01X726390Y1228543D02*
G02I-800J0D01*
G37*
G36*
G01X733871D02*
G02I-800J0D01*
G37*
G36*
G01X722650Y1236023D02*
G02I-800J0D01*
G37*
G36*
G01X733871Y1224803D02*
G02I-800J0D01*
G37*
G36*
G01X722650Y1232283D02*
G02I-800J0D01*
G37*
G36*
G01X726390Y1224803D02*
G02I-800J0D01*
G37*
G36*
G01X730131Y1236023D02*
G02I-800J0D01*
G37*
G36*
G01Y1232283D02*
G02I-800J0D01*
G37*
G36*
G01Y1250984D02*
G02I-800J0D01*
G37*
G36*
G01X733871Y1247243D02*
G02I-800J0D01*
G37*
G36*
G01X722650Y1250984D02*
G02I-800J0D01*
G37*
G36*
G01X726390Y1243503D02*
G02I-800J0D01*
G37*
G36*
G01X733871D02*
G02I-800J0D01*
G37*
G36*
G01X726390Y1247243D02*
G02I-800J0D01*
G37*
G36*
G01X722650Y1254724D02*
G02I-800J0D01*
G37*
G36*
G01X730131D02*
G02I-800J0D01*
G37*
G36*
G01X737610Y1097637D02*
G02I-800J0D01*
G37*
G36*
G01X748831Y1105117D02*
G02I-800J0D01*
G37*
G36*
G01X745090Y1093897D02*
G02I-800J0D01*
G37*
G36*
G01X741351Y1105117D02*
G02I-800J0D01*
G37*
G36*
G01X745090Y1097637D02*
G02I-800J0D01*
G37*
G36*
G01X737610Y1093897D02*
G02I-800J0D01*
G37*
G36*
G01X741351Y1101376D02*
G02I-800J0D01*
G37*
G36*
G01X748831D02*
G02I-800J0D01*
G37*
G36*
G01X745091Y1236023D02*
G02I-800J0D01*
G37*
G36*
G01X737611Y1232283D02*
G02I-800J0D01*
G37*
G36*
G01X745091D02*
G02I-800J0D01*
G37*
G36*
G01X737611Y1236023D02*
G02I-800J0D01*
G37*
G36*
G01X741351Y1224803D02*
G02I-800J0D01*
G37*
G36*
G01Y1228543D02*
G02I-800J0D01*
G37*
G36*
G01X748831Y1224803D02*
G02I-800J0D01*
G37*
G36*
G01Y1228543D02*
G02I-800J0D01*
G37*
G36*
G01X741351Y1243503D02*
G02I-800J0D01*
G37*
G36*
G01Y1247243D02*
G02I-800J0D01*
G37*
G36*
G01X745091Y1250984D02*
G02I-800J0D01*
G37*
G36*
G01X737611D02*
G02I-800J0D01*
G37*
G36*
G01X745091Y1254724D02*
G02I-800J0D01*
G37*
G36*
G01X737611D02*
G02I-800J0D01*
G37*
G36*
G01X752571Y1097637D02*
G02I-800J0D01*
G37*
G36*
G01X763792Y1101376D02*
G02I-800J0D01*
G37*
G36*
G01Y1105117D02*
G02I-800J0D01*
G37*
G36*
G01X756312D02*
G02I-800J0D01*
G37*
G36*
G01X760051Y1097637D02*
G02I-800J0D01*
G37*
G36*
G01Y1093897D02*
G02I-800J0D01*
G37*
G36*
G01X767531Y1097637D02*
G02I-800J0D01*
G37*
G36*
G01X756312Y1101376D02*
G02I-800J0D01*
G37*
G36*
G01X767531Y1093897D02*
G02I-800J0D01*
G37*
G36*
G01X752571D02*
G02I-800J0D01*
G37*
G36*
G01X756312Y1123818D02*
G02I-800J0D01*
G37*
G36*
G01X760052Y1112598D02*
G02I-800J0D01*
G37*
G36*
G01X752571Y1123818D02*
G02I-800J0D01*
G37*
G36*
G01X763792Y1112598D02*
G02I-800J0D01*
G37*
G36*
G01X756312Y1116338D02*
G02I-800J0D01*
G37*
G36*
G01X752571D02*
G02I-800J0D01*
G37*
G36*
G01X760052Y1120078D02*
G02I-800J0D01*
G37*
G36*
G01X763792D02*
G02I-800J0D01*
G37*
G36*
G01X752571Y1131299D02*
G02I-800J0D01*
G37*
G36*
G01X763792Y1135039D02*
G02I-800J0D01*
G37*
G36*
G01X756312Y1131299D02*
G02I-800J0D01*
G37*
G36*
G01X763792Y1127559D02*
G02I-800J0D01*
G37*
G36*
G01X760052Y1135039D02*
G02I-800J0D01*
G37*
G36*
G01Y1127559D02*
G02I-800J0D01*
G37*
G36*
G01X763792Y1202362D02*
G02I-800J0D01*
G37*
G36*
G01X756312Y1198621D02*
G02I-800J0D01*
G37*
G36*
G01X760052Y1202362D02*
G02I-800J0D01*
G37*
G36*
G01X752572Y1198621D02*
G02I-800J0D01*
G37*
G36*
G01X763792Y1217322D02*
G02I-800J0D01*
G37*
G36*
G01X752572Y1213582D02*
G02I-800J0D01*
G37*
G36*
G01X763792Y1209842D02*
G02I-800J0D01*
G37*
G36*
G01X756312Y1213582D02*
G02I-800J0D01*
G37*
G36*
G01X752572Y1206102D02*
G02I-800J0D01*
G37*
G36*
G01X760052Y1217322D02*
G02I-800J0D01*
G37*
G36*
G01Y1209842D02*
G02I-800J0D01*
G37*
G36*
G01X756312Y1206102D02*
G02I-800J0D01*
G37*
G36*
G01Y1228543D02*
G02I-800J0D01*
G37*
G36*
G01X752572Y1236023D02*
G02I-800J0D01*
G37*
G36*
G01X763792Y1228543D02*
G02I-800J0D01*
G37*
G36*
G01X752572Y1232283D02*
G02I-800J0D01*
G37*
G36*
G01X767532D02*
G02I-800J0D01*
G37*
G36*
G01Y1236023D02*
G02I-800J0D01*
G37*
G36*
G01X760052Y1232283D02*
G02I-800J0D01*
G37*
G36*
G01X763792Y1224803D02*
G02I-800J0D01*
G37*
G36*
G01X760052Y1236023D02*
G02I-800J0D01*
G37*
G36*
G01X756312Y1224803D02*
G02I-800J0D01*
G37*
G36*
G01X782493Y1090157D02*
G02I-800J0D01*
G37*
G36*
G01X778753D02*
G02I-800J0D01*
G37*
G36*
G01X771272Y1101377D02*
G02I-800J0D01*
G37*
G36*
G01X782493D02*
G02I-800J0D01*
G37*
G36*
G01X778753D02*
G02I-800J0D01*
G37*
G36*
G01X775012Y1097637D02*
G02I-800J0D01*
G37*
G36*
G01X771272Y1105117D02*
G02I-800J0D01*
G37*
G36*
G01X775012Y1093897D02*
G02I-800J0D01*
G37*
G36*
G01X771272Y1228543D02*
G02I-800J0D01*
G37*
G36*
G01X782493D02*
G02I-800J0D01*
G37*
G36*
G01X771272Y1224803D02*
G02I-800J0D01*
G37*
G36*
G01X778753Y1228543D02*
G02I-800J0D01*
G37*
G36*
G01X775012Y1232283D02*
G02I-800J0D01*
G37*
G36*
G01Y1236023D02*
G02I-800J0D01*
G37*
G36*
G01X778753Y1239763D02*
G02I-800J0D01*
G37*
G36*
G01X782493D02*
G02I-800J0D01*
G37*
G36*
G01X940026Y1577634D02*
G03X940910Y1577268I884J885D01*
G01X956342D01*
G02X956484Y1577209I0J-200D01*
G01X959830Y1573863D01*
G02X959889Y1573721I-141J-142D01*
G01Y1543680D01*
G03X960255Y1542796I1251J0D01*
G01X964295Y1538756D01*
G03X965179Y1538390I884J885D01*
G01X1019906D01*
G02X1020048Y1538331I0J-200D01*
G01X1031515Y1526864D01*
G02X1031574Y1526722I-141J-142D01*
G01Y1492904D01*
G02X1031515Y1492762I-200J0D01*
G01X1031368Y1492615D01*
G02X1031226Y1492556I-142J141D01*
G01X947183D01*
G02X947041Y1492615I0J200D01*
G01X944876Y1494780D01*
G03X943992Y1495146I-884J-885D01*
G01X933579D01*
G03X932695Y1494780I0J-1251D01*
G01X917141Y1479226D01*
G03X916775Y1478342I885J-884D01*
G01Y1465020D01*
G02X916716Y1464878I-200J0D01*
G01X914188Y1462350D01*
G03X913822Y1461466I885J-884D01*
G01Y1460928D01*
G02X913763Y1460786I-200J0D01*
G01X913527Y1460550D01*
G03X913161Y1459666I885J-884D01*
G01Y1446448D01*
G02X913102Y1446306I-200J0D01*
G01X912955Y1446159D01*
G02X912813Y1446100I-142J141D01*
G01X900559D01*
G02X900417Y1446159I0J200D01*
G01X900270Y1446306D01*
G02X900211Y1446448I141J142D01*
G01Y1459640D01*
G03X899845Y1460524I-1251J0D01*
G01X899532Y1460837D01*
G02X899473Y1460979I141J142D01*
G01Y1462024D01*
G03X899107Y1462908I-1251J0D01*
G01X894403Y1467612D01*
G02X894344Y1467754I141J142D01*
G01Y1473096D01*
G03X893978Y1473980I-1251J0D01*
G01X888953Y1479005D01*
G03X888069Y1479371I-884J-885D01*
G01X880504D01*
G03X879620Y1479005I0J-1251D01*
G01X872265Y1471650D01*
G03X871899Y1470766I885J-884D01*
G01Y1460991D01*
G02X871840Y1460849I-200J0D01*
G01X871502Y1460511D01*
G03X871136Y1459627I885J-884D01*
G01Y1446423D01*
G02X871077Y1446281I-200J0D01*
G01X870968Y1446172D01*
G02X870826Y1446113I-142J141D01*
G01X858702D01*
G02X858560Y1446172I0J200D01*
G01X858139Y1446593D01*
G02X858080Y1446735I141J142D01*
G01Y1459524D01*
G03X857714Y1460408I-1251J0D01*
G01X853660Y1464462D01*
G03X852776Y1464828I-884J-885D01*
G01X828441D01*
G03X827557Y1464462I0J-1251D01*
G01X827039Y1463944D01*
G03X826673Y1463060I885J-884D01*
G01Y1461847D01*
G02X826614Y1461705I-200J0D01*
G01X826571Y1461662D01*
G02X826429Y1461603I-142J141D01*
G01X825036D01*
G03X824152Y1461237I0J-1251D01*
G01X821533Y1458618D01*
G02X821391Y1458559I-142J141D01*
G01X820451D01*
G03X819567Y1458193I0J-1251D01*
G01X819360Y1457986D01*
G03X818994Y1457102I885J-884D01*
G01Y1446462D01*
G02X818935Y1446320I-200J0D01*
G01X818826Y1446211D01*
G02X818684Y1446152I-142J141D01*
G01X806393D01*
G02X806251Y1446211I0J200D01*
G01X806063Y1446399D01*
G02X806004Y1446541I141J142D01*
G01Y1459828D01*
G02X806063Y1459970I200J0D01*
G01X806195Y1460102D01*
G03X806561Y1460986I-885J884D01*
G01Y1474310D01*
G02X806615Y1474447I200J0D01*
G03X806950Y1475299I-916J852D01*
G01Y1523715D01*
G02X807009Y1523857I200J0D01*
G01X816830Y1533678D01*
G03X817196Y1534562I-885J884D01*
G01Y1620853D01*
G02X817255Y1620995I200J0D01*
G01X822528Y1626268D01*
G02X822670Y1626327I142J-141D01*
G01X927565D01*
G02X927707Y1626268I0J-200D01*
G01X932114Y1621861D01*
G02X932173Y1621719I-141J-142D01*
G01Y1586005D01*
G03X932539Y1585121I1251J0D01*
G01X940026Y1577634D01*
G37*
G36*
G01X953110Y1480583D02*
G03X953130Y1480563I894J874D01*
G02X953192Y1480419I-138J-145D01*
G01Y1451442D01*
G02X953133Y1451300I-200J0D01*
G01X952668Y1450835D01*
G02X952526Y1450776I-142J141D01*
G01X930592D01*
G02X930450Y1450835I0J200D01*
G01X929621Y1451664D01*
G02X929562Y1451806I141J142D01*
G01Y1480891D01*
G02X929621Y1481033I200J0D01*
G01X930418Y1481830D01*
G02X930560Y1481889I142J-141D01*
G01X951737D01*
G02X951894Y1481812I-1J-200D01*
G03X951995Y1481698I984J770D01*
G01X953110Y1480583D01*
G37*
G36*
G01X955751Y1485453D02*
X957168Y1486870D01*
G02X957310Y1486929I142J-141D01*
G01X1045732D01*
G02X1045874Y1486870I0J-200D01*
G01X1046659Y1486085D01*
G02X1046718Y1485943I-141J-142D01*
G01Y1452303D01*
G02X1046659Y1452161I-200J0D01*
G01X1045333Y1450835D01*
G02X1045191Y1450776I-142J141D01*
G01X956304D01*
G02X956162Y1450835I0J200D01*
G01X955751Y1451246D01*
G02X955692Y1451388I141J142D01*
G01Y1485311D01*
G02X955751Y1485453I200J0D01*
G37*
G36*
G01X1060051Y1228543D02*
G02I-800J0D01*
G37*
G36*
G01Y1239763D02*
G02I-800J0D01*
G37*
G36*
G01X1071272Y1228543D02*
G02I-800J0D01*
G37*
G36*
G01X1067532Y1236023D02*
G02I-800J0D01*
G37*
G36*
G01Y1232283D02*
G02I-800J0D01*
G37*
G36*
G01X1075012Y1236023D02*
G02I-800J0D01*
G37*
G36*
G01Y1232283D02*
G02I-800J0D01*
G37*
G36*
G01X1071272Y1224803D02*
G02I-800J0D01*
G37*
G36*
G01X1063791Y1228543D02*
G02I-800J0D01*
G37*
G36*
G01Y1239763D02*
G02I-800J0D01*
G37*
G36*
G01X1089972Y1075196D02*
G02I-800J0D01*
G37*
G36*
G01Y1078936D02*
G02I-800J0D01*
G37*
G36*
G01Y1097637D02*
G02I-800J0D01*
G37*
G36*
G01Y1093897D02*
G02I-800J0D01*
G37*
G36*
G01X1078752Y1187401D02*
G02I-800J0D01*
G37*
G36*
G01X1082492D02*
G02I-800J0D01*
G37*
G36*
G01X1078752Y1194881D02*
G02I-800J0D01*
G37*
G36*
G01Y1202362D02*
G02I-800J0D01*
G37*
G36*
G01X1089972Y1191141D02*
G02I-800J0D01*
G37*
G36*
G01Y1198621D02*
G02I-800J0D01*
G37*
G36*
G01X1082492Y1202362D02*
G02I-800J0D01*
G37*
G36*
G01X1086232Y1198621D02*
G02I-800J0D01*
G37*
G36*
G01X1082492Y1194881D02*
G02I-800J0D01*
G37*
G36*
G01X1086232Y1191141D02*
G02I-800J0D01*
G37*
G36*
G01X1089972Y1206102D02*
G02I-800J0D01*
G37*
G36*
G01X1078752Y1209842D02*
G02I-800J0D01*
G37*
G36*
G01X1082492D02*
G02I-800J0D01*
G37*
G36*
G01Y1217322D02*
G02I-800J0D01*
G37*
G36*
G01X1089972Y1213582D02*
G02I-800J0D01*
G37*
G36*
G01X1078752Y1217322D02*
G02I-800J0D01*
G37*
G36*
G01X1086232Y1206102D02*
G02I-800J0D01*
G37*
G36*
G01Y1213582D02*
G02I-800J0D01*
G37*
G36*
G01X1089972Y1232283D02*
G02I-800J0D01*
G37*
G36*
G01X1082492D02*
G02I-800J0D01*
G37*
G36*
G01Y1236023D02*
G02I-800J0D01*
G37*
G36*
G01X1089972D02*
G02I-800J0D01*
G37*
G36*
G01X1078752Y1224803D02*
G02I-800J0D01*
G37*
G36*
G01Y1228543D02*
G02I-800J0D01*
G37*
G36*
G01X1086232Y1224803D02*
G02I-800J0D01*
G37*
G36*
G01Y1228543D02*
G02I-800J0D01*
G37*
G36*
G01X1097453Y1075196D02*
G02I-800J0D01*
G37*
G36*
G01X1104933D02*
G02I-800J0D01*
G37*
G36*
G01X1101193Y1082677D02*
G02I-800J0D01*
G37*
G36*
G01X1104933Y1078936D02*
G02I-800J0D01*
G37*
G36*
G01X1108673Y1082677D02*
G02I-800J0D01*
G37*
G36*
G01Y1086417D02*
G02I-800J0D01*
G37*
G36*
G01X1093713Y1082677D02*
G02I-800J0D01*
G37*
G36*
G01X1101193Y1086417D02*
G02I-800J0D01*
G37*
G36*
G01X1093713D02*
G02I-800J0D01*
G37*
G36*
G01X1097453Y1078936D02*
G02I-800J0D01*
G37*
G36*
G01X1093713Y1105116D02*
G02I-800J0D01*
G37*
G36*
G01X1104933Y1097637D02*
G02I-800J0D01*
G37*
G36*
G01X1097453D02*
G02I-800J0D01*
G37*
G36*
G01X1101193Y1105116D02*
G02I-800J0D01*
G37*
G36*
G01X1104933Y1093897D02*
G02I-800J0D01*
G37*
G36*
G01X1101193Y1101376D02*
G02I-800J0D01*
G37*
G36*
G01X1097453Y1093897D02*
G02I-800J0D01*
G37*
G36*
G01X1093713Y1101376D02*
G02I-800J0D01*
G37*
G36*
G01X1108673Y1105116D02*
G02I-800J0D01*
G37*
G36*
G01Y1101376D02*
G02I-800J0D01*
G37*
G36*
G01X1101193Y1228543D02*
G02I-800J0D01*
G37*
G36*
G01X1104933Y1236023D02*
G02I-800J0D01*
G37*
G36*
G01X1093713Y1224803D02*
G02I-800J0D01*
G37*
G36*
G01X1104933Y1232283D02*
G02I-800J0D01*
G37*
G36*
G01X1108673Y1224803D02*
G02I-800J0D01*
G37*
G36*
G01X1097453Y1236023D02*
G02I-800J0D01*
G37*
G36*
G01X1101193Y1224803D02*
G02I-800J0D01*
G37*
G36*
G01X1108673Y1228543D02*
G02I-800J0D01*
G37*
G36*
G01X1097453Y1232283D02*
G02I-800J0D01*
G37*
G36*
G01X1093713Y1228543D02*
G02I-800J0D01*
G37*
G36*
G01X1112413Y1075196D02*
G02I-800J0D01*
G37*
G36*
G01X1119894D02*
G02I-800J0D01*
G37*
G36*
G01X1123634Y1086417D02*
G02I-800J0D01*
G37*
G36*
G01X1119894Y1078936D02*
G02I-800J0D01*
G37*
G36*
G01X1116154Y1082677D02*
G02I-800J0D01*
G37*
G36*
G01X1112413Y1078936D02*
G02I-800J0D01*
G37*
G36*
G01X1116154Y1086417D02*
G02I-800J0D01*
G37*
G36*
G01X1123634Y1082677D02*
G02I-800J0D01*
G37*
G36*
G01X1119894Y1097637D02*
G02I-800J0D01*
G37*
G36*
G01X1116154Y1101376D02*
G02I-800J0D01*
G37*
G36*
G01X1112413Y1093897D02*
G02I-800J0D01*
G37*
G36*
G01Y1097637D02*
G02I-800J0D01*
G37*
G36*
G01X1123634Y1105116D02*
G02I-800J0D01*
G37*
G36*
G01X1119894Y1093897D02*
G02I-800J0D01*
G37*
G36*
G01X1123634Y1101376D02*
G02I-800J0D01*
G37*
G36*
G01X1116154Y1105116D02*
G02I-800J0D01*
G37*
G36*
G01X1123634Y1224803D02*
G02I-800J0D01*
G37*
G36*
G01X1119894Y1232283D02*
G02I-800J0D01*
G37*
G36*
G01X1116154Y1228543D02*
G02I-800J0D01*
G37*
G36*
G01X1112413Y1232283D02*
G02I-800J0D01*
G37*
G36*
G01X1119894Y1236023D02*
G02I-800J0D01*
G37*
G36*
G01X1116154Y1224803D02*
G02I-800J0D01*
G37*
G36*
G01X1112413Y1236023D02*
G02I-800J0D01*
G37*
G36*
G01X1123634Y1228543D02*
G02I-800J0D01*
G37*
G36*
G01Y1243503D02*
G02I-800J0D01*
G37*
G36*
G01X1119894Y1250984D02*
G02I-800J0D01*
G37*
G36*
G01X1123634Y1247243D02*
G02I-800J0D01*
G37*
G36*
G01X1116154Y1243503D02*
G02I-800J0D01*
G37*
G36*
G01Y1247243D02*
G02I-800J0D01*
G37*
G36*
G01X1119894Y1254724D02*
G02I-800J0D01*
G37*
G36*
G01X1127374Y1075196D02*
G02I-800J0D01*
G37*
G36*
G01X1134854D02*
G02I-800J0D01*
G37*
G36*
G01Y1078936D02*
G02I-800J0D01*
G37*
G36*
G01X1127374D02*
G02I-800J0D01*
G37*
G36*
G01X1131114Y1086417D02*
G02I-800J0D01*
G37*
G36*
G01Y1082677D02*
G02I-800J0D01*
G37*
G36*
G01X1138595Y1086417D02*
G02I-800J0D01*
G37*
G36*
G01Y1082677D02*
G02I-800J0D01*
G37*
G36*
G01X1127374Y1093897D02*
G02I-800J0D01*
G37*
G36*
G01X1131114Y1105116D02*
G02I-800J0D01*
G37*
G36*
G01X1134854Y1093897D02*
G02I-800J0D01*
G37*
G36*
G01X1131114Y1101376D02*
G02I-800J0D01*
G37*
G36*
G01X1134854Y1097637D02*
G02I-800J0D01*
G37*
G36*
G01X1138594Y1105116D02*
G02I-800J0D01*
G37*
G36*
G01X1127374Y1097637D02*
G02I-800J0D01*
G37*
G36*
G01X1138594Y1101376D02*
G02I-800J0D01*
G37*
G36*
G01X1134854Y1236023D02*
G02I-800J0D01*
G37*
G36*
G01X1138595Y1228543D02*
G02I-800J0D01*
G37*
G36*
G01X1134854Y1232283D02*
G02I-800J0D01*
G37*
G36*
G01X1127374D02*
G02I-800J0D01*
G37*
G36*
G01Y1236023D02*
G02I-800J0D01*
G37*
G36*
G01X1138595Y1224803D02*
G02I-800J0D01*
G37*
G36*
G01X1131114Y1228543D02*
G02I-800J0D01*
G37*
G36*
G01Y1224803D02*
G02I-800J0D01*
G37*
G36*
G01X1138595Y1243503D02*
G02I-800J0D01*
G37*
G36*
G01X1131114Y1247243D02*
G02I-800J0D01*
G37*
G36*
G01X1127374Y1250984D02*
G02I-800J0D01*
G37*
G36*
G01X1138595Y1247243D02*
G02I-800J0D01*
G37*
G36*
G01X1131114Y1243503D02*
G02I-800J0D01*
G37*
G36*
G01X1134854Y1250984D02*
G02I-800J0D01*
G37*
G36*
G01X1127374Y1254724D02*
G02I-800J0D01*
G37*
G36*
G01X1134854D02*
G02I-800J0D01*
G37*
G36*
G01X1142335Y1075196D02*
G02I-800J0D01*
G37*
G36*
G01X1146075Y1086417D02*
G02I-800J0D01*
G37*
G36*
G01Y1082677D02*
G02I-800J0D01*
G37*
G36*
G01X1142335Y1078936D02*
G02I-800J0D01*
G37*
G36*
G01X1146075Y1105116D02*
G02I-800J0D01*
G37*
G36*
G01X1142335Y1093897D02*
G02I-800J0D01*
G37*
G36*
G01X1146075Y1101376D02*
G02I-800J0D01*
G37*
G36*
G01X1142335Y1097637D02*
G02I-800J0D01*
G37*
G36*
G01X1149814D02*
G02I-800J0D01*
G37*
G36*
G01X1157294Y1093897D02*
G02I-800J0D01*
G37*
G36*
G01X1153555Y1101376D02*
G02I-800J0D01*
G37*
G36*
G01X1157294Y1097637D02*
G02I-800J0D01*
G37*
G36*
G01X1149814Y1093897D02*
G02I-800J0D01*
G37*
G36*
G01X1153555Y1105116D02*
G02I-800J0D01*
G37*
G36*
G01X1149815Y1236023D02*
G02I-800J0D01*
G37*
G36*
G01Y1232283D02*
G02I-800J0D01*
G37*
G36*
G01X1153555Y1228543D02*
G02I-800J0D01*
G37*
G36*
G01X1146075Y1224803D02*
G02I-800J0D01*
G37*
G36*
G01X1157295Y1232283D02*
G02I-800J0D01*
G37*
G36*
G01Y1236023D02*
G02I-800J0D01*
G37*
G36*
G01X1142335D02*
G02I-800J0D01*
G37*
G36*
G01X1146075Y1228543D02*
G02I-800J0D01*
G37*
G36*
G01X1153555Y1224803D02*
G02I-800J0D01*
G37*
G36*
G01X1142335Y1232283D02*
G02I-800J0D01*
G37*
G36*
G01Y1250984D02*
G02I-800J0D01*
G37*
G36*
G01X1146075Y1247243D02*
G02I-800J0D01*
G37*
G36*
G01X1153555Y1243503D02*
G02I-800J0D01*
G37*
G36*
G01X1146075D02*
G02I-800J0D01*
G37*
G36*
G01X1153555Y1247243D02*
G02I-800J0D01*
G37*
G36*
G01X1149815Y1250984D02*
G02I-800J0D01*
G37*
G36*
G01X1157295D02*
G02I-800J0D01*
G37*
G36*
G01X1142335Y1254724D02*
G02I-800J0D01*
G37*
G36*
G01X1149815D02*
G02I-800J0D01*
G37*
G36*
G01X1157295D02*
G02I-800J0D01*
G37*
G36*
G01X1161035Y1105116D02*
G02I-800J0D01*
G37*
G36*
G01Y1101376D02*
G02I-800J0D01*
G37*
G36*
G01X1172255Y1093897D02*
G02I-800J0D01*
G37*
G36*
G01X1168516Y1105116D02*
G02I-800J0D01*
G37*
G36*
G01X1172255Y1097637D02*
G02I-800J0D01*
G37*
G36*
G01X1164775Y1093897D02*
G02I-800J0D01*
G37*
G36*
G01Y1097637D02*
G02I-800J0D01*
G37*
G36*
G01X1168516Y1101376D02*
G02I-800J0D01*
G37*
G36*
G01X1161035Y1224803D02*
G02I-800J0D01*
G37*
G36*
G01X1164776Y1232283D02*
G02I-800J0D01*
G37*
G36*
G01X1168516Y1224803D02*
G02I-800J0D01*
G37*
G36*
G01X1161035Y1228543D02*
G02I-800J0D01*
G37*
G36*
G01X1172256Y1232283D02*
G02I-800J0D01*
G37*
G36*
G01X1164776Y1236023D02*
G02I-800J0D01*
G37*
G36*
G01X1172256D02*
G02I-800J0D01*
G37*
G36*
G01X1168516Y1228543D02*
G02I-800J0D01*
G37*
G36*
G01X1172256Y1250984D02*
G02I-800J0D01*
G37*
G36*
G01X1168516Y1247243D02*
G02I-800J0D01*
G37*
G36*
G01X1164776Y1250984D02*
G02I-800J0D01*
G37*
G36*
G01X1161035Y1247243D02*
G02I-800J0D01*
G37*
G36*
G01Y1243503D02*
G02I-800J0D01*
G37*
G36*
G01X1168516D02*
G02I-800J0D01*
G37*
G36*
G01X1172256Y1254724D02*
G02I-800J0D01*
G37*
G36*
G01X1164776D02*
G02I-800J0D01*
G37*
G36*
G01X1179735Y1097637D02*
G02I-800J0D01*
G37*
G36*
G01X1187216Y1093897D02*
G02I-800J0D01*
G37*
G36*
G01X1183476Y1105116D02*
G02I-800J0D01*
G37*
G36*
G01X1175996D02*
G02I-800J0D01*
G37*
G36*
G01X1179735Y1093897D02*
G02I-800J0D01*
G37*
G36*
G01X1183476Y1101376D02*
G02I-800J0D01*
G37*
G36*
G01X1175996D02*
G02I-800J0D01*
G37*
G36*
G01X1187216Y1097637D02*
G02I-800J0D01*
G37*
G36*
G01X1183476Y1228543D02*
G02I-800J0D01*
G37*
G36*
G01X1187217Y1236023D02*
G02I-800J0D01*
G37*
G36*
G01X1179736D02*
G02I-800J0D01*
G37*
G36*
G01X1187217Y1232283D02*
G02I-800J0D01*
G37*
G36*
G01X1175996Y1228543D02*
G02I-800J0D01*
G37*
G36*
G01X1179736Y1232283D02*
G02I-800J0D01*
G37*
G36*
G01X1183476Y1224803D02*
G02I-800J0D01*
G37*
G36*
G01X1175996D02*
G02I-800J0D01*
G37*
G36*
G01X1202176Y1093897D02*
G02I-800J0D01*
G37*
G36*
G01X1194696Y1097637D02*
G02I-800J0D01*
G37*
G36*
G01X1198437Y1105116D02*
G02I-800J0D01*
G37*
G36*
G01X1205917D02*
G02I-800J0D01*
G37*
G36*
G01X1198437Y1101376D02*
G02I-800J0D01*
G37*
G36*
G01X1205917D02*
G02I-800J0D01*
G37*
G36*
G01X1190957D02*
G02I-800J0D01*
G37*
G36*
G01X1194696Y1093897D02*
G02I-800J0D01*
G37*
G36*
G01X1202176Y1097637D02*
G02I-800J0D01*
G37*
G36*
G01X1190957Y1105116D02*
G02I-800J0D01*
G37*
G36*
G01X1198437Y1224803D02*
G02I-800J0D01*
G37*
G36*
G01X1194697Y1236023D02*
G02I-800J0D01*
G37*
G36*
G01X1190957Y1228543D02*
G02I-800J0D01*
G37*
G36*
G01X1202177Y1236023D02*
G02I-800J0D01*
G37*
G36*
G01X1190957Y1224803D02*
G02I-800J0D01*
G37*
G36*
G01X1194697Y1232283D02*
G02I-800J0D01*
G37*
G36*
G01X1198437Y1228543D02*
G02I-800J0D01*
G37*
G36*
G01X1202177Y1232283D02*
G02I-800J0D01*
G37*
G36*
G01X1205917Y1228543D02*
G02I-800J0D01*
G37*
G36*
G01Y1224803D02*
G02I-800J0D01*
G37*
G36*
G01Y1243503D02*
G02I-800J0D01*
G37*
G36*
G01Y1247243D02*
G02I-800J0D01*
G37*
G36*
G01X1220878Y1105116D02*
G02I-800J0D01*
G37*
G36*
G01X1217137Y1093897D02*
G02I-800J0D01*
G37*
G36*
G01X1213398Y1101376D02*
G02I-800J0D01*
G37*
G36*
G01Y1105116D02*
G02I-800J0D01*
G37*
G36*
G01X1209657Y1093897D02*
G02I-800J0D01*
G37*
G36*
G01X1217137Y1097637D02*
G02I-800J0D01*
G37*
G36*
G01X1220878Y1101376D02*
G02I-800J0D01*
G37*
G36*
G01X1209657Y1097637D02*
G02I-800J0D01*
G37*
G36*
G01X1213398Y1123818D02*
G02I-800J0D01*
G37*
G36*
G01X1209658Y1116338D02*
G02I-800J0D01*
G37*
G36*
G01X1213398D02*
G02I-800J0D01*
G37*
G36*
G01X1217138Y1120078D02*
G02I-800J0D01*
G37*
G36*
G01Y1112598D02*
G02I-800J0D01*
G37*
G36*
G01X1209658Y1123818D02*
G02I-800J0D01*
G37*
G36*
G01X1220878Y1112598D02*
G02I-800J0D01*
G37*
G36*
G01Y1120078D02*
G02I-800J0D01*
G37*
G36*
G01X1217138Y1127559D02*
G02I-800J0D01*
G37*
G36*
G01Y1135039D02*
G02I-800J0D01*
G37*
G36*
G01X1213398Y1131299D02*
G02I-800J0D01*
G37*
G36*
G01X1209658D02*
G02I-800J0D01*
G37*
G36*
G01X1220878Y1135039D02*
G02I-800J0D01*
G37*
G36*
G01Y1127559D02*
G02I-800J0D01*
G37*
G36*
G01X1213398Y1198621D02*
G02I-800J0D01*
G37*
G36*
G01X1209658D02*
G02I-800J0D01*
G37*
G36*
G01X1217138Y1202362D02*
G02I-800J0D01*
G37*
G36*
G01X1220878D02*
G02I-800J0D01*
G37*
G36*
G01Y1217322D02*
G02I-800J0D01*
G37*
G36*
G01Y1209842D02*
G02I-800J0D01*
G37*
G36*
G01X1213398Y1206102D02*
G02I-800J0D01*
G37*
G36*
G01X1217138Y1217322D02*
G02I-800J0D01*
G37*
G36*
G01X1213398Y1213582D02*
G02I-800J0D01*
G37*
G36*
G01X1209658Y1206102D02*
G02I-800J0D01*
G37*
G36*
G01Y1213582D02*
G02I-800J0D01*
G37*
G36*
G01X1217138Y1209842D02*
G02I-800J0D01*
G37*
G36*
G01X1220878Y1224803D02*
G02I-800J0D01*
G37*
G36*
G01X1213398Y1228543D02*
G02I-800J0D01*
G37*
G36*
G01X1209658Y1232283D02*
G02I-800J0D01*
G37*
G36*
G01X1217138Y1236023D02*
G02I-800J0D01*
G37*
G36*
G01Y1232283D02*
G02I-800J0D01*
G37*
G36*
G01X1213398Y1224803D02*
G02I-800J0D01*
G37*
G36*
G01X1220878Y1228543D02*
G02I-800J0D01*
G37*
G36*
G01X1209658Y1236023D02*
G02I-800J0D01*
G37*
G36*
G01X1213398Y1243503D02*
G02I-800J0D01*
G37*
G36*
G01X1220878Y1247243D02*
G02I-800J0D01*
G37*
G36*
G01Y1243503D02*
G02I-800J0D01*
G37*
G36*
G01X1213398Y1247243D02*
G02I-800J0D01*
G37*
G36*
G01X1209658Y1250984D02*
G02I-800J0D01*
G37*
G36*
G01X1217138D02*
G02I-800J0D01*
G37*
G36*
G01X1209658Y1254724D02*
G02I-800J0D01*
G37*
G36*
G01X1217138D02*
G02I-800J0D01*
G37*
G36*
G01X1235839Y1090157D02*
G02I-800J0D01*
G37*
G36*
G01X1228358Y1101377D02*
G02I-800J0D01*
G37*
G36*
G01X1232098Y1093897D02*
G02I-800J0D01*
G37*
G36*
G01X1235839Y1101377D02*
G02I-800J0D01*
G37*
G36*
G01X1228358Y1105117D02*
G02I-800J0D01*
G37*
G36*
G01X1224617Y1093897D02*
G02I-800J0D01*
G37*
G36*
G01Y1097637D02*
G02I-800J0D01*
G37*
G36*
G01X1232098D02*
G02I-800J0D01*
G37*
G36*
G01Y1202362D02*
G02I-800J0D01*
G37*
G36*
G01X1235839Y1198621D02*
G02I-800J0D01*
G37*
G36*
G01X1228358Y1202362D02*
G02I-800J0D01*
G37*
G36*
G01X1235839Y1213582D02*
G02I-800J0D01*
G37*
G36*
G01X1232098Y1209842D02*
G02I-800J0D01*
G37*
G36*
G01X1228358D02*
G02I-800J0D01*
G37*
G36*
G01X1235839Y1221062D02*
G02I-800J0D01*
G37*
G36*
G01X1232098Y1217322D02*
G02I-800J0D01*
G37*
G36*
G01X1235839Y1206102D02*
G02I-800J0D01*
G37*
G36*
G01X1228358Y1217322D02*
G02I-800J0D01*
G37*
G36*
G01X1232098Y1232283D02*
G02I-800J0D01*
G37*
G36*
G01X1228358Y1228543D02*
G02I-800J0D01*
G37*
G36*
G01Y1224803D02*
G02I-800J0D01*
G37*
G36*
G01X1224618Y1236023D02*
G02I-800J0D01*
G37*
G36*
G01X1232098D02*
G02I-800J0D01*
G37*
G36*
G01X1235839Y1228543D02*
G02I-800J0D01*
G37*
G36*
G01X1224618Y1232283D02*
G02I-800J0D01*
G37*
G36*
G01X1228358Y1247243D02*
G02I-800J0D01*
G37*
G36*
G01X1224618Y1250984D02*
G02I-800J0D01*
G37*
G36*
G01X1235839Y1239763D02*
G02I-800J0D01*
G37*
G36*
G01X1228358Y1243503D02*
G02I-800J0D01*
G37*
G36*
G01X1232098Y1250984D02*
G02I-800J0D01*
G37*
G36*
G01X1235839Y1247243D02*
G02I-800J0D01*
G37*
G36*
G01X1232098Y1254724D02*
G02I-800J0D01*
G37*
G36*
G01X1224618D02*
G02I-800J0D01*
G37*
G36*
G01X1239579Y1090157D02*
G02I-800J0D01*
G37*
G36*
G01Y1101377D02*
G02I-800J0D01*
G37*
G36*
G01Y1198621D02*
G02I-800J0D01*
G37*
G36*
G01Y1221062D02*
G02I-800J0D01*
G37*
G36*
G01Y1206102D02*
G02I-800J0D01*
G37*
G36*
G01Y1213582D02*
G02I-800J0D01*
G37*
G36*
G01Y1228543D02*
G02I-800J0D01*
G37*
G36*
G01Y1247243D02*
G02I-800J0D01*
G37*
G36*
G01Y1239763D02*
G02I-800J0D01*
G37*
G36*
G01X1524619Y1187401D02*
G02I-800J0D01*
G37*
G36*
G01X1528359D02*
G02I-800J0D01*
G37*
G36*
G01X1517138Y1198621D02*
G02I-800J0D01*
G37*
G36*
G01X1524619Y1194881D02*
G02I-800J0D01*
G37*
G36*
G01X1520878Y1198621D02*
G02I-800J0D01*
G37*
G36*
G01X1524619Y1202362D02*
G02I-800J0D01*
G37*
G36*
G01X1517138Y1191141D02*
G02I-800J0D01*
G37*
G36*
G01X1528359Y1202362D02*
G02I-800J0D01*
G37*
G36*
G01Y1194881D02*
G02I-800J0D01*
G37*
G36*
G01X1520878Y1191141D02*
G02I-800J0D01*
G37*
G36*
G01Y1221062D02*
G02I-800J0D01*
G37*
G36*
G01X1517138Y1213582D02*
G02I-800J0D01*
G37*
G36*
G01Y1206102D02*
G02I-800J0D01*
G37*
G36*
G01X1520878D02*
G02I-800J0D01*
G37*
G36*
G01X1528359Y1217322D02*
G02I-800J0D01*
G37*
G36*
G01X1524619Y1209842D02*
G02I-800J0D01*
G37*
G36*
G01X1517138Y1221062D02*
G02I-800J0D01*
G37*
G36*
G01X1528359Y1209842D02*
G02I-800J0D01*
G37*
G36*
G01X1524619Y1217322D02*
G02I-800J0D01*
G37*
G36*
G01X1520878Y1213582D02*
G02I-800J0D01*
G37*
G36*
G01X1528359Y1228543D02*
G02I-800J0D01*
G37*
G36*
G01X1517138D02*
G02I-800J0D01*
G37*
G36*
G01X1524619Y1232283D02*
G02I-800J0D01*
G37*
G36*
G01X1520878Y1228543D02*
G02I-800J0D01*
G37*
G36*
G01X1524619Y1236023D02*
G02I-800J0D01*
G37*
G36*
G01X1528359Y1224803D02*
G02I-800J0D01*
G37*
G36*
G01X1517138Y1239763D02*
G02I-800J0D01*
G37*
G36*
G01X1520878D02*
G02I-800J0D01*
G37*
G36*
G01Y1247243D02*
G02I-800J0D01*
G37*
G36*
G01X1517138D02*
G02I-800J0D01*
G37*
G36*
G01X1528359Y1243503D02*
G02I-800J0D01*
G37*
G36*
G01Y1247243D02*
G02I-800J0D01*
G37*
G36*
G01X1524619Y1250984D02*
G02I-800J0D01*
G37*
G36*
G01Y1254724D02*
G02I-800J0D01*
G37*
G36*
G01X1547059Y1075196D02*
G02I-800J0D01*
G37*
G36*
G01Y1078936D02*
G02I-800J0D01*
G37*
G36*
G01Y1097637D02*
G02I-800J0D01*
G37*
G36*
G01Y1093897D02*
G02I-800J0D01*
G37*
G36*
G01X1535839Y1187401D02*
G02I-800J0D01*
G37*
G36*
G01X1539579D02*
G02I-800J0D01*
G37*
G36*
G01X1543319Y1191141D02*
G02I-800J0D01*
G37*
G36*
G01X1539579Y1202362D02*
G02I-800J0D01*
G37*
G36*
G01X1535839Y1194881D02*
G02I-800J0D01*
G37*
G36*
G01X1543319Y1198621D02*
G02I-800J0D01*
G37*
G36*
G01X1547059D02*
G02I-800J0D01*
G37*
G36*
G01Y1191141D02*
G02I-800J0D01*
G37*
G36*
G01X1535839Y1202362D02*
G02I-800J0D01*
G37*
G36*
G01X1539579Y1194881D02*
G02I-800J0D01*
G37*
G36*
G01X1543319Y1213582D02*
G02I-800J0D01*
G37*
G36*
G01Y1206102D02*
G02I-800J0D01*
G37*
G36*
G01X1547059Y1213582D02*
G02I-800J0D01*
G37*
G36*
G01X1535839Y1209842D02*
G02I-800J0D01*
G37*
G36*
G01Y1217322D02*
G02I-800J0D01*
G37*
G36*
G01X1547059Y1206102D02*
G02I-800J0D01*
G37*
G36*
G01X1539579Y1209842D02*
G02I-800J0D01*
G37*
G36*
G01Y1217322D02*
G02I-800J0D01*
G37*
G36*
G01X1547059Y1232283D02*
G02I-800J0D01*
G37*
G36*
G01X1535839Y1224803D02*
G02I-800J0D01*
G37*
G36*
G01X1539579Y1236023D02*
G02I-800J0D01*
G37*
G36*
G01X1532099Y1232283D02*
G02I-800J0D01*
G37*
G36*
G01X1543319Y1228543D02*
G02I-800J0D01*
G37*
G36*
G01X1535839D02*
G02I-800J0D01*
G37*
G36*
G01X1547059Y1236023D02*
G02I-800J0D01*
G37*
G36*
G01X1543319Y1224803D02*
G02I-800J0D01*
G37*
G36*
G01X1532099Y1236023D02*
G02I-800J0D01*
G37*
G36*
G01X1539579Y1232283D02*
G02I-800J0D01*
G37*
G36*
G01X1547059Y1250984D02*
G02I-800J0D01*
G37*
G36*
G01X1543319Y1243503D02*
G02I-800J0D01*
G37*
G36*
G01Y1247243D02*
G02I-800J0D01*
G37*
G36*
G01X1539579Y1250984D02*
G02I-800J0D01*
G37*
G36*
G01X1535839Y1243503D02*
G02I-800J0D01*
G37*
G36*
G01X1532099Y1250984D02*
G02I-800J0D01*
G37*
G36*
G01X1535839Y1247243D02*
G02I-800J0D01*
G37*
G36*
G01X1547059Y1254724D02*
G02I-800J0D01*
G37*
G36*
G01X1539579D02*
G02I-800J0D01*
G37*
G36*
G01X1532099D02*
G02I-800J0D01*
G37*
G36*
G01X1554540Y1075196D02*
G02I-800J0D01*
G37*
G36*
G01X1562020D02*
G02I-800J0D01*
G37*
G36*
G01X1558280Y1082677D02*
G02I-800J0D01*
G37*
G36*
G01X1554540Y1078936D02*
G02I-800J0D01*
G37*
G36*
G01X1562020D02*
G02I-800J0D01*
G37*
G36*
G01X1550800Y1086417D02*
G02I-800J0D01*
G37*
G36*
G01Y1082677D02*
G02I-800J0D01*
G37*
G36*
G01X1558280Y1086417D02*
G02I-800J0D01*
G37*
G36*
G01Y1101376D02*
G02I-800J0D01*
G37*
G36*
G01X1562020Y1093897D02*
G02I-800J0D01*
G37*
G36*
G01X1558280Y1105116D02*
G02I-800J0D01*
G37*
G36*
G01X1562020Y1097637D02*
G02I-800J0D01*
G37*
G36*
G01X1550800Y1101376D02*
G02I-800J0D01*
G37*
G36*
G01Y1105116D02*
G02I-800J0D01*
G37*
G36*
G01X1554540Y1093897D02*
G02I-800J0D01*
G37*
G36*
G01Y1097637D02*
G02I-800J0D01*
G37*
G36*
G01Y1232283D02*
G02I-800J0D01*
G37*
G36*
G01X1550800Y1228543D02*
G02I-800J0D01*
G37*
G36*
G01X1554540Y1236023D02*
G02I-800J0D01*
G37*
G36*
G01X1550800Y1224803D02*
G02I-800J0D01*
G37*
G36*
G01X1558280Y1228543D02*
G02I-800J0D01*
G37*
G36*
G01X1562020Y1236023D02*
G02I-800J0D01*
G37*
G36*
G01Y1232283D02*
G02I-800J0D01*
G37*
G36*
G01X1558280Y1224803D02*
G02I-800J0D01*
G37*
G36*
G01X1562020Y1250984D02*
G02I-800J0D01*
G37*
G36*
G01X1550800Y1243503D02*
G02I-800J0D01*
G37*
G36*
G01X1558280Y1247243D02*
G02I-800J0D01*
G37*
G36*
G01X1550800D02*
G02I-800J0D01*
G37*
G36*
G01X1558280Y1243503D02*
G02I-800J0D01*
G37*
G36*
G01X1554540Y1250984D02*
G02I-800J0D01*
G37*
G36*
G01X1562020Y1254724D02*
G02I-800J0D01*
G37*
G36*
G01X1554540D02*
G02I-800J0D01*
G37*
G36*
G01X1576981Y1075196D02*
G02I-800J0D01*
G37*
G36*
G01X1569500D02*
G02I-800J0D01*
G37*
G36*
G01Y1078936D02*
G02I-800J0D01*
G37*
G36*
G01X1573241Y1086417D02*
G02I-800J0D01*
G37*
G36*
G01X1565760Y1082677D02*
G02I-800J0D01*
G37*
G36*
G01Y1086417D02*
G02I-800J0D01*
G37*
G36*
G01X1573241Y1082677D02*
G02I-800J0D01*
G37*
G36*
G01X1576981Y1078936D02*
G02I-800J0D01*
G37*
G36*
G01X1565760Y1105116D02*
G02I-800J0D01*
G37*
G36*
G01X1576981Y1097637D02*
G02I-800J0D01*
G37*
G36*
G01X1569500D02*
G02I-800J0D01*
G37*
G36*
G01X1576981Y1093897D02*
G02I-800J0D01*
G37*
G36*
G01X1569500D02*
G02I-800J0D01*
G37*
G36*
G01X1573241Y1101376D02*
G02I-800J0D01*
G37*
G36*
G01Y1105116D02*
G02I-800J0D01*
G37*
G36*
G01X1565760Y1101376D02*
G02I-800J0D01*
G37*
G36*
G01X1573241Y1228543D02*
G02I-800J0D01*
G37*
G36*
G01X1569500Y1236023D02*
G02I-800J0D01*
G37*
G36*
G01X1565760Y1224803D02*
G02I-800J0D01*
G37*
G36*
G01X1576981Y1236023D02*
G02I-800J0D01*
G37*
G36*
G01X1573241Y1224803D02*
G02I-800J0D01*
G37*
G36*
G01X1565760Y1228543D02*
G02I-800J0D01*
G37*
G36*
G01X1576981Y1232283D02*
G02I-800J0D01*
G37*
G36*
G01X1569500D02*
G02I-800J0D01*
G37*
G36*
G01X1565760Y1243503D02*
G02I-800J0D01*
G37*
G36*
G01Y1247243D02*
G02I-800J0D01*
G37*
G36*
G01X1569500Y1250984D02*
G02I-800J0D01*
G37*
G36*
G01Y1254724D02*
G02I-800J0D01*
G37*
G36*
G01X1584461Y1075196D02*
G02I-800J0D01*
G37*
G36*
G01X1591941D02*
G02I-800J0D01*
G37*
G36*
G01X1595682Y1082677D02*
G02I-800J0D01*
G37*
G36*
G01X1580721D02*
G02I-800J0D01*
G37*
G36*
G01X1584461Y1078936D02*
G02I-800J0D01*
G37*
G36*
G01X1595682Y1086417D02*
G02I-800J0D01*
G37*
G36*
G01X1588201Y1082677D02*
G02I-800J0D01*
G37*
G36*
G01X1580721Y1086417D02*
G02I-800J0D01*
G37*
G36*
G01X1588201D02*
G02I-800J0D01*
G37*
G36*
G01X1591941Y1078936D02*
G02I-800J0D01*
G37*
G36*
G01X1595681Y1105116D02*
G02I-800J0D01*
G37*
G36*
G01X1591941Y1097637D02*
G02I-800J0D01*
G37*
G36*
G01X1584461Y1093897D02*
G02I-800J0D01*
G37*
G36*
G01X1595681Y1101376D02*
G02I-800J0D01*
G37*
G36*
G01X1584461Y1097637D02*
G02I-800J0D01*
G37*
G36*
G01X1588201Y1105116D02*
G02I-800J0D01*
G37*
G36*
G01X1580721Y1101376D02*
G02I-800J0D01*
G37*
G36*
G01X1591941Y1093897D02*
G02I-800J0D01*
G37*
G36*
G01X1588201Y1101376D02*
G02I-800J0D01*
G37*
G36*
G01X1580721Y1105116D02*
G02I-800J0D01*
G37*
G36*
G01X1595682Y1224803D02*
G02I-800J0D01*
G37*
G36*
G01X1591941Y1232283D02*
G02I-800J0D01*
G37*
G36*
G01X1584461Y1236023D02*
G02I-800J0D01*
G37*
G36*
G01X1580721Y1228543D02*
G02I-800J0D01*
G37*
G36*
G01X1584461Y1232283D02*
G02I-800J0D01*
G37*
G36*
G01X1595682Y1228543D02*
G02I-800J0D01*
G37*
G36*
G01X1580721Y1224803D02*
G02I-800J0D01*
G37*
G36*
G01X1588201Y1228543D02*
G02I-800J0D01*
G37*
G36*
G01Y1224803D02*
G02I-800J0D01*
G37*
G36*
G01X1591941Y1236023D02*
G02I-800J0D01*
G37*
G36*
G01X1599422Y1075196D02*
G02I-800J0D01*
G37*
G36*
G01X1603162Y1082677D02*
G02I-800J0D01*
G37*
G36*
G01Y1086417D02*
G02I-800J0D01*
G37*
G36*
G01X1599422Y1078936D02*
G02I-800J0D01*
G37*
G36*
G01X1606901Y1093897D02*
G02I-800J0D01*
G37*
G36*
G01X1603162Y1101376D02*
G02I-800J0D01*
G37*
G36*
G01X1599422Y1097637D02*
G02I-800J0D01*
G37*
G36*
G01Y1093897D02*
G02I-800J0D01*
G37*
G36*
G01X1603162Y1105116D02*
G02I-800J0D01*
G37*
G36*
G01X1610642Y1101376D02*
G02I-800J0D01*
G37*
G36*
G01Y1105116D02*
G02I-800J0D01*
G37*
G36*
G01X1606901Y1097637D02*
G02I-800J0D01*
G37*
G36*
G01X1599422Y1236023D02*
G02I-800J0D01*
G37*
G36*
G01X1606902D02*
G02I-800J0D01*
G37*
G36*
G01X1610642Y1228543D02*
G02I-800J0D01*
G37*
G36*
G01X1606902Y1232283D02*
G02I-800J0D01*
G37*
G36*
G01X1603162Y1224803D02*
G02I-800J0D01*
G37*
G36*
G01X1610642D02*
G02I-800J0D01*
G37*
G36*
G01X1603162Y1228543D02*
G02I-800J0D01*
G37*
G36*
G01X1599422Y1232283D02*
G02I-800J0D01*
G37*
G36*
G01X1621862Y1093897D02*
G02I-800J0D01*
G37*
G36*
G01X1618122Y1105116D02*
G02I-800J0D01*
G37*
G36*
G01Y1101376D02*
G02I-800J0D01*
G37*
G36*
G01X1614381Y1093897D02*
G02I-800J0D01*
G37*
G36*
G01Y1097637D02*
G02I-800J0D01*
G37*
G36*
G01X1625603Y1101376D02*
G02I-800J0D01*
G37*
G36*
G01Y1105116D02*
G02I-800J0D01*
G37*
G36*
G01X1621862Y1097637D02*
G02I-800J0D01*
G37*
G36*
G01X1618122Y1228543D02*
G02I-800J0D01*
G37*
G36*
G01X1625603Y1224803D02*
G02I-800J0D01*
G37*
G36*
G01X1618122D02*
G02I-800J0D01*
G37*
G36*
G01X1621863Y1236023D02*
G02I-800J0D01*
G37*
G36*
G01X1614382D02*
G02I-800J0D01*
G37*
G36*
G01X1621863Y1232283D02*
G02I-800J0D01*
G37*
G36*
G01X1625603Y1228543D02*
G02I-800J0D01*
G37*
G36*
G01X1614382Y1232283D02*
G02I-800J0D01*
G37*
G36*
G01X1640563Y1101376D02*
G02I-800J0D01*
G37*
G36*
G01X1629342Y1093897D02*
G02I-800J0D01*
G37*
G36*
G01X1636822D02*
G02I-800J0D01*
G37*
G36*
G01X1640563Y1105116D02*
G02I-800J0D01*
G37*
G36*
G01X1633083D02*
G02I-800J0D01*
G37*
G36*
G01Y1101376D02*
G02I-800J0D01*
G37*
G36*
G01X1636822Y1097637D02*
G02I-800J0D01*
G37*
G36*
G01X1644303D02*
G02I-800J0D01*
G37*
G36*
G01Y1093897D02*
G02I-800J0D01*
G37*
G36*
G01X1629342Y1097637D02*
G02I-800J0D01*
G37*
G36*
G01X1633083Y1228543D02*
G02I-800J0D01*
G37*
G36*
G01X1629343Y1236023D02*
G02I-800J0D01*
G37*
G36*
G01Y1232283D02*
G02I-800J0D01*
G37*
G36*
G01X1640563Y1224803D02*
G02I-800J0D01*
G37*
G36*
G01X1636823Y1236023D02*
G02I-800J0D01*
G37*
G36*
G01X1644304Y1232283D02*
G02I-800J0D01*
G37*
G36*
G01X1633083Y1224803D02*
G02I-800J0D01*
G37*
G36*
G01X1644304Y1236023D02*
G02I-800J0D01*
G37*
G36*
G01X1636823Y1232283D02*
G02I-800J0D01*
G37*
G36*
G01X1640563Y1228543D02*
G02I-800J0D01*
G37*
G36*
G01X1633083Y1243503D02*
G02I-800J0D01*
G37*
G36*
G01X1640563D02*
G02I-800J0D01*
G37*
G36*
G01X1636823Y1250984D02*
G02I-800J0D01*
G37*
G36*
G01X1633083Y1247243D02*
G02I-800J0D01*
G37*
G36*
G01X1644304Y1250984D02*
G02I-800J0D01*
G37*
G36*
G01X1640563Y1247243D02*
G02I-800J0D01*
G37*
G36*
G01X1636823Y1254724D02*
G02I-800J0D01*
G37*
G36*
G01X1644304D02*
G02I-800J0D01*
G37*
G36*
G01X1659263Y1097637D02*
G02I-800J0D01*
G37*
G36*
G01X1648044Y1101376D02*
G02I-800J0D01*
G37*
G36*
G01X1659263Y1093897D02*
G02I-800J0D01*
G37*
G36*
G01X1655524Y1105116D02*
G02I-800J0D01*
G37*
G36*
G01X1651783Y1093897D02*
G02I-800J0D01*
G37*
G36*
G01X1648044Y1105116D02*
G02I-800J0D01*
G37*
G36*
G01X1655524Y1101376D02*
G02I-800J0D01*
G37*
G36*
G01X1651783Y1097637D02*
G02I-800J0D01*
G37*
G36*
G01X1655524Y1228543D02*
G02I-800J0D01*
G37*
G36*
G01X1648044D02*
G02I-800J0D01*
G37*
G36*
G01X1659264Y1232283D02*
G02I-800J0D01*
G37*
G36*
G01X1655524Y1224803D02*
G02I-800J0D01*
G37*
G36*
G01X1659264Y1236023D02*
G02I-800J0D01*
G37*
G36*
G01X1651784D02*
G02I-800J0D01*
G37*
G36*
G01X1648044Y1224803D02*
G02I-800J0D01*
G37*
G36*
G01X1651784Y1232283D02*
G02I-800J0D01*
G37*
G36*
G01X1655524Y1243503D02*
G02I-800J0D01*
G37*
G36*
G01X1651784Y1250984D02*
G02I-800J0D01*
G37*
G36*
G01X1648044Y1247243D02*
G02I-800J0D01*
G37*
G36*
G01X1655524D02*
G02I-800J0D01*
G37*
G36*
G01X1648044Y1243503D02*
G02I-800J0D01*
G37*
G36*
G01X1659264Y1250984D02*
G02I-800J0D01*
G37*
G36*
G01X1651784Y1254724D02*
G02I-800J0D01*
G37*
G36*
G01X1659264D02*
G02I-800J0D01*
G37*
G36*
G01X1666744Y1093897D02*
G02I-800J0D01*
G37*
G36*
G01X1663004Y1105116D02*
G02I-800J0D01*
G37*
G36*
G01X1670485D02*
G02I-800J0D01*
G37*
G36*
G01X1674224Y1097637D02*
G02I-800J0D01*
G37*
G36*
G01X1670485Y1101376D02*
G02I-800J0D01*
G37*
G36*
G01X1674224Y1093897D02*
G02I-800J0D01*
G37*
G36*
G01X1666744Y1097637D02*
G02I-800J0D01*
G37*
G36*
G01X1663004Y1101376D02*
G02I-800J0D01*
G37*
G36*
G01X1674225Y1112598D02*
G02I-800J0D01*
G37*
G36*
G01X1666745Y1123818D02*
G02I-800J0D01*
G37*
G36*
G01X1674225Y1120078D02*
G02I-800J0D01*
G37*
G36*
G01X1670485Y1123818D02*
G02I-800J0D01*
G37*
G36*
G01X1666745Y1116338D02*
G02I-800J0D01*
G37*
G36*
G01X1670485D02*
G02I-800J0D01*
G37*
G36*
G01X1666745Y1131299D02*
G02I-800J0D01*
G37*
G36*
G01X1670485D02*
G02I-800J0D01*
G37*
G36*
G01X1674225Y1127559D02*
G02I-800J0D01*
G37*
G36*
G01Y1135039D02*
G02I-800J0D01*
G37*
G36*
G01Y1202362D02*
G02I-800J0D01*
G37*
G36*
G01X1666745Y1198621D02*
G02I-800J0D01*
G37*
G36*
G01X1670485D02*
G02I-800J0D01*
G37*
G36*
G01X1666745Y1206102D02*
G02I-800J0D01*
G37*
G36*
G01X1670485Y1213582D02*
G02I-800J0D01*
G37*
G36*
G01X1674225Y1209842D02*
G02I-800J0D01*
G37*
G36*
G01X1670485Y1206102D02*
G02I-800J0D01*
G37*
G36*
G01X1666745Y1213582D02*
G02I-800J0D01*
G37*
G36*
G01X1674225Y1217322D02*
G02I-800J0D01*
G37*
G36*
G01Y1236023D02*
G02I-800J0D01*
G37*
G36*
G01X1663004Y1228543D02*
G02I-800J0D01*
G37*
G36*
G01X1670485D02*
G02I-800J0D01*
G37*
G36*
G01X1674225Y1232283D02*
G02I-800J0D01*
G37*
G36*
G01X1666745D02*
G02I-800J0D01*
G37*
G36*
G01Y1236023D02*
G02I-800J0D01*
G37*
G36*
G01X1663004Y1224803D02*
G02I-800J0D01*
G37*
G36*
G01X1670485D02*
G02I-800J0D01*
G37*
G36*
G01X1692926Y1090157D02*
G02I-800J0D01*
G37*
G36*
G01Y1101377D02*
G02I-800J0D01*
G37*
G36*
G01X1685445D02*
G02I-800J0D01*
G37*
G36*
G01X1677965Y1105116D02*
G02I-800J0D01*
G37*
G36*
G01X1681704Y1097637D02*
G02I-800J0D01*
G37*
G36*
G01X1677965Y1101376D02*
G02I-800J0D01*
G37*
G36*
G01X1689185Y1097637D02*
G02I-800J0D01*
G37*
G36*
G01X1685445Y1105117D02*
G02I-800J0D01*
G37*
G36*
G01X1681704Y1093897D02*
G02I-800J0D01*
G37*
G36*
G01X1689185D02*
G02I-800J0D01*
G37*
G36*
G01X1677965Y1120078D02*
G02I-800J0D01*
G37*
G36*
G01Y1112598D02*
G02I-800J0D01*
G37*
G36*
G01Y1135039D02*
G02I-800J0D01*
G37*
G36*
G01Y1127559D02*
G02I-800J0D01*
G37*
G36*
G01Y1202362D02*
G02I-800J0D01*
G37*
G36*
G01Y1209842D02*
G02I-800J0D01*
G37*
G36*
G01Y1217322D02*
G02I-800J0D01*
G37*
G36*
G01Y1228543D02*
G02I-800J0D01*
G37*
G36*
G01X1681705Y1236023D02*
G02I-800J0D01*
G37*
G36*
G01Y1232283D02*
G02I-800J0D01*
G37*
G36*
G01X1692926Y1228543D02*
G02I-800J0D01*
G37*
G36*
G01X1685445Y1224803D02*
G02I-800J0D01*
G37*
G36*
G01Y1228543D02*
G02I-800J0D01*
G37*
G36*
G01X1677965Y1224803D02*
G02I-800J0D01*
G37*
G36*
G01X1689185Y1232283D02*
G02I-800J0D01*
G37*
G36*
G01Y1236023D02*
G02I-800J0D01*
G37*
G36*
G01X1692926Y1239763D02*
G02I-800J0D01*
G37*
G36*
G01X1696666Y1090157D02*
G02I-800J0D01*
G37*
G36*
G01Y1101377D02*
G02I-800J0D01*
G37*
G36*
G01Y1228543D02*
G02I-800J0D01*
G37*
G36*
G01Y1239763D02*
G02I-800J0D01*
G37*
%LPD*%
G75*
G54D15*
X7271Y70981D03*
X11011Y79720D03*
X8786Y88425D03*
X14264Y94236D03*
X10292D03*
X12786Y87903D03*
X18000Y90000D03*
X18298Y102141D03*
X8000Y102500D03*
X10131Y115473D03*
X15143Y115581D03*
X14996Y133034D03*
X11442Y132719D03*
X19855Y133000D03*
X9082Y135789D03*
X19855Y141362D03*
X11999Y141415D03*
X15948Y141267D03*
X10966Y162073D03*
Y159073D03*
X16909Y153263D03*
X12247Y166341D03*
X17313Y166937D03*
X21909Y153263D03*
X22335Y166721D03*
X16709Y175943D03*
X19572Y219470D03*
Y221970D03*
X10259Y218085D03*
X13059D03*
X19638Y226320D03*
X16859Y216385D03*
X19572Y216970D03*
X22599Y228646D03*
X18206Y244571D03*
X15586Y249108D03*
X13715Y259381D03*
X8970Y254871D03*
X18206Y264571D03*
X7036Y272371D03*
X8335Y280663D03*
X14807Y282181D03*
X15586Y269108D03*
X15499Y288542D03*
X17033Y1006819D03*
X14357Y1009906D03*
X20216Y1009748D03*
X14197Y1014205D03*
Y1017759D03*
X20197Y1014205D03*
Y1017759D03*
X12599Y1438143D03*
X16304Y1468196D03*
X15889Y1494254D03*
X10089D03*
X6489Y1501334D03*
X19745Y1508846D03*
X7983Y1529035D03*
Y1525635D03*
X19735Y1530499D03*
X19859Y1520657D03*
X6951Y1538547D03*
X18879Y1534334D03*
X10367Y1553080D03*
X32350Y67562D03*
X28442Y55340D03*
X32350Y59562D03*
Y63562D03*
X26588Y97667D03*
X35442D03*
X35048Y103411D03*
X35688Y111255D03*
Y114655D03*
X22439Y102495D03*
X35207Y106561D03*
X28388Y121742D03*
X35688Y125428D03*
X28388Y132515D03*
Y118342D03*
X35688Y128828D03*
X28388Y135915D03*
X22935Y162073D03*
Y159073D03*
X26565Y177448D03*
X32507Y180517D03*
X30567Y195176D03*
X28067D03*
X25567D03*
X33067D03*
X29585Y199248D03*
X32585D03*
X29921Y206806D03*
X32585Y202048D03*
X25648Y210509D03*
X28148D03*
X29585Y201748D03*
X27421Y206806D03*
X27340Y230556D03*
X36185Y230117D03*
X31595Y227824D03*
X32201Y238714D03*
X23844Y239299D03*
X21556Y232971D03*
X31682Y246874D03*
X33902Y244297D03*
X26325Y262078D03*
X25549Y256394D03*
X31682Y266874D03*
X29116Y281129D03*
X37117Y279991D03*
X25549Y276394D03*
X34845Y291756D03*
X26629Y295619D03*
X35650Y491982D03*
Y495982D03*
X30177Y534211D03*
X34359Y541135D03*
X34732Y534909D03*
X25819Y527726D03*
Y548726D03*
X34425Y546553D03*
X34448Y552726D03*
X25819Y544726D03*
X30123Y611071D03*
X27686Y621311D03*
X36494Y616905D03*
X36306Y622285D03*
X27686Y629311D03*
Y625311D03*
X36692Y633724D03*
X36575Y627713D03*
X35293Y662952D03*
X35250Y671508D03*
X34565Y699082D03*
X36529Y1006321D03*
X30479Y1006509D03*
X24456Y1006401D03*
X32093Y1009748D03*
X26155Y1009985D03*
X29197Y1014205D03*
X32197Y1017759D03*
X26197D03*
X35197Y1014205D03*
X21196Y1065529D03*
Y1063029D03*
X36089Y1062601D03*
Y1065101D03*
X35925Y1075663D03*
X33425D03*
X28996Y1065529D03*
X23796D03*
X26396D03*
Y1063029D03*
X23796D03*
X28996D03*
X28606Y1082678D03*
X23406D03*
X26006D03*
Y1080178D03*
X23406D03*
X28606D03*
X20806Y1082678D03*
Y1080178D03*
X21321Y1098769D03*
X26521D03*
X29121D03*
X23921D03*
Y1101335D03*
X29121D03*
X26521D03*
X21321D03*
X32574Y1111633D03*
X29874D03*
X27274D03*
X24674D03*
Y1121333D03*
X27274D03*
X29874D03*
X32574D03*
X24674Y1130333D03*
X21974D03*
X21209Y1138705D03*
X23709D03*
X31631Y1198651D03*
X29860Y1438552D03*
X23603Y1449735D03*
X29880Y1441702D03*
X35825Y1464845D03*
X33189Y1501373D03*
X22381Y1554152D03*
X26231Y1554167D03*
X45988Y90512D03*
X51550Y90615D03*
X48476Y180812D03*
X48643Y442919D03*
X48596Y451419D03*
X45643Y472905D03*
X41643Y473419D03*
X49643Y472905D03*
Y464419D03*
X41643Y464919D03*
X48390Y485128D03*
X51239Y485138D03*
X40009Y481467D03*
X43948Y492108D03*
X44563Y482165D03*
X39801Y504825D03*
X42301D03*
X44801D03*
X43804Y500202D03*
X45256Y495993D03*
X45293Y522569D03*
X39742Y517401D03*
X42242D03*
X44742D03*
X46993Y529169D03*
X41408Y531882D03*
X43908D03*
X45293Y525369D03*
X46408Y531882D03*
X38358Y531948D03*
X52869Y537958D03*
X46643Y555194D03*
X52869Y540458D03*
X43843Y555194D03*
X46643Y571194D03*
X43843D03*
Y563194D03*
X46643D03*
X51000Y581222D03*
X45400D03*
X48200D03*
X51000Y591215D03*
X45400D03*
X48200D03*
X51172Y607762D03*
X48372D03*
X45572D03*
Y610562D03*
X48372D03*
X51172D03*
X40362Y610548D03*
X54192Y633473D03*
X42172Y633716D03*
X49192Y628078D03*
X47179Y633736D03*
X37847Y662910D03*
X39549Y682108D03*
X36910D03*
X37804Y671508D03*
X40165Y699082D03*
X37365D03*
X49249Y837718D03*
X52349D03*
X46049D03*
X53549Y843118D03*
X52077Y905295D03*
X48429Y916430D03*
X47264Y919649D03*
X48683Y1006510D03*
X42470Y1006738D03*
X50541Y1009589D03*
X44999Y1009510D03*
X38823Y1009273D03*
X47197Y1014205D03*
X41197D03*
X44197Y1017759D03*
X38197D03*
X48704Y1017982D03*
X43889Y1062601D03*
X38689D03*
X41289D03*
Y1065101D03*
X38689D03*
X43889D03*
X47314Y1072228D03*
X41172Y1079064D03*
X46166Y1093757D03*
X39659Y1105100D03*
X42259D03*
X44859D03*
X47559D03*
X48585Y1123867D03*
X47559Y1114800D03*
X44859D03*
X42259D03*
X39659D03*
X48547Y1133688D03*
X51047D03*
X55188Y1205179D03*
X51023Y1201416D03*
X48842Y1211109D03*
X53479Y1216256D03*
X43198Y1254055D03*
X45698D03*
X48198D03*
X45698Y1251555D03*
X43198D03*
X48198D03*
X47621Y1343672D03*
X39225Y1464845D03*
X48089Y1501387D03*
X39095Y1501361D03*
X47074Y1555923D03*
X40951Y1555932D03*
X64785Y79993D03*
Y82593D03*
Y85193D03*
Y74793D03*
Y77393D03*
X64829Y92874D03*
X55871Y99961D03*
X55921Y95236D03*
X66856Y104249D03*
Y107649D03*
X66478Y162368D03*
X63878D03*
X69261Y211695D03*
Y208695D03*
X65189Y210713D03*
Y213213D03*
Y208213D03*
X54733Y212978D03*
Y215478D03*
Y207978D03*
Y210478D03*
X65189Y215713D03*
X57987Y258880D03*
X60562Y264180D03*
X58062D03*
X66956Y267526D03*
Y270026D03*
X54167Y457339D03*
X56667D03*
X65737Y445603D03*
X57857Y446071D03*
X56667Y459839D03*
X54167D03*
Y462339D03*
X56667D03*
X62224Y473045D03*
X67670Y464818D03*
X58224Y465004D03*
X63154Y462371D03*
X55124Y478625D03*
X53739Y485138D03*
X56239D03*
X56824Y482425D03*
X55124Y475825D03*
X62700Y491214D03*
X66403Y495487D03*
X62700Y493714D03*
X66403Y492987D03*
X68202Y537877D03*
X56572Y539731D03*
X68202Y542877D03*
Y545377D03*
Y540377D03*
X61330Y544895D03*
X56572Y542231D03*
X64130Y541895D03*
Y544895D03*
X61630Y541895D03*
X68188Y548358D03*
X64408Y582747D03*
X63859Y590801D03*
X67684Y597232D03*
X63684Y597130D03*
X67684Y605637D03*
X61854Y617853D03*
Y620653D03*
X53972Y607762D03*
Y610562D03*
X59684Y605443D03*
X63684D03*
X66530Y625013D03*
X58181Y627908D03*
X64692Y642184D03*
X56049Y827218D03*
X68649D03*
X69049Y847718D03*
X65549Y850718D03*
X68598Y859415D03*
X68778Y873821D03*
X63969Y869475D03*
X63930Y874694D03*
X68100Y910122D03*
X71528Y913190D03*
X64632Y901500D03*
X59962Y910251D03*
X53197Y1014205D03*
Y1017759D03*
X55699Y1072761D03*
X61588Y1074481D03*
X62109Y1087656D03*
Y1084656D03*
Y1079656D03*
Y1091656D03*
X60269Y1198820D03*
X63094Y1207604D03*
X55596Y1210466D03*
X68245Y1212054D03*
X58443Y1272257D03*
X54843Y1501625D03*
X60227Y1514751D03*
X60277Y1528395D03*
X55862Y1541791D03*
X65478Y1541980D03*
X60303Y1534436D03*
X60747Y1555890D03*
X64747D03*
X60864Y1583484D03*
X58064D03*
X55264D03*
X69816Y1592527D03*
X60554Y1615152D03*
X73110Y98551D03*
X77804Y95879D03*
X76005Y114623D03*
Y111223D03*
X76660Y103783D03*
X76005Y125396D03*
Y128796D03*
X75194Y141247D03*
X71422Y147540D03*
X82661Y143740D03*
X80041Y148277D03*
X73578Y165393D03*
Y162793D03*
Y170493D03*
Y167993D03*
X80502Y177616D03*
X81083Y172190D03*
X72575Y181426D03*
X75786Y181366D03*
X78581Y181009D03*
X83756Y168697D03*
X84844Y191941D03*
X75400Y184012D03*
X72783Y184221D03*
X72061Y208695D03*
X71761Y211695D03*
X76819Y213859D03*
Y211359D03*
X80522Y213132D03*
Y215632D03*
X80766Y256303D03*
X75438Y265701D03*
X85541Y266114D03*
X80525Y265896D03*
X72256Y267526D03*
X69756D03*
Y270026D03*
X72256D03*
X83014Y281982D03*
X77073Y281716D03*
X71130Y462152D03*
Y459652D03*
Y464652D03*
X73630Y459652D03*
Y462152D03*
Y464652D03*
X78033Y491133D03*
X71461Y498151D03*
Y495151D03*
X73961D03*
X78033Y498633D03*
Y496133D03*
Y493633D03*
X73961Y498151D03*
X78133Y553297D03*
Y555897D03*
X75688Y548358D03*
X73188D03*
X70688D03*
X78133Y558497D03*
Y566597D03*
Y563697D03*
Y561097D03*
X72128Y570686D03*
X74923Y570478D03*
X75340Y576484D03*
X74983Y573689D03*
X72337Y573303D03*
X78733Y578405D03*
X84159Y578986D03*
X83684Y596729D03*
X72515Y596089D03*
X77734Y596782D03*
X81740Y619758D03*
Y616958D03*
Y614158D03*
X69670Y619513D03*
Y616713D03*
Y613913D03*
X79684Y605443D03*
X82648Y670679D03*
X73914Y660107D03*
X79043Y667391D03*
X84845Y659857D03*
X84314Y686107D03*
X82562Y680037D03*
X78735Y683426D03*
X72149Y827318D03*
X74349Y824718D03*
Y821918D03*
X74700Y842890D03*
X84367Y878286D03*
X76528Y878533D03*
X74028Y889065D03*
X83079Y888515D03*
X72035Y898346D03*
X80339Y897943D03*
X76203Y897910D03*
X80593Y946082D03*
X78167Y949261D03*
X76332Y953421D03*
X87632Y1007522D03*
X70059Y1075656D03*
X70302Y1067656D03*
X77734Y1095676D03*
X70947Y1201565D03*
Y1205835D03*
X71006Y1228684D03*
X71020Y1224323D03*
X74909Y1593009D03*
X71910Y1625009D03*
X78291Y1625743D03*
X83689Y1624736D03*
X82291Y1633801D03*
X78291D03*
X70291D03*
X86407Y132509D03*
Y118335D03*
Y121735D03*
Y135909D03*
X91224Y141247D03*
X92337Y144172D03*
X95711Y143518D03*
X94811Y152373D03*
X97961Y152562D03*
X103456Y157370D03*
X98826Y172665D03*
X98763Y178560D03*
X98653Y183834D03*
X99639Y186629D03*
X98943Y200864D03*
X92898Y192490D03*
X98173Y190185D03*
X89353Y206767D03*
X86853D03*
X91853D03*
X98966Y207037D03*
X99032Y212455D03*
X89483Y221708D03*
X86983D03*
X86398Y224421D03*
X88098Y231021D03*
Y228221D03*
X96333Y221642D03*
X91983Y221708D03*
X103841Y228631D03*
X93649Y236189D03*
X91149D03*
X88649D03*
X91090Y248765D03*
X88590D03*
X93590D03*
X97747Y265897D03*
X100247D03*
X94087Y270695D03*
X91287D03*
X88787D03*
Y268195D03*
X91287D03*
X94087D03*
X98255Y374510D03*
X100120Y377898D03*
X100066Y381976D03*
X86788Y581659D03*
X87684Y605443D03*
X95973Y655660D03*
X92897Y658359D03*
X95917Y658374D03*
X95539Y664443D03*
X86289Y822088D03*
X86367Y848086D03*
X90000Y871389D03*
X103770Y868206D03*
X103692Y900295D03*
X91387Y905295D03*
X100058Y977651D03*
X99836Y980330D03*
X103836Y988813D03*
X100200Y988800D03*
X95836Y988813D03*
X85706Y998507D03*
X94398Y1006648D03*
X101025Y1009655D03*
X94586Y1023900D03*
X91765Y1018307D03*
X88007Y1013678D03*
X88479Y1023731D03*
X88287Y1026537D03*
X97609Y1018469D03*
X90450Y1033542D03*
X93496Y1547768D03*
X107364Y116594D03*
X118307Y110784D03*
X113307D03*
X107364Y119594D03*
X117886Y124663D03*
X112864Y124879D03*
X107798Y124283D03*
X119230Y138838D03*
X106205Y161306D03*
X107540Y176665D03*
Y168665D03*
Y196665D03*
Y192665D03*
X107653Y186778D03*
X107572Y204864D03*
Y208864D03*
X112621Y218085D03*
X115421D03*
X103213Y219379D03*
X117948Y249108D03*
X109329Y248371D03*
X111993Y710102D03*
X120250Y758841D03*
X113505Y796856D03*
X109591Y796905D03*
X102355Y874267D03*
X102947Y877196D03*
X102320Y891043D03*
X110887Y884000D03*
X103972Y977609D03*
X103836Y980330D03*
X111836Y988813D03*
X119836D03*
X115836D03*
X107836D03*
X103825Y1009655D03*
X105971Y1025745D03*
X114770Y1016827D03*
X110409Y1024094D03*
X114770Y1029427D03*
X110970Y1030672D03*
X101970D03*
X104970D03*
X107970D03*
X102761Y1096233D03*
X108971Y1109564D03*
X103124D03*
Y1122164D03*
X108971D03*
X103124Y1134764D03*
X108971D03*
X103124Y1147364D03*
X108971D03*
X103124Y1172564D03*
X108971D03*
X103124Y1159964D03*
X108971D03*
X103861Y1182703D03*
X118533Y1207737D03*
X112048Y1214372D03*
X107803Y1218169D03*
X128950Y97667D03*
X133200Y95111D03*
X124606Y102495D03*
X119333Y116594D03*
X130750Y132515D03*
Y121742D03*
Y118342D03*
X119333Y119594D03*
X122867Y125107D03*
X130750Y135915D03*
X124340Y142862D03*
X131481Y143762D03*
X125381Y148717D03*
X131947Y199248D03*
X127929Y195176D03*
X130429D03*
X132929D03*
X134947Y199248D03*
X128010Y210509D03*
X130510D03*
X132283Y206806D03*
X129783D03*
X131947Y201748D03*
X122000Y226320D03*
X119221Y216385D03*
X121934Y216970D03*
Y219470D03*
Y221970D03*
X129702Y230556D03*
X133957Y227824D03*
X124961Y228646D03*
X128687Y242078D03*
X123918Y232971D03*
X134044Y246874D03*
X120568Y244571D03*
X127911Y256394D03*
X126131Y359511D03*
X125753Y365856D03*
X119099Y755052D03*
X118467Y796785D03*
X122437Y860775D03*
X125698Y857515D03*
X122432Y857540D03*
X129666Y857514D03*
X133424Y857303D03*
X122887Y888000D03*
X123387Y892000D03*
X135836Y988813D03*
X131836D03*
X123836D03*
X127836D03*
X120617Y1029427D03*
Y1016827D03*
X133579Y1097469D03*
X124925Y1102091D03*
X130380Y1105091D03*
X124880D03*
X124925Y1114691D03*
Y1127291D03*
X124880Y1117691D03*
X130380D03*
X124925Y1139891D03*
X124880Y1130291D03*
X130380D03*
X130434Y1144964D03*
X124474Y1142997D03*
X130380Y1155491D03*
X124880D03*
X124925Y1152491D03*
X124474Y1168197D03*
X130434Y1170164D03*
X124925Y1165091D03*
Y1177691D03*
X131000Y1180266D03*
X124765Y1180691D03*
X135757Y1221407D03*
X135448Y1229402D03*
Y1234921D03*
X126433Y1230407D03*
X129250Y1227650D03*
X137410Y103411D03*
X137804Y97667D03*
X148600Y90650D03*
X148350Y95236D03*
X138050Y111255D03*
Y114655D03*
X137569Y106561D03*
X138050Y128828D03*
Y125428D03*
X135429Y195176D03*
X134947Y202048D03*
X138547Y230117D03*
X134563Y238714D03*
X138664Y241699D03*
X148061Y378600D03*
X148692Y391001D03*
X148061Y382600D03*
X148692Y394401D03*
Y405174D03*
X140690Y401513D03*
Y398113D03*
X148692Y408574D03*
X138290Y412287D03*
X148692Y419347D03*
Y422747D03*
X138290Y415687D03*
Y426460D03*
X148692Y433521D03*
X138290Y429860D03*
X148692Y436921D03*
X138290Y440633D03*
X148176Y458711D03*
X138290Y444033D03*
X148940Y455921D03*
X145376Y458711D03*
X138290Y469387D03*
Y472787D03*
X147520Y463600D03*
X148692Y476499D03*
X138290Y483560D03*
X148692Y490673D03*
X138290Y486960D03*
X148692Y479899D03*
Y494073D03*
Y524033D03*
Y520633D03*
X138290Y516921D03*
Y513521D03*
Y531094D03*
X148692Y538206D03*
Y534806D03*
X138290Y527694D03*
X142024Y552466D03*
X147925Y603600D03*
Y619600D03*
Y623600D03*
X149469Y634190D03*
X152658Y645389D03*
X136862Y857244D03*
X147836Y988813D03*
X139836D03*
X151836D03*
X143836D03*
X142026Y1012354D03*
X136571Y1009354D03*
X136526Y1012354D03*
X136571Y1021954D03*
X142026Y1024954D03*
X136526D03*
X144640Y1039439D03*
X150952Y1040115D03*
X146595Y1053457D03*
X136432Y1224472D03*
X167191Y92874D03*
X153912Y90615D03*
X158283Y95236D03*
X158233Y99961D03*
X166240Y162368D03*
X157095Y210478D03*
Y207978D03*
Y215478D03*
Y212978D03*
X160424Y264180D03*
X162924D03*
X160349Y258880D03*
X164496Y309405D03*
X150703Y453682D03*
X159836Y988813D03*
X155836Y997860D03*
X160733Y1056594D03*
X153693Y1051037D03*
X160547Y1049283D03*
X160627Y1053561D03*
X160807Y1043955D03*
X166188Y1066551D03*
X163191Y1065313D03*
X159228Y1065613D03*
X165649Y1159350D03*
Y1151870D03*
X167147Y77393D03*
Y74793D03*
Y85193D03*
Y82593D03*
Y79993D03*
X175472Y98551D03*
X178367Y111223D03*
Y114623D03*
X179022Y103783D03*
X169218Y107649D03*
Y104249D03*
X178367Y128796D03*
Y125396D03*
X173784Y147540D03*
X177556Y141247D03*
X185023Y143740D03*
X182403Y148277D03*
X175940Y162793D03*
Y165393D03*
X168840Y162368D03*
X175940Y167993D03*
Y170493D03*
X178148Y181366D03*
X180943Y181009D03*
X174937Y181426D03*
X182864Y177616D03*
X183445Y172190D03*
X175145Y184221D03*
X177762Y184012D03*
X171623Y211695D03*
X182884Y213132D03*
X179181Y211359D03*
Y213859D03*
X174123Y211695D03*
X167551Y208213D03*
Y213213D03*
Y210713D03*
X171623Y208695D03*
X174423D03*
X167551Y215713D03*
X182884Y215632D03*
X177800Y265701D03*
X182887Y265896D03*
X174618Y267526D03*
Y270026D03*
X169318Y267526D03*
X172118D03*
Y270026D03*
X169318D03*
X179435Y281716D03*
X170215Y311671D03*
X175615Y550907D03*
X173115D03*
X175615Y553407D03*
X173115D03*
X174923Y545263D03*
Y541863D03*
X177385Y566929D03*
X171339Y572070D03*
X172686Y569928D03*
X175033Y570962D03*
X174776Y568475D03*
X177099Y569426D03*
X169389Y1155610D03*
X191568Y76587D03*
Y72615D03*
X193007Y100625D03*
X186026Y97475D03*
X185957Y106186D03*
X197380Y112083D03*
X188769Y118335D03*
Y121735D03*
Y132509D03*
Y135909D03*
X193586Y141247D03*
X198073Y143518D03*
X197173Y152373D03*
X201015Y183834D03*
X201125Y178560D03*
X186118Y168697D03*
X201188Y172665D03*
X187206Y191941D03*
X195260Y192490D03*
X200535Y190185D03*
X201305Y200864D03*
X189215Y206767D03*
X191715D03*
X194215D03*
X201394Y212455D03*
X201328Y207037D03*
X194345Y221708D03*
X198695Y221642D03*
X190460Y228221D03*
Y231021D03*
X191845Y221708D03*
X188760Y224421D03*
X189345Y221708D03*
X191011Y236189D03*
X193511D03*
X196011D03*
X190952Y248765D03*
X193452D03*
X195952D03*
X183128Y256303D03*
X187903Y266114D03*
X196449Y268195D03*
X193649D03*
X196449Y270695D03*
X193649D03*
X191149D03*
Y268195D03*
X185376Y281982D03*
X185328Y545528D03*
X194063Y577716D03*
X191125Y610400D03*
X203248Y55513D03*
X199473Y68581D03*
X205848Y60513D03*
X208645Y60369D03*
X199486Y80581D03*
X214389Y86012D03*
X203616Y88801D03*
X214389Y94374D03*
X206533Y94351D03*
X210482Y94279D03*
X209530Y86046D03*
X205976Y85731D03*
X209726Y116594D03*
X201669Y103621D03*
X215669Y110784D03*
X209726Y119594D03*
X210160Y124283D03*
X215226Y124879D03*
X208567Y161306D03*
X200323Y152562D03*
X205818Y157370D03*
X209902Y176665D03*
Y168665D03*
X202001Y186629D03*
X209902Y196665D03*
Y192665D03*
X210015Y186778D03*
X209934Y204864D03*
Y208864D03*
X214983Y218085D03*
X205575Y219379D03*
X206203Y228631D03*
X211691Y248371D03*
X200109Y265897D03*
X202609D03*
X204675Y382109D03*
X204674Y551683D03*
Y558917D03*
Y561420D03*
X200495Y577937D03*
X208500Y595500D03*
X203500Y606929D03*
X208000Y604567D03*
X203460Y618400D03*
X203741Y612592D03*
X209158Y610072D03*
X209094Y616317D03*
X208540Y621591D03*
X205941Y668934D03*
X201115Y695581D03*
X203046Y693716D03*
X213969Y1447453D03*
Y1461853D03*
Y1458453D03*
Y1450853D03*
X231312Y97667D03*
X221695Y116594D03*
X226968Y102495D03*
X220669Y110784D03*
X221695Y119594D03*
X225229Y125107D03*
X220248Y124663D03*
X226702Y142862D03*
X227743Y148717D03*
X221592Y138838D03*
X230291Y195176D03*
X230372Y210509D03*
X224362Y226320D03*
X224296Y216970D03*
Y219470D03*
Y221970D03*
X221583Y216385D03*
X217783Y218085D03*
X232064Y230556D03*
X227323Y228646D03*
X231049Y242078D03*
X226280Y232971D03*
X220310Y249108D03*
X222930Y244571D03*
X233417Y253198D03*
X230842Y313888D03*
X233258Y359186D03*
X228267Y396718D03*
X221375Y455024D03*
X220349Y465622D03*
X225500Y530000D03*
X225000Y540500D03*
X224000Y547075D03*
X224200Y549800D03*
X223500Y568000D03*
X224104Y562800D03*
X224040Y558800D03*
X221693Y594982D03*
X222289Y590895D03*
X220333Y617930D03*
X220255Y629749D03*
X217906Y1430452D03*
Y1427052D03*
X219525Y1440028D03*
X216125D03*
X227249Y1447453D03*
Y1450853D03*
Y1458453D03*
Y1461853D03*
X224780Y1478149D03*
X217985Y1483055D03*
X225765Y1471985D03*
X233313Y1476699D03*
X221899Y1488800D03*
X218021Y1494724D03*
X222843Y1498442D03*
X217614Y1489671D03*
X233180Y1486442D03*
X233166Y1491454D03*
X226135Y1502442D03*
X230758Y1505046D03*
X226971Y1514578D03*
X227552Y1530675D03*
X232622Y1531104D03*
X226971Y1522578D03*
X219981Y1530797D03*
X223322Y1518578D03*
X222119Y1539941D03*
X227882Y1540816D03*
X233753Y1539752D03*
X239772Y103411D03*
X240166Y97667D03*
X235562Y95111D03*
X240412Y114655D03*
Y111255D03*
X239931Y106561D03*
X233112Y132515D03*
Y121742D03*
X240412Y125428D03*
X233112Y118342D03*
X240412Y128828D03*
X233112Y135915D03*
X233843Y143762D03*
X232791Y195176D03*
X235291D03*
X237309Y199248D03*
X234309D03*
X237791Y195176D03*
X237309Y202048D03*
X232872Y210509D03*
X234645Y206806D03*
X232145D03*
X234309Y201748D03*
X240909Y230117D03*
X236319Y227824D03*
X236925Y238714D03*
X236406Y246874D03*
X238626Y244297D03*
X234986Y336161D03*
X236264Y342494D03*
X245362Y546712D03*
Y542712D03*
X247536Y602689D03*
X247278Y618288D03*
X243278D03*
X240194Y643113D03*
X242102Y656321D03*
X250102D03*
X246102D03*
X245000Y678462D03*
X244267Y696911D03*
X235790Y754332D03*
X241204Y814841D03*
X237591Y815266D03*
X248556Y824003D03*
X246311Y819000D03*
X238400Y836900D03*
X234976Y1481676D03*
X243535Y1511473D03*
X245500Y1517033D03*
X237633Y1511909D03*
X244600Y1531700D03*
X240808Y1519942D03*
X235687Y1522578D03*
X237580Y1528604D03*
X245937Y1524237D03*
X239949Y1541327D03*
X244912Y1539389D03*
X250962Y90650D03*
X256274Y90615D03*
X260595Y99961D03*
X260645Y95236D03*
X250712D03*
X259457Y210478D03*
Y207978D03*
Y215478D03*
Y212978D03*
X262786Y264180D03*
X262711Y258880D03*
X257993Y307994D03*
X256475Y422088D03*
X252695Y442956D03*
X254512Y438323D03*
X261965Y458455D03*
X250336Y456386D03*
X254678Y445873D03*
X263301Y444232D03*
X262526Y451108D03*
X249125Y465874D03*
X252688Y636364D03*
X248690Y678519D03*
X248090Y691114D03*
X254634Y698241D03*
X248506Y812042D03*
X256303Y812254D03*
X250700Y819900D03*
X254058Y819851D03*
X255289Y824340D03*
X252305Y831018D03*
X252100Y836800D03*
X250876Y1532782D03*
X255909Y1542043D03*
X250790Y1539759D03*
X269509Y77393D03*
Y74793D03*
Y85193D03*
Y82593D03*
Y79993D03*
X277834Y98551D03*
X269553Y92874D03*
X271580Y107649D03*
Y104249D03*
X276146Y147540D03*
X279918Y141247D03*
X268602Y162368D03*
X271202D03*
X278302Y162793D03*
Y165393D03*
Y167993D03*
Y170493D03*
X277299Y181426D03*
X280124Y184012D03*
X277507Y184221D03*
X269913Y210713D03*
X273985Y208695D03*
X276785D03*
X273985Y211695D03*
X276485D03*
X269913Y208213D03*
Y213213D03*
Y215713D03*
X265286Y264180D03*
X280162Y265701D03*
X276980Y267526D03*
Y270026D03*
X271680Y267526D03*
X274480D03*
Y270026D03*
X271680D03*
X281797Y281716D03*
X277575Y395084D03*
X274425Y381500D03*
X278784Y435158D03*
X278529Y440489D03*
X274949Y442606D03*
X278827Y444841D03*
X282230Y458572D03*
X265011Y453881D03*
X280220Y448493D03*
X274866Y446606D03*
X265011Y446595D03*
X275873Y463479D03*
X276344Y467367D03*
X274096Y820725D03*
X274697Y830951D03*
X275123Y847874D03*
X269700Y853100D03*
X275400Y864400D03*
X278400Y890839D03*
X275400Y899400D03*
X279261Y926339D03*
X278739Y936439D03*
X289797Y36735D03*
X290113Y23188D03*
X284666Y34068D03*
X289631Y28281D03*
X293930Y76587D03*
Y72615D03*
X295369Y100625D03*
X288388Y97475D03*
X280729Y111223D03*
Y114623D03*
X281384Y103783D03*
X288319Y106186D03*
X280729Y125396D03*
X291131Y121735D03*
X280729Y128796D03*
X291131Y118335D03*
Y132509D03*
Y135909D03*
X295948Y141247D03*
X287385Y143740D03*
X284765Y148277D03*
X285807Y172190D03*
X280510Y181366D03*
X283305Y181009D03*
X288480Y168697D03*
X285226Y177616D03*
X289568Y191941D03*
X297622Y192490D03*
X291577Y206767D03*
X294077D03*
X296577D03*
X285246Y213132D03*
X281543Y211359D03*
Y213859D03*
X296707Y221708D03*
X292822Y228221D03*
Y231021D03*
X294207Y221708D03*
X291122Y224421D03*
X291707Y221708D03*
X285246Y215632D03*
X293373Y236189D03*
X295873D03*
X293314Y248765D03*
X295814D03*
X285490Y256303D03*
X290265Y266114D03*
X285249Y265896D03*
X296011Y270695D03*
X293511D03*
Y268195D03*
X296011D03*
X287738Y281982D03*
X286940Y315039D03*
X297719Y339559D03*
X291396Y350223D03*
X292520Y384410D03*
X292358Y393858D03*
X298000Y391496D03*
X295699Y382047D03*
X296000Y403500D03*
X298000Y409000D03*
X294000Y398583D03*
X295253Y440869D03*
Y438269D03*
X292453D03*
Y440869D03*
Y435669D03*
Y430469D03*
Y433069D03*
X295253D03*
Y430469D03*
Y435669D03*
X293307Y451677D03*
X295807D03*
X293307Y454177D03*
X295807D03*
X295011Y460218D03*
Y463618D03*
X281980Y953926D03*
X312256Y37543D03*
X305610Y55513D03*
X301835Y68581D03*
X310817Y60393D03*
X307916Y60529D03*
X301848Y80581D03*
X305978Y88801D03*
X312844Y94279D03*
X308895Y94351D03*
X308338Y85731D03*
X311892Y86046D03*
X312088Y116594D03*
X299742Y112083D03*
X304031Y103621D03*
X312088Y119594D03*
X312522Y124283D03*
X300435Y143518D03*
X299535Y152373D03*
X310929Y161306D03*
X302685Y152562D03*
X308180Y157370D03*
X312264Y176665D03*
Y168665D03*
X303377Y183834D03*
X303550Y172665D03*
X303487Y178560D03*
X304363Y186629D03*
X302897Y190185D03*
X312264Y196665D03*
Y192665D03*
X303667Y200864D03*
X312377Y186778D03*
X300814Y192859D03*
X312296Y204864D03*
Y208864D03*
X303756Y212455D03*
X303690Y207037D03*
X301057Y221642D03*
X307937Y219379D03*
X308565Y228631D03*
X298373Y236189D03*
X298314Y248765D03*
X302471Y265897D03*
X304971D03*
X298811Y270695D03*
Y268195D03*
X315079Y314890D03*
X312263Y324518D03*
X301943Y328867D03*
X308952Y356875D03*
X312316Y356747D03*
X299000Y377912D03*
Y386500D03*
X299088Y397912D03*
X322847Y19806D03*
X321840Y14408D03*
X322113Y26187D03*
X316751Y86012D03*
Y94374D03*
X324057Y116594D03*
X318031Y110784D03*
X323031D03*
X324057Y119594D03*
X327591Y125107D03*
X322610Y124663D03*
X317588Y124879D03*
X329064Y142862D03*
X330105Y148717D03*
X323954Y138838D03*
X317345Y218085D03*
X320145D03*
X323945Y216385D03*
X326658Y216970D03*
Y219470D03*
X326724Y226320D03*
X326658Y221970D03*
X329685Y228646D03*
X328642Y232971D03*
X322672Y249108D03*
X325292Y244571D03*
X314053Y248371D03*
X327032Y303962D03*
X314855Y311740D03*
X318508Y324322D03*
X315944Y332584D03*
X316067Y347937D03*
X321416Y348015D03*
X317333Y353470D03*
X318500Y356519D03*
X315310Y356712D03*
X320993Y467306D03*
Y470706D03*
Y481479D03*
Y484879D03*
Y514839D03*
Y511439D03*
Y525613D03*
Y529013D03*
X318660Y539315D03*
X320785Y553287D03*
X327456Y550065D03*
X320993Y564879D03*
Y561479D03*
Y575652D03*
Y579052D03*
Y603999D03*
Y593225D03*
Y589825D03*
Y607399D03*
X321119Y622912D03*
X330905Y15806D03*
Y19806D03*
Y27806D03*
X333674Y97667D03*
X342134Y103411D03*
X342528Y97667D03*
X337924Y95111D03*
X342774Y111255D03*
Y114655D03*
X329330Y102495D03*
X342293Y106561D03*
X335474Y118342D03*
Y132515D03*
X342774Y125428D03*
X335474Y121742D03*
X342774Y128828D03*
X335474Y135915D03*
X336205Y143762D03*
X335153Y195176D03*
X332653D03*
X336671Y199248D03*
X337653Y195176D03*
X340153D03*
X339671Y199248D03*
X336671Y201748D03*
X334507Y206806D03*
X337007D03*
X335234Y210509D03*
X332734D03*
X339671Y202048D03*
X343271Y230117D03*
X338681Y227824D03*
X334426Y230556D03*
X339287Y238714D03*
X333411Y242078D03*
X338768Y246874D03*
X340988Y244297D03*
X332635Y256394D03*
X347058Y399918D03*
X339072Y416888D03*
Y419488D03*
Y422088D03*
X345050Y454334D03*
X331395Y474418D03*
Y488591D03*
Y477818D03*
Y491991D03*
Y518552D03*
Y521952D03*
Y536125D03*
Y532725D03*
X337078Y551381D03*
X335399Y544718D03*
X331395Y568591D03*
Y571991D03*
Y586165D03*
Y582765D03*
Y600338D03*
Y596938D03*
Y611111D03*
Y614511D03*
X333985Y1017945D03*
X341077Y1018056D03*
X339251Y1138130D03*
X336755Y1143489D03*
X340500Y1147500D03*
X335190Y1173065D03*
X341266Y1171956D03*
X330800Y1174500D03*
X343121Y1188412D03*
X342009Y1176100D03*
X339776Y1187962D03*
X335502Y1188222D03*
X339540Y1196894D03*
X358636Y90615D03*
X353324Y90650D03*
X362957Y99961D03*
X353074Y95236D03*
X359376Y290592D03*
X348351Y319372D03*
X348806Y315427D03*
X351132Y322202D03*
X349120Y336100D03*
X351136Y372334D03*
X350486Y377173D03*
X358491D03*
X347591Y391533D03*
X359486Y385123D03*
X349311Y385644D03*
X354486Y385123D03*
X357655Y405889D03*
Y408489D03*
X358248Y403300D03*
X353894Y406060D03*
X354155Y421489D03*
Y418889D03*
Y416289D03*
X350163Y412106D03*
X357655Y413689D03*
Y416289D03*
Y421489D03*
Y418889D03*
Y424089D03*
Y411089D03*
X358042Y432718D03*
X357655Y426689D03*
X358042Y435518D03*
X358754Y450091D03*
X356241Y447001D03*
X359241D03*
X353320Y454214D03*
X353663Y449045D03*
X353367Y459330D03*
X358754Y462060D03*
X353670Y473571D03*
Y481071D03*
Y478571D03*
Y476071D03*
X360242Y477053D03*
X357742D03*
X358207Y836462D03*
X346366Y1134729D03*
X361621D03*
X349748D03*
X357748D03*
X353748D03*
X352545Y1142666D03*
X360877Y1157404D03*
X354420Y1157544D03*
X352931Y1167768D03*
X357950D03*
X357057Y1179542D03*
X357796Y1188058D03*
X357083Y1185205D03*
X361792Y1187310D03*
X348432Y1187215D03*
X348125Y1180175D03*
X358368Y1201043D03*
X354398D03*
X350402D03*
X346387Y1199256D03*
X360523Y1192282D03*
X349276Y1217228D03*
X351940Y1219895D03*
X362332Y1230265D03*
X355215Y1223170D03*
X360273Y1228226D03*
X358062Y1226016D03*
X371871Y85193D03*
Y82593D03*
Y79993D03*
Y77393D03*
Y74793D03*
X371915Y92874D03*
X363007Y95236D03*
X373942Y104249D03*
Y107649D03*
X370964Y162368D03*
X373564D03*
X372275Y208213D03*
X379147Y208695D03*
X376347D03*
Y211695D03*
X372275Y210713D03*
Y213213D03*
X361819Y207978D03*
Y212978D03*
Y215478D03*
Y210478D03*
X372275Y215713D03*
X367648Y264180D03*
X365148D03*
X365073Y258880D03*
X374042Y270026D03*
X376842D03*
X374042Y267526D03*
X376842D03*
X371417Y353820D03*
X365559Y354300D03*
X377237Y371060D03*
X373264Y379429D03*
X378875Y379088D03*
X366526Y377173D03*
X370486D03*
X362486Y385123D03*
X366486D03*
X370160Y391569D03*
X368587Y401066D03*
X378927Y406739D03*
X367919Y439318D03*
X375919Y442118D03*
Y439318D03*
X367919Y442118D03*
X361754Y450091D03*
X367564Y456034D03*
Y461034D03*
X373546Y470001D03*
X376046D03*
X361754Y462060D03*
X373971Y489036D03*
X371832Y485580D03*
X374332D03*
X376832D03*
X366420Y479986D03*
Y477486D03*
X363686Y478668D03*
Y476168D03*
X376207Y492836D03*
Y495636D03*
X376881Y518564D03*
X363015Y710365D03*
X365887Y710329D03*
X372400Y746300D03*
X372300Y750000D03*
X373500Y767300D03*
X376300D03*
X370415Y766108D03*
X373703Y782555D03*
X365850Y773950D03*
X371436Y791188D03*
X365691Y815127D03*
X371507Y815303D03*
X362042Y814772D03*
X368067Y925136D03*
X370214Y943812D03*
X368626Y931346D03*
X368964Y937738D03*
X372858Y935136D03*
X366761Y934550D03*
X363893Y946863D03*
X379928Y949774D03*
X379245Y956643D03*
X378875Y961862D03*
X370214Y947812D03*
X370101Y953699D03*
X370214Y963812D03*
Y971812D03*
X378928Y967812D03*
X372501Y1123695D03*
X365748Y1134325D03*
X368657Y1150087D03*
X366133Y1170767D03*
X366429Y1185238D03*
X366222Y1180235D03*
X362402Y1201039D03*
X366402Y1200969D03*
X366521Y1208993D03*
X370202Y1314764D03*
Y1311364D03*
X383612Y33768D03*
X388612Y31168D03*
X387948Y27288D03*
X380196Y98551D03*
X390750Y97475D03*
X383091Y111223D03*
Y114623D03*
X383746Y103783D03*
X390681Y106186D03*
X393493Y118335D03*
X383091Y125396D03*
Y128796D03*
X393493Y132509D03*
Y121735D03*
Y135909D03*
X380664Y165393D03*
Y162793D03*
Y167993D03*
Y170493D03*
X387588Y177616D03*
X382872Y181366D03*
X379661Y181426D03*
X385667Y181009D03*
X390842Y168697D03*
X388169Y172190D03*
X391930Y191941D03*
X382486Y184012D03*
X379869Y184221D03*
X393939Y206767D03*
X383905Y211359D03*
X387608Y213132D03*
X378847Y211695D03*
X383905Y213859D03*
X394069Y221708D03*
X393484Y224421D03*
X387608Y215632D03*
X387852Y256303D03*
X387611Y265896D03*
X382524Y265701D03*
X392627Y266114D03*
X379342Y270026D03*
Y267526D03*
X384159Y281716D03*
X390100Y281982D03*
X391737Y377581D03*
X384173Y379028D03*
X381237Y371076D03*
X394237Y379591D03*
X391940Y383817D03*
Y388817D03*
Y386317D03*
X385864Y398278D03*
X383364D03*
X378927Y409539D03*
X381927D03*
Y407039D03*
X381591Y401981D03*
X384091D03*
X378210Y424067D03*
X380710D03*
X385710D03*
X383210D03*
X378445Y413611D03*
X380945D03*
X385945D03*
X383445D03*
X385584Y438293D03*
Y441093D03*
Y443893D03*
X393646Y474382D03*
X385634Y472020D03*
X393662Y470382D03*
X385694Y477318D03*
X385293Y466409D03*
X387141Y484882D03*
X385131Y487382D03*
X391470Y732865D03*
X380963Y731000D03*
X381875Y740341D03*
X379800Y769200D03*
X380331Y782627D03*
X380607Y786932D03*
X392415Y792725D03*
X389015D03*
X387958Y813700D03*
X381631Y814147D03*
X384666Y814103D03*
X383391Y804000D03*
X386589Y864408D03*
X383462Y860535D03*
X392584Y875845D03*
X382675Y870151D03*
X391614Y930676D03*
X384856Y947987D03*
X378119Y953696D03*
X392910Y948536D03*
X393998Y971780D03*
X378790Y1001083D03*
X380280Y1006071D03*
X383710Y1007283D03*
X382465Y1012430D03*
X378410Y1131573D03*
X380261Y1129692D03*
X385091Y1297453D03*
Y1300853D03*
X386415Y1321645D03*
X391691Y1326715D03*
X392234Y1369579D03*
Y1364501D03*
X391757Y1383480D03*
X391852Y1389931D03*
X393951Y1447455D03*
X381900Y1544800D03*
X389700Y1536900D03*
X391740Y1545629D03*
Y1540529D03*
X382017Y1559700D03*
X395296Y1561024D03*
X391740Y1550729D03*
Y1555829D03*
X410789Y22627D03*
X408680Y37530D03*
X396680Y37543D03*
X400714Y45448D03*
X404686D03*
X397731Y100625D03*
X402104Y112083D03*
X406393Y103621D03*
X405912Y172665D03*
X405739Y183834D03*
X405849Y178560D03*
X406725Y186629D03*
X399984Y192490D03*
X405259Y190185D03*
X406029Y200864D03*
X395942Y192300D03*
X398939Y206767D03*
X396439D03*
X406118Y212455D03*
X406052Y207037D03*
X395184Y228221D03*
X399069Y221708D03*
X396569D03*
X403419Y221642D03*
X395184Y231021D03*
X410299Y219379D03*
X410927Y228631D03*
X400735Y236189D03*
X398235D03*
X395735D03*
X400676Y248765D03*
X398176D03*
X395676D03*
X407333Y265897D03*
X404833D03*
X401173Y268195D03*
Y270695D03*
X398373Y268195D03*
X395873D03*
Y270695D03*
X398373D03*
X405843Y315158D03*
X403343D03*
X394883Y341777D03*
Y338377D03*
X410086Y336795D03*
X409655Y331589D03*
X410688Y344736D03*
X400993Y331589D03*
Y335589D03*
X400728Y353152D03*
X411007Y356743D03*
X406421Y387151D03*
Y382151D03*
Y384651D03*
X398453Y387702D03*
X401253D03*
X394653Y389402D03*
X395577Y438293D03*
Y441093D03*
Y443893D03*
X397315Y471560D03*
X405801Y475560D03*
X405301Y467560D03*
X397315Y475560D03*
X406200Y741300D03*
X397223Y796792D03*
X400023D03*
X397900Y789000D03*
X407000Y784700D03*
X404468Y864407D03*
X396306Y864409D03*
X406770Y869767D03*
X405466Y881299D03*
X397431Y870654D03*
X401108Y878487D03*
X401121Y929686D03*
X409121D03*
X401121Y932186D03*
X409121D03*
X405179Y959051D03*
X404971Y956256D03*
X402354Y956465D03*
X401968Y959111D03*
X399173Y959468D03*
X397252Y962861D03*
X404176Y977684D03*
Y975084D03*
Y969984D03*
Y972484D03*
X396671Y968287D03*
X406954Y982970D03*
X409554D03*
X404354D03*
X407547Y1058097D03*
X410047D03*
X405047D03*
X407547Y1060697D03*
X410047D03*
X405047D03*
X408989Y1082501D03*
X409015Y1087705D03*
Y1085205D03*
X408847Y1090956D03*
Y1093956D03*
X406895Y1107997D03*
X402695D03*
Y1110897D03*
X407780Y1113648D03*
X409231Y1118801D03*
X406995Y1110597D03*
X404895Y1112397D03*
X404795Y1109397D03*
X402695Y1113797D03*
X408961Y1162384D03*
Y1164884D03*
Y1167384D03*
Y1169884D03*
Y1172384D03*
X403263Y1160834D03*
X408961Y1174884D03*
X406319Y1186709D03*
Y1184209D03*
Y1181709D03*
Y1179209D03*
X404004Y1192621D03*
Y1190121D03*
X397063Y1221428D03*
X401063D03*
X405063D03*
X409063D03*
X397063Y1233428D03*
Y1229428D03*
Y1225428D03*
X401063Y1237428D03*
Y1233428D03*
Y1229428D03*
Y1225428D03*
X405063Y1237428D03*
Y1233428D03*
Y1229428D03*
Y1225428D03*
X409063Y1237428D03*
Y1233428D03*
Y1229428D03*
Y1225428D03*
X401063Y1241428D03*
X405063Y1245428D03*
Y1241428D03*
X409063Y1245428D03*
Y1241428D03*
X404324Y1271889D03*
Y1275889D03*
X407767Y1292198D03*
X403678Y1295426D03*
X398584Y1313443D03*
X401011Y1307258D03*
X402967Y1319815D03*
X409220Y1315516D03*
X404583Y1316131D03*
X404921Y1321819D03*
X408787Y1321795D03*
X399959Y1352153D03*
X408159Y1349072D03*
X404759D03*
X395112Y1395690D03*
X398340Y1399779D03*
X395770Y1389817D03*
X410172Y1402446D03*
X402489Y1417275D03*
X405889D03*
X407970Y1449751D03*
X404500Y1452500D03*
X395888Y1450022D03*
X395199Y1482223D03*
X395380Y1485778D03*
X397266Y1514647D03*
X398747Y1500959D03*
X395370Y1501022D03*
X397266Y1518047D03*
X408964Y1531149D03*
X394391Y1537786D03*
Y1535286D03*
X399373Y1555855D03*
X405496Y1561024D03*
X400396D03*
X410596D03*
X397461Y1569560D03*
X401461D03*
X416900Y33400D03*
X422473Y22627D03*
X422450Y30483D03*
X422378Y26534D03*
X414145Y27486D03*
X413904Y32569D03*
X426147Y147540D03*
X414626Y176665D03*
Y168665D03*
Y196665D03*
Y192665D03*
X414739Y186778D03*
X414658Y204864D03*
Y208864D03*
X423651Y307470D03*
X419177Y304470D03*
X415777D03*
X422988Y323627D03*
X415129Y325181D03*
X412671Y333418D03*
X412812Y330617D03*
X426830Y359026D03*
X426138Y355079D03*
X416574Y357528D03*
X421413Y359053D03*
X412318Y367903D03*
X420422Y367859D03*
X418997Y382210D03*
Y384710D03*
Y387210D03*
X422215Y424939D03*
Y427439D03*
X414924Y435321D03*
Y438121D03*
X412124Y435321D03*
Y438121D03*
X414924Y440921D03*
X412124D03*
X414924Y443721D03*
X412124D03*
X426647Y452987D03*
X421267Y452799D03*
X414910Y448931D03*
X415433Y459170D03*
X425673Y461607D03*
X424876Y471334D03*
X418801Y474513D03*
X414275Y492469D03*
X424731Y492704D03*
X414275Y497469D03*
Y499969D03*
X427693Y498943D03*
X424731Y497704D03*
Y495204D03*
Y500204D03*
X414275Y494969D03*
X419340Y549990D03*
X419140Y547390D03*
Y544790D03*
X419340Y552590D03*
Y555190D03*
X423963Y625778D03*
X426607Y712360D03*
Y709760D03*
X424993Y728291D03*
X423700Y795500D03*
X426300Y797400D03*
X421200Y786400D03*
X411267Y829193D03*
Y831693D03*
X416267D03*
X413767D03*
Y829193D03*
X416267D03*
X425062Y883981D03*
X417121Y929686D03*
X425121D03*
X417121Y932186D03*
X425121D03*
X411960Y962261D03*
X414560D03*
X417160D03*
X411276Y978109D03*
X416476D03*
X413876D03*
X415047Y1058097D03*
X412547D03*
X415047Y1060697D03*
X412547D03*
X411989Y1082501D03*
X412015Y1085205D03*
X414989Y1082501D03*
X415015Y1085205D03*
Y1088205D03*
X412015D03*
X412297Y1091227D03*
X425060Y1101917D03*
X420782Y1105552D03*
X423340Y1104335D03*
X424995Y1106897D03*
X416988Y1104792D03*
X418495Y1106867D03*
X414580Y1113648D03*
X412080D03*
X411461Y1162384D03*
Y1164884D03*
Y1167384D03*
Y1169884D03*
Y1172384D03*
X420619Y1179421D03*
Y1181921D03*
Y1184421D03*
Y1186921D03*
X411461Y1174884D03*
X422934Y1192621D03*
Y1190121D03*
X417469Y1192621D03*
Y1190121D03*
X413063Y1221428D03*
X417063D03*
X421063D03*
X425063D03*
X413063Y1237428D03*
Y1233428D03*
Y1229428D03*
Y1225428D03*
X417063Y1237428D03*
Y1233428D03*
Y1229428D03*
Y1225428D03*
X421063Y1237428D03*
Y1233428D03*
Y1229428D03*
Y1225428D03*
X425063Y1237428D03*
Y1233428D03*
Y1229428D03*
Y1225428D03*
X413063Y1245428D03*
Y1241428D03*
X417063Y1245428D03*
Y1241428D03*
X421063Y1245428D03*
Y1241428D03*
X425063Y1245428D03*
Y1241428D03*
X425702Y1257160D03*
X422702Y1260160D03*
Y1257160D03*
X425702Y1260160D03*
X419702Y1257160D03*
Y1260160D03*
X413526Y1288938D03*
X419977Y1288843D03*
X413640Y1292856D03*
X419545Y1317722D03*
X413127Y1318011D03*
X425283Y1364023D03*
X417305Y1359169D03*
X425855Y1360495D03*
X425912Y1357141D03*
X416029Y1371572D03*
X420636Y1383912D03*
X418610Y1371590D03*
X423400Y1394500D03*
X423200Y1397500D03*
X418430Y1394237D03*
X422729Y1400490D03*
X420925Y1390330D03*
X419045Y1398874D03*
X421300Y1415400D03*
X419100Y1402200D03*
X421200Y1417900D03*
X411000Y1463500D03*
Y1460500D03*
Y1457500D03*
Y1454500D03*
Y1451000D03*
X413934Y1477101D03*
X417334D03*
X415202Y1496118D03*
Y1499518D03*
X417153Y1516886D03*
X413753D03*
X419619Y1539978D03*
X421454Y1544625D03*
X422539Y1534361D03*
X426701Y1541947D03*
X418151Y1552470D03*
X417461Y1569584D03*
X429919Y141247D03*
X437386Y143740D03*
X434766Y148277D03*
X431525Y304470D03*
X434925D03*
X427051Y307470D03*
X441296Y325061D03*
X436666Y322583D03*
X427713Y321965D03*
X430361Y323187D03*
X443424Y332988D03*
X440538Y355372D03*
X428420Y353578D03*
X435886Y353867D03*
X431524Y370309D03*
X434924D03*
X428637Y408104D03*
X431437D03*
X434237D03*
X428354Y420375D03*
X431154D03*
X433954D03*
X438098Y442114D03*
X437835Y435101D03*
X432270Y431112D03*
X432440Y440101D03*
X432075Y452718D03*
X438086Y452601D03*
X438078Y447121D03*
X433673Y461607D03*
X429673D03*
X435789Y501525D03*
X427568Y502003D03*
X435831Y498923D03*
X438644Y500461D03*
X428740Y549990D03*
X442804Y546990D03*
Y544390D03*
X428740Y546990D03*
Y544390D03*
Y555190D03*
Y552590D03*
X431384D03*
Y555190D03*
Y544390D03*
Y546990D03*
Y549990D03*
X443144Y628667D03*
X441162Y638313D03*
X439290Y712399D03*
X436790D03*
X439290Y709799D03*
X436790D03*
X434290Y712399D03*
Y709799D03*
X429290D03*
X431790Y712399D03*
X429290D03*
X431790Y709799D03*
X429253Y759847D03*
X432303Y785067D03*
X434100Y797400D03*
X430600D03*
X443091Y1026266D03*
X432678Y1016186D03*
X429878D03*
X427078D03*
X427052Y1019384D03*
X429852D03*
X432652D03*
X433378Y1091816D03*
Y1089316D03*
X430878Y1084316D03*
Y1086816D03*
X433378D03*
Y1084316D03*
X436244Y1090288D03*
X433378Y1081816D03*
X430878D03*
X429677Y1106955D03*
X439023Y1107997D03*
X436244Y1093088D03*
X434823Y1107997D03*
X431476Y1115896D03*
X427810Y1110092D03*
X439908Y1113648D03*
X441359Y1116101D03*
Y1118801D03*
X439123Y1110597D03*
X434823Y1113797D03*
Y1110897D03*
X437023Y1112397D03*
X436923Y1109397D03*
X431476Y1118396D03*
X429348Y1129092D03*
X432838Y1128821D03*
X436789Y1167384D03*
Y1164884D03*
Y1162384D03*
Y1172384D03*
Y1169884D03*
X439289Y1167384D03*
Y1164884D03*
Y1162384D03*
X427231D03*
X429731D03*
Y1164884D03*
Y1167384D03*
Y1169884D03*
Y1172384D03*
X427231D03*
Y1169884D03*
Y1167384D03*
Y1164884D03*
X439289Y1172384D03*
Y1169884D03*
X437132Y1158266D03*
X433249Y1186709D03*
Y1184209D03*
Y1181709D03*
Y1179209D03*
X429731Y1174884D03*
X427231D03*
X436789D03*
X439289D03*
X430934Y1190121D03*
Y1192621D03*
X429063Y1221428D03*
X433063D03*
X429063Y1237428D03*
Y1233428D03*
Y1229428D03*
Y1225428D03*
X433063Y1237428D03*
Y1233428D03*
Y1229428D03*
Y1225428D03*
X429063Y1245428D03*
Y1241428D03*
X433063Y1245428D03*
Y1241428D03*
X440702Y1260160D03*
Y1257160D03*
X437702Y1260160D03*
Y1257160D03*
X428702D03*
X431702Y1260160D03*
Y1257160D03*
X434702Y1260160D03*
Y1257160D03*
X428702Y1260160D03*
X434424Y1286274D03*
X430527Y1289198D03*
X440906D03*
X431867Y1315696D03*
X431885Y1313115D03*
X439434Y1322369D03*
X429530Y1325051D03*
X445949Y141247D03*
X450436Y143518D03*
X449536Y152373D03*
X452686Y152562D03*
X458181Y157370D03*
X443508Y337713D03*
X446566Y337917D03*
X443480Y344014D03*
X450852Y372054D03*
X455885Y367702D03*
X448391Y382641D03*
X448323Y379643D03*
X451144Y468809D03*
X459414Y468689D03*
X459757Y463520D03*
X459461Y473805D03*
X459929Y491669D03*
X450942Y506449D03*
X448442D03*
X445942D03*
X460537Y501905D03*
X459952Y496842D03*
X459645Y509486D03*
X446025Y511512D03*
X448525D03*
X446025Y519699D03*
X448525D03*
X452404Y549790D03*
X443004Y549890D03*
X452404Y546990D03*
Y544390D03*
X443004Y555090D03*
X452404Y552390D03*
Y554990D03*
X443004Y552490D03*
X455009Y554912D03*
Y552312D03*
Y544312D03*
Y546912D03*
Y549712D03*
X447279Y637031D03*
X447921Y630789D03*
X453552Y631779D03*
X446987Y643360D03*
X456469Y638302D03*
X460498Y870334D03*
X458120Y974701D03*
X451460Y974695D03*
X450591Y1004766D03*
X453270Y1003763D03*
X459360Y1012325D03*
X443591Y1019766D03*
X459885Y1018860D03*
X451140Y1021793D03*
X447091Y1019766D03*
X450875Y1028416D03*
X443091Y1034266D03*
X452091Y1039880D03*
X459700Y1032266D03*
X455468Y1104335D03*
X457188Y1101917D03*
X452910Y1105552D03*
X457123Y1106897D03*
X449116Y1104792D03*
X450623Y1106867D03*
X444208Y1113648D03*
X446708D03*
X457559Y1169884D03*
Y1167384D03*
Y1164884D03*
Y1162384D03*
X455059D03*
Y1164884D03*
Y1167384D03*
Y1169884D03*
Y1172384D03*
X457559D03*
X455059Y1174884D03*
X457559D03*
X447549Y1179421D03*
Y1181921D03*
Y1184421D03*
Y1186921D03*
X449864Y1190121D03*
Y1192621D03*
X449702Y1260160D03*
Y1257160D03*
X443702Y1260160D03*
X446702D03*
Y1257160D03*
X443702D03*
X451304Y1297045D03*
X454385Y1301845D03*
Y1305245D03*
X444288Y1314391D03*
X462089Y116594D03*
X474058D03*
X473032Y110784D03*
X468032D03*
X462089Y119594D03*
X474058D03*
X477592Y125107D03*
X462523Y124283D03*
X467589Y124879D03*
X472611Y124663D03*
X473955Y138838D03*
X460930Y161306D03*
X467346Y218085D03*
X470146D03*
X473946Y216385D03*
X475293Y244571D03*
X472673Y249108D03*
X464054Y248371D03*
X460950Y328185D03*
Y324785D03*
X463950Y332659D03*
Y336059D03*
X460950Y343933D03*
Y340533D03*
X472810Y347995D03*
X472913Y360089D03*
X472608Y352495D03*
X467335Y359944D03*
X463950Y351807D03*
Y348407D03*
X472913Y369089D03*
Y373589D03*
X469530Y366754D03*
X472913Y387089D03*
Y391589D03*
Y382589D03*
Y378089D03*
X470796Y394592D03*
X464848Y464566D03*
X467848D03*
X465126Y460435D03*
X462126D03*
X473658Y470509D03*
Y475509D03*
X467848Y476535D03*
X464848D03*
X468558Y495669D03*
Y499669D03*
Y516609D03*
X464199Y510184D03*
X468850Y545586D03*
X469300Y799500D03*
X459245Y807152D03*
X473654Y821234D03*
X472399Y839566D03*
X463404Y846870D03*
X465492Y861970D03*
X471726Y883705D03*
X474540Y927341D03*
X471110Y921577D03*
X471876Y937236D03*
X471068Y930235D03*
X473992Y952546D03*
X475018Y992568D03*
X467345Y996480D03*
X459360Y1004680D03*
X464795Y1000647D03*
X462185Y1016825D03*
X459860Y1015825D03*
X464385Y1038534D03*
X471558Y1029482D03*
X471755Y1038665D03*
X470610Y1033783D03*
X475588Y1043055D03*
X473639Y1030952D03*
X459700Y1035716D03*
X470978Y1046591D03*
X474348Y1090171D03*
X462913Y1106365D03*
X474277Y1093048D03*
X472482Y1107997D03*
X468282D03*
X459938Y1110092D03*
X463604Y1115896D03*
X473367Y1113648D03*
X474818Y1116101D03*
Y1118801D03*
X472582Y1110597D03*
X470482Y1112397D03*
X468282Y1110897D03*
Y1113797D03*
X470382Y1109397D03*
X463604Y1118396D03*
X462687Y1160834D03*
X474548Y1172384D03*
Y1169884D03*
Y1167384D03*
Y1164884D03*
Y1162384D03*
X468850Y1160834D03*
X474548Y1174884D03*
X465785Y1197471D03*
X461285Y1193471D03*
Y1197471D03*
X465785Y1193471D03*
X474647Y1260160D03*
Y1257160D03*
X471647D03*
Y1260160D03*
X459290Y1297035D03*
X463290D03*
X492135Y103411D03*
X492529Y97667D03*
X483675D03*
X487925Y95111D03*
X479331Y102495D03*
X485475Y118342D03*
Y121742D03*
Y132515D03*
Y135915D03*
X479065Y142862D03*
X486206Y143762D03*
X480106Y148717D03*
X487654Y195176D03*
X489672Y199248D03*
X485154Y195176D03*
X482654D03*
X486672Y199248D03*
X490154Y195176D03*
X485235Y210509D03*
X482735D03*
X489672Y202048D03*
X486672Y201748D03*
X484508Y206806D03*
X487008D03*
X476659Y216970D03*
Y219470D03*
X476725Y226320D03*
X476659Y221970D03*
X493272Y230117D03*
X484427Y230556D03*
X488682Y227824D03*
X479686Y228646D03*
X483412Y242078D03*
X478643Y232971D03*
X488769Y246874D03*
X489288Y238714D03*
X490989Y244297D03*
X482636Y256394D03*
X492817Y357111D03*
X491843Y351089D03*
X481724Y373589D03*
Y369089D03*
X490885Y373589D03*
X491053Y365423D03*
X491289Y391589D03*
X481724Y382589D03*
Y378089D03*
X490885Y382570D03*
X490985Y412342D03*
X488438Y418417D03*
X485485Y439903D03*
X489485D03*
X481485Y439900D03*
Y431917D03*
X489485Y431417D03*
X492736Y491982D03*
X482836Y534249D03*
X491818Y534909D03*
X491445Y541135D03*
X482905Y527726D03*
Y548726D03*
Y544726D03*
X491534Y552726D03*
X491511Y546553D03*
X487209Y611071D03*
X484772Y621311D03*
X493392Y622285D03*
X493580Y616905D03*
X484772Y629311D03*
Y625311D03*
X493661Y627713D03*
X493778Y633724D03*
X481165Y646036D03*
X483059Y662649D03*
X488765Y667224D03*
X481742Y657477D03*
X486837Y701306D03*
Y704706D03*
X489406Y797558D03*
X489572Y822805D03*
X479448Y828594D03*
X479700Y847600D03*
X477574Y860815D03*
X490706Y859339D03*
X491616Y938771D03*
X476475Y952249D03*
X479613Y952189D03*
X489163Y977163D03*
X487091Y989550D03*
X480711Y999941D03*
X477857Y1004375D03*
X488041Y1020440D03*
X485678Y1039880D03*
X485633Y1036155D03*
X477765Y1093432D03*
X477607Y1089942D03*
X491503Y1086796D03*
Y1084296D03*
X478517Y1086724D03*
Y1084224D03*
Y1081724D03*
X476017D03*
Y1084224D03*
Y1086724D03*
X486369Y1105552D03*
X490647Y1101917D03*
X488927Y1104335D03*
X490582Y1106897D03*
X482575Y1104792D03*
X484082Y1106867D03*
X480167Y1113648D03*
X477667D03*
X477048Y1172384D03*
Y1169884D03*
Y1167384D03*
Y1164884D03*
Y1162384D03*
X479521Y1179209D03*
Y1181709D03*
Y1184209D03*
Y1186709D03*
X477048Y1174884D03*
X490671Y1192621D03*
Y1190121D03*
X477206Y1192621D03*
Y1190121D03*
X489647Y1260160D03*
Y1257160D03*
X486647D03*
Y1260160D03*
X480647Y1257160D03*
X477647D03*
Y1260160D03*
X480647D03*
X483647Y1257160D03*
Y1260160D03*
X490100Y1302100D03*
X487600D03*
X503325Y90650D03*
X508637Y90615D03*
X503075Y95236D03*
X492775Y114655D03*
Y111255D03*
X492294Y106561D03*
X492775Y128828D03*
Y125428D03*
X496023Y362913D03*
X497048Y369450D03*
X495750Y377531D03*
X506500Y379687D03*
X495203Y386890D03*
X503729Y439919D03*
X503682Y448419D03*
X500729Y469905D03*
X496729Y470419D03*
X504729Y469905D03*
X496729Y461919D03*
X504729Y461419D03*
X505476Y485128D03*
X497095Y481467D03*
X501224Y492050D03*
X501649Y482165D03*
X501887Y504825D03*
X499387D03*
X496887D03*
X500890Y500202D03*
X502493Y495917D03*
X492736Y495982D03*
X501828Y517401D03*
X499328D03*
X496828D03*
X502379Y522569D03*
X495444Y531948D03*
X503494Y531882D03*
X502379Y525369D03*
X500994Y531882D03*
X498494D03*
X504079Y529169D03*
X503729Y555194D03*
X500929D03*
Y571194D03*
X503729D03*
Y563194D03*
X500929D03*
X505286Y581222D03*
X502486D03*
X505286Y591215D03*
X502486D03*
X505458Y610562D03*
X502658D03*
Y607762D03*
X505458D03*
X497448Y610548D03*
X504265Y633736D03*
X499258Y633716D03*
X506278Y628078D03*
X494465Y657772D03*
X502755Y657694D03*
X496070Y665976D03*
X499528Y657843D03*
X504966Y678098D03*
X498284Y681453D03*
Y678953D03*
X500714Y708755D03*
X502832Y720491D03*
X504895Y770457D03*
X501495D03*
X504508Y783817D03*
X506166Y793224D03*
X504641Y789139D03*
X507095Y814784D03*
X494677Y830468D03*
X509665Y824512D03*
X495073Y835586D03*
X495470Y844271D03*
X495700Y849389D03*
X503383Y863025D03*
X498507Y865392D03*
X508248Y873319D03*
X509791Y881932D03*
X509017Y905295D03*
X494315Y941212D03*
X503144Y957934D03*
X504088Y985171D03*
X506888D03*
X506702Y978947D03*
X493091Y989550D03*
X503933Y981392D03*
X498435Y1008766D03*
X506566D03*
Y996766D03*
X498524Y997590D03*
X498585Y1016266D03*
X506566Y1012266D03*
X503177Y1058097D03*
X495677D03*
X493177D03*
X498177D03*
X500677D03*
X503177Y1060697D03*
X495677D03*
X493177D03*
X498177D03*
X500677D03*
X494003Y1086796D03*
X496503D03*
X499003D03*
X501503D03*
Y1084296D03*
X499003D03*
X496503D03*
X494003D03*
X501831Y1090288D03*
X496372Y1106298D03*
X504610Y1107997D03*
X501831Y1093088D03*
X500410Y1107997D03*
X497063Y1115896D03*
X505495Y1113648D03*
X506946Y1116101D03*
Y1118801D03*
X504710Y1110597D03*
X500410Y1113797D03*
X502610Y1112397D03*
X500410Y1110897D03*
X502510Y1109397D03*
X493397Y1110092D03*
X497063Y1118396D03*
X498727Y1128759D03*
X495236Y1129094D03*
X502376Y1172384D03*
Y1169884D03*
Y1167384D03*
Y1164884D03*
Y1162384D03*
X504876Y1172384D03*
Y1169884D03*
Y1167384D03*
Y1164884D03*
Y1162384D03*
X492818D03*
Y1164884D03*
Y1167384D03*
Y1169884D03*
Y1172384D03*
X495318D03*
Y1169884D03*
Y1167384D03*
Y1164884D03*
Y1162384D03*
X502562Y1158200D03*
X506451Y1179209D03*
Y1181709D03*
Y1184209D03*
Y1186709D03*
X504876Y1174884D03*
X493821Y1186921D03*
Y1184421D03*
Y1181921D03*
Y1179421D03*
X492818Y1174884D03*
X495318D03*
X502376D03*
X504136Y1190121D03*
Y1192621D03*
X496136Y1190121D03*
Y1192621D03*
X506562Y1222194D03*
X502562D03*
X498562D03*
X494562D03*
X506562Y1226194D03*
Y1230194D03*
Y1234194D03*
Y1238194D03*
X502562Y1226194D03*
Y1230194D03*
Y1234194D03*
Y1238194D03*
X498562Y1226194D03*
Y1230194D03*
Y1234194D03*
Y1238194D03*
X494562Y1226194D03*
Y1230194D03*
Y1234194D03*
Y1238194D03*
Y1246194D03*
Y1242194D03*
X506562D03*
Y1246194D03*
X502562Y1242194D03*
Y1246194D03*
X498562Y1242194D03*
Y1246194D03*
X504647Y1257160D03*
X507347D03*
X501647D03*
Y1260160D03*
X495647D03*
X492647D03*
Y1257160D03*
X495647D03*
X498647D03*
Y1260160D03*
X507347D03*
X504647D03*
X521872Y82593D03*
Y85193D03*
Y74793D03*
Y77393D03*
Y79993D03*
X521916Y92874D03*
X512958Y99961D03*
X513008Y95236D03*
X523943Y107649D03*
Y104249D03*
X520965Y162368D03*
X523565D03*
X511820Y207978D03*
Y210478D03*
Y215478D03*
Y212978D03*
X522276Y208213D03*
Y213213D03*
Y210713D03*
Y215713D03*
X515149Y264180D03*
X517649D03*
X515074Y258880D03*
X524043Y270026D03*
Y267526D03*
X514769Y312953D03*
X519638Y314346D03*
X511790Y313804D03*
X512943Y443071D03*
X520823Y442603D03*
X511753Y454339D03*
Y456839D03*
X509253D03*
Y454339D03*
X518240Y459371D03*
X509253Y459339D03*
X511753D03*
X512210Y475825D03*
X517310Y470045D03*
X513310Y462004D03*
X522756Y461818D03*
X508325Y485138D03*
X512210Y478625D03*
X513910Y482425D03*
X513325Y485138D03*
X510825D03*
X519786Y491214D03*
X523489Y492987D03*
X519786Y493714D03*
X523489Y495487D03*
X509955Y537958D03*
X513658Y539731D03*
X518716Y541895D03*
X521216Y544895D03*
Y541895D03*
X513658Y542231D03*
X518416Y544895D03*
X509955Y540458D03*
X521494Y582747D03*
X508086Y581222D03*
X520945Y590801D03*
X508086Y591215D03*
X520770Y597130D03*
X524770Y605637D03*
X518940Y620653D03*
Y617853D03*
X511058Y610562D03*
Y607762D03*
X508258Y610562D03*
Y607762D03*
X520770Y605443D03*
X516770D03*
X523616Y625013D03*
X515267Y627908D03*
X511278Y633473D03*
X521778Y642184D03*
X521868Y666577D03*
X518812Y662874D03*
X510425Y683246D03*
X522200Y677613D03*
X521540Y686319D03*
X515484Y695757D03*
X515504Y701351D03*
X521159Y706388D03*
X515649D03*
X512530Y718301D03*
X514531Y716398D03*
X523929Y706388D03*
X518389D03*
X521131Y741071D03*
X517731D03*
X511724Y741035D03*
X508324D03*
X520549Y761982D03*
X509096Y753072D03*
X515422Y753455D03*
X513504Y755804D03*
X513278Y783286D03*
X520833Y773389D03*
X513551Y773203D03*
X522697Y797102D03*
X519891Y795848D03*
X518157Y803973D03*
X518565Y811973D03*
X520741Y805149D03*
X522481Y824661D03*
X517702Y826600D03*
X514682Y834590D03*
X511741Y846649D03*
X524741Y845149D03*
X520870Y874694D03*
X525159Y913818D03*
X521572Y901500D03*
X516902Y910251D03*
X520146Y939241D03*
X523289Y939195D03*
X521353Y952266D03*
X522544Y992854D03*
X512232Y985172D03*
X514566Y1000766D03*
X514690Y996766D03*
Y1004766D03*
X514566Y1016266D03*
X514649Y1020266D03*
X514843Y1030766D03*
X519500Y1028377D03*
X518497Y1105552D03*
X522775Y1101917D03*
X521055Y1104335D03*
X514703Y1104792D03*
X522710Y1106897D03*
X516210Y1106867D03*
X509795Y1113648D03*
X512295D03*
X520646Y1169884D03*
Y1167384D03*
Y1164884D03*
Y1162384D03*
X523146D03*
Y1164884D03*
Y1167384D03*
Y1169884D03*
Y1172384D03*
X520646D03*
X520751Y1186921D03*
Y1184421D03*
Y1181921D03*
Y1179421D03*
X523146Y1174884D03*
X520646D03*
X523066Y1190121D03*
Y1192621D03*
X522562Y1222194D03*
X518562D03*
X514562D03*
X510562D03*
X522562Y1226194D03*
X518562D03*
Y1230194D03*
Y1234194D03*
X514562Y1226194D03*
Y1230194D03*
Y1234194D03*
Y1238194D03*
X510562Y1226194D03*
Y1230194D03*
Y1234194D03*
Y1238194D03*
X514562Y1242194D03*
Y1246194D03*
X510562Y1242194D03*
Y1246194D03*
X530197Y98551D03*
X540751Y97475D03*
X533092Y114623D03*
Y111223D03*
X533747Y103783D03*
X533092Y128796D03*
Y125396D03*
X532281Y141247D03*
X528509Y147540D03*
X539748Y143740D03*
X537128Y148277D03*
X530665Y162793D03*
Y165393D03*
Y170493D03*
Y167993D03*
X538170Y172190D03*
X535668Y181009D03*
X529662Y181426D03*
X532873Y181366D03*
X537589Y177616D03*
X529870Y184221D03*
X532487Y184012D03*
X533906Y211359D03*
Y213859D03*
X528848Y211695D03*
X537609Y213132D03*
X526348Y208695D03*
X529148D03*
X526348Y211695D03*
X537609Y215632D03*
X537853Y256303D03*
X532525Y265701D03*
X537612Y265896D03*
X526843Y270026D03*
X529343D03*
X526843Y267526D03*
X529343D03*
X534160Y281716D03*
X540101Y281982D03*
X532659Y359557D03*
X526388Y351301D03*
X531612Y354272D03*
X531636Y349057D03*
X528812Y369164D03*
X533211Y364746D03*
X533115Y371856D03*
X530144Y376062D03*
X531953Y380749D03*
X542034Y392209D03*
X541706Y386223D03*
X533189Y390723D03*
X531953Y385749D03*
X531992Y397552D03*
X526216Y456652D03*
X528716D03*
X526216Y459152D03*
Y461652D03*
X528716Y459152D03*
Y461652D03*
X535119Y491133D03*
X531047Y498151D03*
X535119Y493633D03*
Y496133D03*
Y498633D03*
X531047Y495151D03*
X528547D03*
X528247Y498151D03*
X525288Y537877D03*
X535219Y555897D03*
Y553297D03*
X533488Y548344D03*
X525288Y540377D03*
Y545377D03*
Y542877D03*
X528488Y548344D03*
X525988D03*
X530988D03*
X535219Y561097D03*
Y563697D03*
Y566797D03*
Y558497D03*
X532009Y570478D03*
X529214Y570686D03*
X529423Y573303D03*
X532069Y573689D03*
X532426Y576484D03*
X535819Y578405D03*
X541245Y578986D03*
X524770Y597232D03*
X534820Y596782D03*
X540770Y596729D03*
X529601Y596089D03*
X526756Y613913D03*
Y616713D03*
Y619513D03*
X538826Y614158D03*
Y616958D03*
Y619758D03*
X536770Y605443D03*
X537664Y661556D03*
X534264D03*
X529664Y664056D03*
X526264D03*
X538316Y687357D03*
X535738Y687489D03*
X536087Y702364D03*
X529469Y706230D03*
X526699Y706388D03*
X535585Y736593D03*
X538985D03*
X530985Y741593D03*
X527585D03*
X524598Y753387D03*
X539449Y782389D03*
X537578Y772428D03*
X532304Y806649D03*
X531313Y812850D03*
Y826630D03*
X532316Y833649D03*
X534000Y843000D03*
X537300Y842900D03*
X530741Y845149D03*
X534632Y849830D03*
X525718Y873821D03*
X533468Y878533D03*
X538468Y888033D03*
X530968Y888283D03*
X528975Y898346D03*
X537279Y897943D03*
X533143Y897910D03*
X531076Y913190D03*
X527879Y952189D03*
X530473Y961728D03*
X528500Y1106365D03*
X529191Y1115896D03*
X525525Y1110092D03*
X529191Y1118396D03*
X528274Y1160834D03*
X554198Y68581D03*
X554211Y80581D03*
X546293Y76587D03*
Y72615D03*
X547732Y100625D03*
X540682Y106186D03*
X552105Y112083D03*
X556394Y103621D03*
X543494Y121735D03*
Y132509D03*
Y118335D03*
Y135909D03*
X548311Y141247D03*
X552798Y143518D03*
X551898Y152373D03*
X555048Y152562D03*
X540843Y168697D03*
X555850Y178560D03*
X555913Y172665D03*
X555740Y183834D03*
X541931Y191941D03*
X555260Y190185D03*
X549985Y192490D03*
X556030Y200864D03*
X548940Y206767D03*
X546440D03*
X543940D03*
X556119Y212455D03*
X556053Y207037D03*
X549070Y221708D03*
X546570D03*
X553420Y221642D03*
X545185Y231021D03*
Y228221D03*
X544070Y221708D03*
X543485Y224421D03*
X550736Y236189D03*
X548236D03*
X545736D03*
X550677Y248765D03*
X548177D03*
X545677D03*
X542628Y266114D03*
X545874Y268195D03*
X548374D03*
X551174Y270695D03*
X554834Y265897D03*
X551174Y268195D03*
X548374Y270695D03*
X545874D03*
X551536Y359223D03*
Y354723D03*
Y350223D03*
Y345723D03*
Y377223D03*
Y372723D03*
Y368223D03*
Y363723D03*
Y381723D03*
X551620Y390723D03*
X553563Y384987D03*
X544738Y581659D03*
X544770Y605443D03*
X551475Y661504D03*
X547227Y678299D03*
X547276Y675521D03*
X543101Y698772D03*
X540379Y719785D03*
X557751Y750851D03*
X549168Y781600D03*
X545768D03*
X550420Y793743D03*
X556326D03*
X540578Y793889D03*
X544515Y793875D03*
X544741Y809649D03*
X544878Y816309D03*
X546855Y829949D03*
X550087Y829836D03*
X556326Y829989D03*
X556741Y820149D03*
X544741Y823149D03*
X546241Y843149D03*
X557836Y851669D03*
X548665Y850399D03*
X540968Y878360D03*
X546940Y871389D03*
X548327Y905295D03*
X552238Y959102D03*
X552923Y988813D03*
X542793Y998507D03*
X544719Y1007522D03*
X551485Y1006648D03*
X551673Y1023900D03*
X548852Y1018307D03*
X545094Y1013678D03*
X545566Y1023731D03*
X554696Y1018469D03*
X556493Y1118351D03*
X557584Y1543411D03*
X560573Y60513D03*
X563433Y60438D03*
X557973Y55513D03*
X569114Y86012D03*
X558341Y88801D03*
X569114Y94374D03*
X561258Y94351D03*
X565207Y94279D03*
X560701Y85731D03*
X564255Y86046D03*
X564451Y116594D03*
X570394Y110784D03*
X564451Y119594D03*
X574973Y124663D03*
X564885Y124283D03*
X569951Y124879D03*
X563292Y161306D03*
X560543Y157370D03*
X564627Y176665D03*
Y168665D03*
X556726Y186629D03*
X564627Y196665D03*
Y192665D03*
X564740Y186778D03*
X564659Y204864D03*
Y208864D03*
X569708Y218085D03*
X572508D03*
X560300Y219379D03*
X560928Y228631D03*
X575035Y249108D03*
X566416Y248371D03*
X557334Y265897D03*
X573479Y374705D03*
X569938Y378317D03*
X559070Y684809D03*
Y700809D03*
Y688209D03*
X561570Y696209D03*
Y692809D03*
X559070Y716809D03*
X561570Y708809D03*
Y712209D03*
X559070Y704209D03*
Y720209D03*
X558616Y732530D03*
X562001Y732834D03*
X562374Y721593D03*
X567428Y750145D03*
X557847Y744599D03*
X563200Y739600D03*
X571493Y763090D03*
X570038Y752339D03*
X564362Y757979D03*
X560263Y782207D03*
X567126Y779066D03*
X571984Y784507D03*
X561001Y806889D03*
X567559Y803008D03*
Y824661D03*
X562400Y818900D03*
X560813Y840574D03*
X568990Y844721D03*
X572476Y845535D03*
X559295Y874267D03*
X559887Y877196D03*
X561134Y869291D03*
X559260Y891043D03*
X559214Y897425D03*
X564165Y894411D03*
X567827Y884000D03*
X562328Y957307D03*
X566303Y951807D03*
X569403D03*
X563103D03*
X570603Y957207D03*
X560923Y980443D03*
X556923Y980523D03*
X564923Y988813D03*
X560923D03*
X556923D03*
X568923D03*
X558112Y1009655D03*
X560912D03*
X567484Y1024003D03*
X571857Y1016827D03*
X559057Y1030563D03*
X562057D03*
X568057Y1030672D03*
X565057D03*
X571857Y1029427D03*
X566058Y1109564D03*
X560211D03*
X566058Y1122164D03*
X560211D03*
X566058Y1134764D03*
X560211D03*
X566058Y1147364D03*
X560211D03*
X566058Y1159964D03*
X560211D03*
X566058Y1172564D03*
X560211D03*
X566058Y1185164D03*
X560211D03*
X568532Y1200001D03*
X575620Y1207737D03*
X569135Y1214372D03*
X564890Y1218169D03*
X570796Y1530309D03*
X567324Y1528151D03*
X572432Y1521462D03*
X565400Y1535100D03*
X563968Y1541445D03*
X568279Y1538438D03*
X572507Y1541375D03*
X586037Y97667D03*
X581693Y102495D03*
X576420Y116594D03*
X575394Y110784D03*
X587837Y118342D03*
Y121742D03*
Y132515D03*
X576420Y119594D03*
X579954Y125107D03*
X587837Y135915D03*
X581427Y142862D03*
X588568Y143762D03*
X582468Y148717D03*
X576317Y138838D03*
X587516Y195176D03*
X585016D03*
X589034Y199248D03*
X587597Y210509D03*
X585097D03*
X589034Y201748D03*
X586870Y206806D03*
X576308Y216385D03*
X579021Y216970D03*
Y219470D03*
X579087Y226320D03*
X579021Y221970D03*
X586789Y230556D03*
X591044Y227824D03*
X582048Y228646D03*
X585774Y242078D03*
X581005Y232971D03*
X577655Y244571D03*
X584998Y256394D03*
X578193Y336391D03*
X584679Y336285D03*
X576556Y728219D03*
X575979Y732517D03*
X573778Y747437D03*
X577638Y769772D03*
X578271Y763556D03*
X583102Y767137D03*
X587183Y785008D03*
X578204Y775137D03*
X585912Y778470D03*
X588345Y798030D03*
X588659Y790336D03*
X582100Y787600D03*
X586060Y793145D03*
X581001Y810973D03*
X588377Y807536D03*
X588272Y804601D03*
X588231Y801520D03*
X577501Y829069D03*
X588001Y829624D03*
X582737Y819831D03*
X581158Y823473D03*
X573300Y829600D03*
X579827Y888000D03*
X580327Y892000D03*
X586136Y908935D03*
X583065Y903294D03*
X573103Y941307D03*
X585703D03*
X586103Y961807D03*
X573895Y965319D03*
X584923Y988813D03*
X576923D03*
X580923D03*
X588923D03*
X572923D03*
X577704Y1029427D03*
Y1016827D03*
X587880Y1034834D03*
X581967Y1105091D03*
X587467D03*
X582012Y1102091D03*
X587467Y1117691D03*
X581967D03*
X582012Y1127291D03*
Y1114691D03*
X587467Y1130291D03*
X581967D03*
X587467Y1142891D03*
X582012Y1139891D03*
X581967Y1155491D03*
X587467D03*
X581967Y1142891D03*
X582012Y1152491D03*
X581967Y1168091D03*
X587467D03*
X582012Y1165091D03*
X581967Y1180691D03*
X587467D03*
X582012Y1177691D03*
X586502Y1227300D03*
X583520Y1230407D03*
X581803Y1493687D03*
X578859Y1497758D03*
X588859Y1490895D03*
X590826Y1495688D03*
X588507Y1514141D03*
X582027Y1502800D03*
X581803Y1509687D03*
X577931Y1505687D03*
X575809Y1532912D03*
X572849Y1518702D03*
X587809Y1528389D03*
X583809Y1533025D03*
X579809Y1528163D03*
X587809Y1545854D03*
X583809Y1541607D03*
X577571Y1544013D03*
X594497Y103411D03*
X594891Y97667D03*
X605687Y90650D03*
X590287Y95111D03*
X595137Y111255D03*
Y114655D03*
X594656Y106561D03*
X595137Y125428D03*
Y128828D03*
X590016Y195176D03*
X592516D03*
X592034Y199248D03*
Y202048D03*
X589370Y206806D03*
X595634Y230117D03*
X591131Y246874D03*
X591650Y238714D03*
X593351Y244297D03*
X592900Y309871D03*
X605147Y378600D03*
Y382600D03*
X597776Y401513D03*
Y398113D03*
X595376Y412287D03*
Y426460D03*
Y415687D03*
Y440633D03*
Y429860D03*
X605262Y458711D03*
X595376Y444033D03*
X602462Y458711D03*
X595376Y469387D03*
Y472787D03*
X604606Y463600D03*
X595376Y483560D03*
Y486960D03*
X598462Y504684D03*
X595376Y513521D03*
Y516921D03*
Y531094D03*
Y527694D03*
X599110Y552466D03*
X605011Y603600D03*
Y619600D03*
Y623600D03*
X592272Y877262D03*
X592110Y895611D03*
X601084Y913544D03*
X604715Y914640D03*
X589203Y941407D03*
X591403Y938807D03*
Y936007D03*
X591754Y956979D03*
X597556Y965829D03*
X602484Y965764D03*
X600923Y988813D03*
X592923D03*
X604923D03*
X596923D03*
X599113Y1012354D03*
X593658Y1009354D03*
X593613Y1012354D03*
X599113Y1024954D03*
X593613D03*
X593658Y1021954D03*
X606434Y1041904D03*
X603682Y1053457D03*
X594183Y1220068D03*
X593519Y1224472D03*
X592885Y1229402D03*
X592634Y1234921D03*
X591487Y1501687D03*
X591481Y1509313D03*
X595809Y1532133D03*
X591872Y1518071D03*
X595809Y1546214D03*
X591809Y1542407D03*
X610999Y90615D03*
X615370Y95236D03*
X615320Y99961D03*
X605437Y95236D03*
X620727Y162368D03*
X614182Y210478D03*
Y215478D03*
Y212978D03*
Y207978D03*
X617511Y264180D03*
X620011D03*
X617436Y258880D03*
X605778Y391001D03*
Y405174D03*
Y394401D03*
Y408574D03*
Y422747D03*
Y419347D03*
Y433521D03*
Y436921D03*
X607789Y453682D03*
X606026Y455921D03*
X605778Y479899D03*
Y490673D03*
Y476499D03*
Y494073D03*
Y520633D03*
Y524033D03*
Y534806D03*
Y538206D03*
X609133Y941137D03*
X605733D03*
X608965Y966414D03*
X616923Y988813D03*
X608923D03*
X612923Y997860D03*
X618878Y1011914D03*
X621479Y1030482D03*
X607993Y1036920D03*
X610780Y1051037D03*
X617634Y1049283D03*
X617894Y1043955D03*
X612955Y1062941D03*
X622736Y1151870D03*
Y1159350D03*
X613738Y1546507D03*
X624234Y74793D03*
Y82593D03*
Y85193D03*
Y77393D03*
Y79993D03*
X624278Y92874D03*
X632559Y98551D03*
X635454Y114623D03*
Y111223D03*
X636109Y103783D03*
X626305Y104249D03*
Y107649D03*
X635454Y128796D03*
Y125396D03*
X630871Y147540D03*
X634643Y141247D03*
X639490Y148277D03*
X625927Y162368D03*
X623327D03*
X633027Y165393D03*
Y162793D03*
Y170493D03*
Y167993D03*
X639951Y177616D03*
X632024Y181426D03*
X635235Y181366D03*
X632232Y184221D03*
X634849Y184012D03*
X628710Y211695D03*
Y208695D03*
X631510D03*
X624638Y208213D03*
X636268Y211359D03*
Y213859D03*
X631210Y211695D03*
X624638Y213213D03*
Y210713D03*
Y215713D03*
X639974Y265896D03*
X634887Y265701D03*
X629205Y267526D03*
X626405D03*
X631705D03*
X629205Y270026D03*
X626405D03*
X631705D03*
X636522Y281716D03*
X632009Y541863D03*
Y545263D03*
X630201Y553407D03*
X632701D03*
X630201Y550907D03*
X632701D03*
X634185Y569426D03*
X634471Y566929D03*
X628425Y572070D03*
X629772Y569928D03*
X632119Y570962D03*
X631862Y568475D03*
X621592Y1033862D03*
X626476Y1155610D03*
X621727Y1556800D03*
X648655Y76587D03*
Y72615D03*
X650094Y100625D03*
X643113Y97475D03*
X643044Y106186D03*
X645856Y118335D03*
Y132509D03*
Y121735D03*
Y135909D03*
X650673Y141247D03*
X655160Y143518D03*
X642110Y143740D03*
X654260Y152373D03*
X640532Y172190D03*
X638030Y181009D03*
X643205Y168697D03*
X644293Y191941D03*
X652347Y192490D03*
X646302Y206767D03*
X651302D03*
X648802D03*
X639971Y213132D03*
X648932Y221708D03*
X647547Y228221D03*
X645847Y224421D03*
X647547Y231021D03*
X646432Y221708D03*
X651432D03*
X639971Y215632D03*
X650598Y236189D03*
X648098D03*
X653098D03*
X653039Y248765D03*
X650539D03*
X648039D03*
X640215Y256303D03*
X644990Y266114D03*
X650736Y268195D03*
X653536Y270695D03*
Y268195D03*
X650736Y270695D03*
X648236D03*
Y268195D03*
X642463Y281982D03*
X642414Y545528D03*
X651149Y577716D03*
X648211Y610400D03*
X650958Y668153D03*
X662935Y60513D03*
X665795Y60438D03*
X657507Y58013D03*
X656560Y68581D03*
X671476Y86012D03*
X656573Y80581D03*
X660703Y88801D03*
X663620Y94351D03*
X667569Y94279D03*
X663063Y85731D03*
X666617Y86046D03*
X658756Y103621D03*
X666813Y116594D03*
X654467Y112083D03*
X666813Y119594D03*
X667247Y124283D03*
X672313Y124879D03*
X665654Y161306D03*
X657410Y152562D03*
X662905Y157370D03*
X666989Y176665D03*
Y168665D03*
X658275Y172665D03*
X658212Y178560D03*
X658102Y183834D03*
X659088Y186629D03*
X657622Y190185D03*
X658392Y200864D03*
X666989Y196665D03*
Y192665D03*
X667102Y186778D03*
X667021Y204864D03*
Y208864D03*
X658481Y212455D03*
X658415Y207037D03*
X655782Y221642D03*
X662662Y219379D03*
X663290Y228631D03*
X668886Y248371D03*
X657196Y265897D03*
X659696D03*
X661761Y382109D03*
X661760Y551683D03*
Y561420D03*
Y558917D03*
X657581Y577937D03*
X660586Y606929D03*
X665086Y604567D03*
X665586Y595500D03*
X660827Y612592D03*
X666244Y610072D03*
X660546Y618400D03*
X666180Y616317D03*
X665643Y646055D03*
X658233Y646449D03*
X658064Y650119D03*
X657967Y662981D03*
X662092Y666275D03*
X659209Y691851D03*
X661018Y707592D03*
X688399Y97667D03*
X671476Y94374D03*
X678782Y116594D03*
X684055Y102495D03*
X677756Y110784D03*
X672756D03*
X678782Y119594D03*
X682316Y125107D03*
X677335Y124663D03*
X683789Y142862D03*
X684830Y148717D03*
X678679Y138838D03*
X674870Y218085D03*
X681383Y219470D03*
Y216970D03*
X678670Y216385D03*
X681383Y221970D03*
X681449Y226320D03*
X672070Y218085D03*
X684410Y228646D03*
X683367Y232971D03*
X677397Y249108D03*
X680017Y244571D03*
X682857Y339477D03*
X687055Y376456D03*
X685353Y396718D03*
X678461Y455981D03*
X675237Y465611D03*
X682586Y530000D03*
X682086Y540500D03*
X681086Y547075D03*
X681286Y549800D03*
X680586Y568000D03*
X681126Y558800D03*
X681190Y562800D03*
X696859Y103411D03*
X697253Y97667D03*
X692649Y95111D03*
X697499Y114655D03*
Y111255D03*
X697018Y106561D03*
X690199Y132515D03*
X697499Y125428D03*
Y128828D03*
X690199Y121742D03*
Y118342D03*
Y135915D03*
X690930Y143762D03*
X691396Y199248D03*
X687378Y195176D03*
X689878D03*
X694396Y199248D03*
X694878Y195176D03*
X692378D03*
X691396Y201748D03*
X689232Y206806D03*
X687459Y210509D03*
X689959D03*
X694396Y202048D03*
X691732Y206806D03*
X697996Y230117D03*
X689151Y230556D03*
X693406Y227824D03*
X694012Y238714D03*
X688136Y242078D03*
X693493Y246874D03*
X695713Y244297D03*
X690504Y253198D03*
X689486Y339583D03*
X702448Y546712D03*
Y542712D03*
X699188Y656321D03*
X702086Y678462D03*
X692478Y730641D03*
X702691Y762971D03*
Y756971D03*
X692356Y764614D03*
X691991Y759581D03*
X702677Y780659D03*
Y775159D03*
X692155Y778974D03*
X692221Y773449D03*
X690449Y814406D03*
X708049Y90650D03*
X713361Y90615D03*
X717732Y95236D03*
X717682Y99961D03*
X707799Y95236D03*
X716544Y215478D03*
Y210478D03*
Y207978D03*
Y212978D03*
X718338Y305272D03*
X712692Y356779D03*
X717105Y410964D03*
X717420Y404334D03*
X709781Y442956D03*
X720996Y442856D03*
X711598Y438323D03*
X719051Y458455D03*
X719612Y451108D03*
X710643Y456335D03*
X711764Y445873D03*
X706211Y465874D03*
X711463Y546712D03*
X704364Y618288D03*
X711328Y653821D03*
X705390Y655789D03*
X705776Y678519D03*
X713200Y699676D03*
X716623Y702463D03*
X703600Y702212D03*
X703680Y697094D03*
X715802Y706446D03*
X710196Y707562D03*
X717434Y782500D03*
X710275Y786131D03*
X713222Y793312D03*
Y790812D03*
X712901Y821600D03*
X726596Y74793D03*
Y77393D03*
Y79993D03*
Y85193D03*
Y82593D03*
X726640Y92874D03*
X734921Y98551D03*
X728667Y104249D03*
Y107649D03*
X733233Y147540D03*
X728289Y162368D03*
X725689D03*
X734386Y181426D03*
X734594Y184221D03*
X727000Y213213D03*
Y208213D03*
X733872Y208695D03*
X731072D03*
X733572Y211695D03*
X731072D03*
X727000Y210713D03*
Y215713D03*
X722373Y264180D03*
X719873D03*
X719798Y258880D03*
X737249Y265701D03*
X731567Y267526D03*
X728767D03*
X734067D03*
Y270026D03*
X731567D03*
X728767D03*
X723404Y379657D03*
X721900Y384500D03*
X723440Y391496D03*
X734661Y393633D03*
X731511Y381113D03*
X723440Y398583D03*
X732035Y442606D03*
X722097Y453881D03*
X731952Y446606D03*
X722097Y446595D03*
X732959Y463479D03*
X733430Y467367D03*
X724362Y504731D03*
X722473Y693718D03*
X723656Y705858D03*
X720985Y711658D03*
X725667Y732161D03*
X723177Y728219D03*
X721163Y738981D03*
X733000Y816000D03*
X730880Y828924D03*
X733680Y828977D03*
X732713Y853890D03*
X722600Y869600D03*
X728503Y891692D03*
X736452Y890548D03*
X728692Y886653D03*
X724707Y893143D03*
X719661Y904900D03*
X722789Y927095D03*
X722400Y942500D03*
X725194Y942073D03*
X720271Y931730D03*
X732306Y942682D03*
X728846Y948331D03*
X733798Y950186D03*
X727116Y959326D03*
X732825Y1604100D03*
X736067Y1611892D03*
X729600Y1625165D03*
X732268Y1618260D03*
X751017Y76587D03*
Y72615D03*
X752456Y100625D03*
X745475Y97475D03*
X737816Y114623D03*
Y111223D03*
X745406Y106186D03*
X738471Y103783D03*
X748218Y118335D03*
X737816Y128796D03*
X748218Y132509D03*
Y121735D03*
X737816Y125396D03*
X748218Y135909D03*
X737005Y141247D03*
X744472Y143740D03*
X741852Y148277D03*
X735389Y165393D03*
Y162793D03*
Y170493D03*
Y167993D03*
X740392Y181009D03*
X737597Y181366D03*
X745567Y168697D03*
X742894Y172190D03*
X742313Y177616D03*
X746655Y191941D03*
X737211Y184012D03*
X750667Y192300D03*
X751164Y206767D03*
X748664D03*
X738630Y213859D03*
Y211359D03*
X742333Y213132D03*
X749909Y228221D03*
Y231021D03*
X751294Y221708D03*
X748209Y224421D03*
X748794Y221708D03*
X742333Y215632D03*
X750460Y236189D03*
X750401Y248765D03*
X742577Y256303D03*
X747352Y266114D03*
X742336Y265896D03*
X750598Y268195D03*
Y270695D03*
X744825Y281982D03*
X738884Y281716D03*
X741051Y316389D03*
X749444Y393858D03*
X749606Y384410D03*
X752785Y382047D03*
X753086Y403500D03*
X751086Y398583D03*
X749539Y438269D03*
Y440869D03*
Y435669D03*
Y430469D03*
Y433069D03*
X735599Y449961D03*
X739316Y458572D03*
X750393Y451677D03*
Y454177D03*
X741992Y763480D03*
X742000Y768137D03*
X743428Y772418D03*
X741993Y775909D03*
X736000Y864266D03*
X742407Y988452D03*
X743062Y1004460D03*
X749439Y1458777D03*
X740530Y1524113D03*
X747140Y1581335D03*
X749786Y1590517D03*
X738775Y1597866D03*
X737892Y1602340D03*
X749704Y1608631D03*
X744924Y1617709D03*
X743331Y1627871D03*
X741705Y1622015D03*
X738325Y1634485D03*
X762697Y55513D03*
X758922Y68581D03*
X765297Y60513D03*
X758935Y80581D03*
X763065Y88801D03*
X765982Y94351D03*
X769931Y94279D03*
X765425Y85731D03*
X756829Y112083D03*
X761118Y103621D03*
X769609Y124283D03*
X753035Y141247D03*
X757522Y143518D03*
X756622Y152373D03*
X759772Y152562D03*
X765267Y157370D03*
X760637Y172665D03*
X760464Y183834D03*
X760574Y178560D03*
X761450Y186629D03*
X754709Y192490D03*
X759984Y190185D03*
X760754Y200864D03*
X753182Y198671D03*
X753664Y206767D03*
X769383Y208864D03*
X760843Y212455D03*
X760777Y207037D03*
X753794Y221708D03*
X758144Y221642D03*
X765024Y219379D03*
X763653Y224536D03*
X752960Y236189D03*
X755460D03*
X755401Y248765D03*
X752901D03*
X753098Y268195D03*
X755898D03*
X753098Y270695D03*
X755898D03*
X759558Y265897D03*
X762058D03*
X769349Y324518D03*
X759029Y328867D03*
X754805Y339559D03*
X759624Y353961D03*
X756086Y377912D03*
X766344D03*
X755086Y391496D03*
X756086Y386500D03*
X766344Y381912D03*
X756174Y397912D03*
X755086Y409000D03*
X766344Y397912D03*
X752339Y438269D03*
Y433069D03*
Y430469D03*
Y435669D03*
Y440869D03*
X752893Y451677D03*
Y454177D03*
X752097Y460218D03*
Y463618D03*
X755035Y1443524D03*
X765713Y1437365D03*
X760398Y1440276D03*
X755187Y1580821D03*
X759802Y1590864D03*
X763542Y1590186D03*
X768361Y1610083D03*
X762671Y1619367D03*
X756358Y1613767D03*
X768157Y60438D03*
X773838Y86012D03*
Y94374D03*
X768979Y86046D03*
X781144Y116594D03*
X769175D03*
X775118Y110784D03*
X780118D03*
X781144Y119594D03*
X769175D03*
X784678Y125107D03*
X779697Y124663D03*
X774675Y124879D03*
X781041Y138838D03*
X768016Y161306D03*
X769351Y176665D03*
Y168665D03*
Y192665D03*
X769464Y186778D03*
X769383Y204864D03*
X774432Y218085D03*
X777232D03*
X783745Y216970D03*
X781032Y216385D03*
X783745Y221970D03*
X783811Y226320D03*
X783745Y219470D03*
X782379Y244571D03*
X779759Y249108D03*
X771140Y248371D03*
X772165Y314890D03*
X784118Y303962D03*
X771941Y311740D03*
X772162Y332584D03*
X778502Y348015D03*
X772859Y347937D03*
X774419Y353470D03*
X784902Y428653D03*
X778079Y467306D03*
Y470706D03*
Y481479D03*
Y484879D03*
Y514839D03*
Y511439D03*
Y529013D03*
Y525613D03*
X775746Y539315D03*
X777708Y553287D03*
X781429Y545017D03*
X778079Y561479D03*
Y564879D03*
Y575652D03*
Y579052D03*
Y589825D03*
Y593225D03*
Y603999D03*
Y607399D03*
X778860Y626912D03*
X778205Y622912D03*
X783694Y1410977D03*
X778685Y1416198D03*
X780162Y1412848D03*
X777749Y1431432D03*
X783469Y1424655D03*
X771557Y1446818D03*
X768910Y1437741D03*
X777749Y1435432D03*
Y1439432D03*
X777260Y1446237D03*
X778428Y1455156D03*
X777725Y1450193D03*
X783620Y1460108D03*
X768812Y1453306D03*
X781124Y1583553D03*
X781110Y1595254D03*
X777059Y1608982D03*
X784046Y1600438D03*
X778045Y1619395D03*
X778358Y1627418D03*
X771383Y1616917D03*
X799221Y103411D03*
X799615Y97667D03*
X790761D03*
X795011Y95111D03*
X799861Y114655D03*
Y111255D03*
X786417Y102495D03*
X799380Y106561D03*
X792561Y132515D03*
Y118342D03*
X799861Y128828D03*
X792561Y121742D03*
X799861Y125428D03*
X792561Y135915D03*
X786151Y142862D03*
X793292Y143762D03*
X787192Y148717D03*
X796758Y199248D03*
X797240Y195176D03*
X794740D03*
X789740D03*
X792240D03*
X793758Y199248D03*
X794094Y206806D03*
X791594D03*
X789821Y210509D03*
X792321D03*
X793758Y201748D03*
X796758Y202048D03*
X800358Y230117D03*
X795768Y227824D03*
X791513Y230556D03*
X786772Y228646D03*
X796374Y238714D03*
X790498Y242078D03*
X785729Y232971D03*
X795855Y246874D03*
X798075Y244297D03*
X789722Y256394D03*
X786461Y293028D03*
X790280Y287421D03*
X800155Y337368D03*
X800029Y333368D03*
X797141Y350368D03*
X795445Y356950D03*
X789581Y405011D03*
X793893Y409502D03*
X784804Y425371D03*
X794173Y450510D03*
X802136Y448334D03*
X788481Y474418D03*
Y477818D03*
Y488591D03*
Y491991D03*
Y518552D03*
Y521952D03*
Y532725D03*
Y536125D03*
X796000Y553101D03*
X788481Y571991D03*
Y568591D03*
Y586165D03*
Y582765D03*
Y600338D03*
Y596938D03*
Y614511D03*
Y611111D03*
X788600Y1006923D03*
X799631Y1025440D03*
X795631D03*
X789050Y1026150D03*
X796338Y1138130D03*
X793842Y1143384D03*
X797160Y1146609D03*
X792277Y1173065D03*
X799020Y1175975D03*
X798353Y1172011D03*
X787887Y1174500D03*
X798542Y1188345D03*
X792382Y1191664D03*
X794533Y1195766D03*
X794983Y1334030D03*
Y1331230D03*
X793548Y1397690D03*
X795296Y1416995D03*
X792848Y1414718D03*
X793459Y1429165D03*
X789647Y1427518D03*
X788648Y1422044D03*
X785820Y1425993D03*
X798601Y1431673D03*
X793288Y1450918D03*
X793744Y1437159D03*
X786787Y1433800D03*
X787694Y1442749D03*
X800607Y1440760D03*
X790361Y1447895D03*
X790754Y1441399D03*
X793994Y1441499D03*
X799057Y1449158D03*
X797083Y1467883D03*
X799057Y1456016D03*
X794005Y1464178D03*
X790296Y1463459D03*
X787038Y1460533D03*
X786591Y1452803D03*
X790989Y1455695D03*
X799314Y1475693D03*
X797318Y1471242D03*
X810411Y90650D03*
X815723Y90615D03*
X810161Y95236D03*
X805952Y301675D03*
X817456Y305368D03*
Y313368D03*
X809490Y305368D03*
X809466Y310604D03*
X801097Y325858D03*
X817100Y319600D03*
X809457Y330459D03*
X809490Y325368D03*
Y317368D03*
X809489Y313830D03*
X809490Y321368D03*
Y333368D03*
X816177Y441442D03*
X813456Y441474D03*
X810749Y443045D03*
X815840Y444091D03*
Y456060D03*
X810453Y453330D03*
X810406Y448214D03*
X810756Y471071D03*
Y468571D03*
X814580Y468806D03*
X814828Y472053D03*
X810756Y473571D03*
Y476071D03*
X813902Y730738D03*
X813678Y740979D03*
X813653Y746856D03*
X817584Y764219D03*
X813635Y762000D03*
X818000Y797000D03*
X817845Y817879D03*
X818500Y810135D03*
X813000Y805000D03*
X813548Y814000D03*
X813009Y819734D03*
X815500Y824000D03*
X815863Y830097D03*
X814299Y840877D03*
X813887Y835146D03*
X816037Y845578D03*
X812440Y862306D03*
X814080Y864464D03*
X812575Y880834D03*
X812219Y883586D03*
X817884Y915425D03*
X803673Y1025440D03*
X803453Y1134729D03*
X814835D03*
X806835D03*
X809632Y1142666D03*
X817964Y1157404D03*
X811507Y1157544D03*
X810018Y1167768D03*
X815037D03*
X814160Y1178240D03*
X814170Y1185205D03*
X805212Y1180175D03*
X805519Y1187215D03*
X815455Y1201043D03*
X811485D03*
X807489D03*
X804452Y1199814D03*
X804458Y1193112D03*
X809027Y1219895D03*
X807020Y1217900D03*
X812302Y1223170D03*
X815149Y1226016D03*
X810148Y1374884D03*
X806148Y1383715D03*
Y1375208D03*
X810204Y1401661D03*
X804654Y1404769D03*
X812901Y1432804D03*
X815901D03*
X810059Y1432778D03*
X812104Y1426483D03*
X809986Y1438785D03*
X812986D03*
X815986D03*
X809986Y1441485D03*
X812986D03*
X815986D03*
X812901Y1435504D03*
X815901D03*
X810001D03*
X803057Y1449158D03*
X801057Y1447158D03*
X805569Y1441519D03*
X803057Y1456016D03*
X801057Y1458016D03*
X802684Y1465549D03*
X801354Y1478681D03*
X807576Y1469584D03*
X804919Y1489247D03*
X828958Y79993D03*
Y77393D03*
Y74793D03*
Y85193D03*
Y82593D03*
X829002Y92874D03*
X820094Y95236D03*
X820044Y99961D03*
X831029Y104249D03*
Y107649D03*
X830651Y162368D03*
X828051D03*
X829362Y213213D03*
X818906Y207978D03*
Y212978D03*
Y215478D03*
Y210478D03*
X829362Y208213D03*
Y210713D03*
Y215713D03*
X822235Y264180D03*
X824735D03*
X822160Y258880D03*
X831129Y267526D03*
Y270026D03*
X822477Y309368D03*
X825971Y345101D03*
X829485D03*
X822626Y348066D03*
X818840Y444091D03*
X825103Y430358D03*
Y435558D03*
Y432958D03*
X831378Y433086D03*
Y435686D03*
Y430486D03*
X818840Y456060D03*
X824650Y455034D03*
Y450034D03*
X817328Y472053D03*
X820810Y471243D03*
X817380Y468806D03*
X823544Y475061D03*
Y472561D03*
X820810Y473743D03*
X828918Y480580D03*
X831418D03*
X831057Y484036D03*
X834282Y536085D03*
X828272Y535462D03*
X827291Y533100D03*
X829496Y676793D03*
X829784Y716589D03*
Y705489D03*
X823890Y703415D03*
X823670Y710542D03*
X824387Y726246D03*
X818307Y724144D03*
X821582Y727140D03*
X826484Y747127D03*
X827500Y750000D03*
X819788Y739634D03*
X830484Y738750D03*
X824500Y760500D03*
X830075Y769000D03*
X822151Y752283D03*
X824500Y756000D03*
X817365Y756827D03*
X824500Y778500D03*
Y774000D03*
Y782500D03*
X830075Y787000D03*
X824500Y796500D03*
X824342Y792315D03*
X824500Y800500D03*
X830075Y805000D03*
X824500Y814500D03*
X830075Y823000D03*
X829946Y829788D03*
X825721Y839816D03*
X830014Y833046D03*
X829757Y842672D03*
X822608Y848526D03*
X822916Y852576D03*
X823540Y857956D03*
X831654Y864494D03*
X831583Y853454D03*
X822938Y863298D03*
X826209Y866052D03*
X823234Y870830D03*
X833194Y873561D03*
X827992Y874107D03*
X826070Y893014D03*
X817152Y896380D03*
X817139Y890330D03*
X830063Y898500D03*
X819918Y889365D03*
X823900Y882083D03*
X824804Y898395D03*
X834465Y884538D03*
X829848Y914211D03*
X818031Y907747D03*
X825336Y916774D03*
X831057Y916745D03*
X834751Y922368D03*
X823552Y930700D03*
X829617Y939583D03*
X824414Y939655D03*
X816519Y931147D03*
X824168Y949538D03*
X825670Y964671D03*
X832423Y964669D03*
X828964Y977780D03*
X830356Y1116251D03*
X827856D03*
X825335Y1137129D03*
X819449Y1134534D03*
X819026Y1128137D03*
X825744Y1150087D03*
X823220Y1170767D03*
X818879Y1187310D03*
X823309Y1180235D03*
X823516Y1185238D03*
X819489Y1201039D03*
X823489Y1200969D03*
X823608Y1208993D03*
X819419Y1230265D03*
X817360Y1228226D03*
X816648Y1380758D03*
X824901Y1427404D03*
X827901D03*
X821901D03*
X818901Y1430104D03*
X821901D03*
X830901D03*
X827901D03*
X824901D03*
Y1432804D03*
X827901D03*
X830901D03*
X821901D03*
X818901D03*
X824901Y1435504D03*
X827901D03*
X821901D03*
X818901D03*
X821986Y1441485D03*
X818986D03*
Y1438785D03*
X821986D03*
X826204Y1444689D03*
Y1440689D03*
X826341Y1451236D03*
X826365Y1458974D03*
X826219Y1455244D03*
X837283Y98551D03*
X847837Y97475D03*
X840178Y114623D03*
Y111223D03*
X840833Y103783D03*
X847768Y106186D03*
X840178Y128796D03*
Y125396D03*
X837751Y165393D03*
Y162793D03*
Y170493D03*
Y167993D03*
X842754Y181009D03*
X839959Y181366D03*
X836748Y181426D03*
X847929Y168697D03*
X844675Y177616D03*
X845256Y172190D03*
X839573Y184012D03*
X836956Y184221D03*
X836234Y208695D03*
X833434D03*
X835934Y211695D03*
X840992Y213859D03*
Y211359D03*
X833434Y211695D03*
X844695Y213132D03*
Y215632D03*
X844939Y256303D03*
X844698Y265896D03*
X839611Y265701D03*
X849714Y266114D03*
X836429Y267526D03*
X833929D03*
Y270026D03*
X836429D03*
X841246Y281716D03*
X847187Y281982D03*
X842240Y324854D03*
X848879Y360849D03*
X845435Y356172D03*
X846098Y408715D03*
X849591Y411388D03*
X842515Y461382D03*
X850732Y469382D03*
X842779Y473076D03*
X842916Y467009D03*
X833293Y490636D03*
Y487836D03*
X833918Y480580D03*
X834215Y484138D03*
X844227Y479882D03*
X842476Y482382D03*
X833269Y506683D03*
X833953Y530621D03*
X848444Y657756D03*
X837272Y663910D03*
X839636Y666533D03*
X842352Y659243D03*
X842640Y662814D03*
X838152Y700215D03*
X845784Y705489D03*
Y716589D03*
X845850Y710969D03*
X845784Y708089D03*
X836078Y709619D03*
X835987Y713745D03*
X838484Y746701D03*
X846484Y738750D03*
X836713Y738751D03*
X842661Y769521D03*
X846000Y772079D03*
X840136Y830903D03*
X836839Y831301D03*
X836894Y824401D03*
X848224Y823502D03*
X835626Y843629D03*
X838189Y843459D03*
Y847490D03*
X835215Y847719D03*
X848384Y843459D03*
X846239Y847490D03*
X835553Y835119D03*
X848384Y839459D03*
Y835459D03*
X838194Y836962D03*
X848739Y847459D03*
X837183Y855459D03*
X840234Y851459D03*
X847138Y859459D03*
X839530Y859408D03*
X848384Y863459D03*
X846336Y855459D03*
X845820Y863413D03*
X848384Y851459D03*
X843574Y859423D03*
X837434Y851459D03*
X833327Y855560D03*
X837383Y879530D03*
X837396Y871459D03*
X840234Y875459D03*
X836999Y867413D03*
X845876Y879459D03*
X848384Y867459D03*
X845820Y867413D03*
X848384Y879459D03*
Y871459D03*
Y875459D03*
X837290Y887490D03*
X842827Y895443D03*
X835346Y891346D03*
X848322Y888421D03*
X848792Y896472D03*
X836066Y894955D03*
X847098Y891213D03*
X845633Y883492D03*
X845964Y887490D03*
X837276Y883459D03*
X848200Y883400D03*
X841329Y926602D03*
X841274Y914060D03*
X843315Y916612D03*
X836909Y916618D03*
Y914018D03*
X833683Y939579D03*
X836243D03*
X833683Y949105D03*
X836243D03*
X842856Y949146D03*
X836423Y964669D03*
X835431Y977775D03*
X840935Y1011499D03*
X844058Y1011738D03*
X848045Y1019310D03*
X848070Y1022190D03*
X839744Y1444959D03*
Y1440859D03*
Y1448959D03*
X836704Y1448849D03*
Y1440849D03*
X836744Y1444849D03*
X845306Y1438269D03*
X846844Y1454334D03*
X837685Y1453196D03*
X839744Y1457959D03*
X835474Y1457397D03*
X846044Y1451459D03*
X839744Y1461959D03*
X834475Y1460059D03*
X865059Y55513D03*
X861284Y68581D03*
X861297Y80581D03*
X853379Y76587D03*
Y72615D03*
X854818Y100625D03*
X859191Y112083D03*
X863480Y103621D03*
X850580Y118335D03*
Y132509D03*
Y121735D03*
Y135909D03*
X862826Y183834D03*
X862999Y172665D03*
X862936Y178560D03*
X849017Y191941D03*
X863812Y186629D03*
X857071Y192490D03*
X862346Y190185D03*
X863116Y200864D03*
X853029Y192300D03*
X853526Y206767D03*
X856026D03*
X851026D03*
X863205Y212455D03*
X863139Y207037D03*
X860506Y221642D03*
X852271Y228221D03*
Y231021D03*
X853656Y221708D03*
X856156D03*
X850571Y224421D03*
X851156Y221708D03*
X866015Y224536D03*
X852822Y236189D03*
X855322D03*
X857822D03*
X852763Y248765D03*
X855263D03*
X857763D03*
X852960Y268195D03*
Y270695D03*
X855460D03*
X864420Y265897D03*
X858260Y268195D03*
Y270695D03*
X861920Y265897D03*
X855460Y268195D03*
X863430Y309368D03*
Y316970D03*
X863114Y324505D03*
X863040Y330140D03*
X861770Y343006D03*
X852569Y356712D03*
X856069Y356426D03*
X854086Y374500D03*
X858586D03*
X863086D03*
X860586Y383000D03*
X861235Y394000D03*
X854086Y392999D03*
X864086Y384000D03*
X855017Y411969D03*
X861413Y417071D03*
X858827Y419896D03*
X858410Y413890D03*
X858767Y416685D03*
X861622Y419688D03*
X862882Y458991D03*
X854882D03*
X862882Y461791D03*
X854882D03*
X850748Y465382D03*
X861468Y483303D03*
Y487303D03*
X858169Y495032D03*
X853989Y630453D03*
Y632953D03*
X861663Y646653D03*
X855300Y646819D03*
X853982Y657506D03*
X859441Y678015D03*
X849680Y694789D03*
X858186Y701170D03*
X855646Y692710D03*
X864029Y688970D03*
X867455Y710611D03*
X858002Y707244D03*
X857986Y722670D03*
X854484Y746701D03*
X859199Y744517D03*
X854484Y738633D03*
X859000Y756000D03*
X849500Y758500D03*
Y763500D03*
X863443Y753254D03*
X859000Y764000D03*
Y760000D03*
Y774000D03*
X849500Y776500D03*
Y781500D03*
X861425Y770500D03*
X859000Y781000D03*
Y778000D03*
X853282Y789887D03*
X857632Y789385D03*
X859000Y792000D03*
X849500Y794500D03*
Y799500D03*
X861425Y788500D03*
X859000Y800000D03*
Y796000D03*
X861425Y806500D03*
X859000Y810000D03*
X849500Y812500D03*
X859000Y814000D03*
X850496Y831469D03*
X861425Y824500D03*
X849500Y817500D03*
X859000Y818000D03*
X851184Y839459D03*
Y835459D03*
X859165Y848728D03*
X851239Y847459D03*
X851184Y843459D03*
Y863459D03*
X862114Y859479D03*
X851184Y851459D03*
X859603Y863570D03*
X859461Y859459D03*
X851184Y867459D03*
Y871459D03*
Y875459D03*
X859234Y879600D03*
X859463Y866125D03*
X851184Y879459D03*
X849267Y892567D03*
X859614Y883800D03*
Y887846D03*
X850900Y888359D03*
X850800Y883500D03*
X858988Y898307D03*
X855524Y898505D03*
X864253Y918042D03*
X856628D03*
X849600Y918028D03*
X849205Y924129D03*
X867096Y935963D03*
X858601Y934505D03*
X853030Y934690D03*
X851925Y951350D03*
X850686Y1006923D03*
X853449Y1007048D03*
X863334Y1009393D03*
X861047Y1018909D03*
X860887Y1023208D03*
Y1026762D03*
X863956Y1020763D03*
X863689Y1024974D03*
X863944Y1432359D03*
Y1429359D03*
X860944Y1432359D03*
X857944Y1429359D03*
X860944D03*
Y1426359D03*
X857944D03*
X863944D03*
X857944Y1432359D03*
X863944Y1435359D03*
Y1441359D03*
Y1438359D03*
X860944Y1441359D03*
X857944Y1435359D03*
X860944D03*
X857944Y1441359D03*
Y1438359D03*
X860944D03*
X850544Y1447559D03*
X853514Y1457510D03*
X850644Y1457359D03*
X870519Y60438D03*
X867659Y60513D03*
X876200Y86012D03*
X867787Y85731D03*
X865427Y88801D03*
X876200Y94374D03*
X872293Y94279D03*
X868344Y94351D03*
X871341Y86046D03*
X871713Y168665D03*
Y176665D03*
Y196665D03*
Y192665D03*
X871826Y186778D03*
X871745Y204864D03*
Y208864D03*
X867386Y219379D03*
X883118Y262687D03*
X876622Y293721D03*
X872050Y302644D03*
X873262Y300030D03*
X869924Y305368D03*
X879112Y302369D03*
X877977Y305368D03*
Y309368D03*
X869924Y313368D03*
X877977D03*
Y325368D03*
Y317368D03*
Y321368D03*
X869924D03*
Y328722D03*
X874005Y344917D03*
X870413Y342791D03*
X869924Y333722D03*
X877977Y333368D03*
Y329368D03*
X872158Y359962D03*
X868086Y373750D03*
X876736Y383125D03*
X877909Y391731D03*
X880736Y383125D03*
X882925Y391099D03*
X872736Y391754D03*
X867586Y393000D03*
Y385000D03*
X869342Y407627D03*
X868586Y398500D03*
X877253Y420380D03*
X876917Y415322D03*
X879417D03*
X881190Y411619D03*
X878690D03*
X874253Y422880D03*
Y420080D03*
X877253Y422880D03*
X881271Y426952D03*
X878771D03*
X873536Y437408D03*
X876036D03*
X881036D03*
X878536D03*
X873771Y426952D03*
X876271D03*
X870882Y458991D03*
X880910Y454634D03*
Y457434D03*
Y460234D03*
X870882Y461791D03*
X869454Y479303D03*
X869954Y487303D03*
X882954Y486256D03*
X882195Y539204D03*
X867093Y554703D03*
X866938Y549771D03*
X878382Y554942D03*
X874649Y545296D03*
X876949Y571419D03*
X867093Y586828D03*
Y574703D03*
X881476Y588202D03*
X881131Y577349D03*
X875290Y578703D03*
X876351Y605023D03*
Y608523D03*
X879135Y632552D03*
X872862Y666859D03*
X878881Y667156D03*
X876286Y690970D03*
X868919Y700894D03*
X876286Y694970D03*
Y698970D03*
X881157Y749148D03*
X874142Y748914D03*
X879875Y753612D03*
X873728Y752692D03*
X875473Y742056D03*
X878670Y742841D03*
X869325Y761259D03*
X870017Y757313D03*
X867000Y774000D03*
X870000Y780000D03*
X879887Y784719D03*
X880040Y792851D03*
X867000Y792000D03*
X876402Y797415D03*
X874925Y800746D03*
X870035Y801032D03*
X867000Y810000D03*
X879916Y808965D03*
X877407Y828017D03*
X877818Y824214D03*
X876475Y830372D03*
X871600Y898584D03*
X872628Y918042D03*
X876628Y915242D03*
X880628Y918042D03*
X876628D03*
X872126Y934766D03*
X865830Y961600D03*
X870209Y949384D03*
X865973Y978187D03*
X874066Y977928D03*
X875391Y993796D03*
X872183Y993980D03*
X878976Y994020D03*
X871069Y1023114D03*
X878927Y1022387D03*
X878783Y1018751D03*
X872845Y1018988D03*
X866906Y1018751D03*
X866887Y1023208D03*
X875887D03*
X878887Y1026762D03*
X872887D03*
X866887D03*
X869741Y1025895D03*
X873824Y1071604D03*
X871224D03*
X876424D03*
Y1074104D03*
X871224D03*
X873824D03*
X868624Y1071604D03*
Y1074104D03*
X870057Y1091604D03*
X875257D03*
Y1089104D03*
X870057D03*
X872657D03*
X880115Y1084666D03*
X867457Y1091604D03*
Y1089104D03*
X872657Y1091604D03*
X875375Y1107647D03*
X872675D03*
X870075D03*
X867475D03*
X871364Y1120636D03*
X873964D03*
X876564D03*
X879264D03*
X875376Y1110175D03*
X872676D03*
X870076D03*
X867476D03*
X871364Y1139336D03*
X868664D03*
X879264Y1130336D03*
X876564D03*
X873964D03*
X871364D03*
X870522Y1148080D03*
X868022D03*
X875321Y1207654D03*
X872600Y1300833D03*
Y1298333D03*
X872944Y1432359D03*
Y1429359D03*
Y1426359D03*
X869944Y1432359D03*
Y1429359D03*
Y1426359D03*
X866944Y1432359D03*
Y1429359D03*
Y1426359D03*
X872944Y1435359D03*
Y1441359D03*
Y1438359D03*
X869944Y1435359D03*
X866944D03*
X869944Y1441359D03*
Y1438359D03*
X866944Y1441359D03*
Y1438359D03*
X881244Y1448859D03*
Y1440859D03*
X878244Y1451605D03*
X881244Y1464859D03*
Y1453059D03*
Y1456859D03*
X875744Y1453573D03*
X881244Y1476859D03*
X883233Y147540D03*
X887005Y141247D03*
X894472Y143740D03*
X891852Y148277D03*
X893284Y233339D03*
Y236739D03*
X895064Y250186D03*
X891383Y243203D03*
X896034Y243307D03*
X885884Y255118D03*
X897004Y257480D03*
X892484Y260860D03*
X887148Y249670D03*
X896953Y272012D03*
X886496Y268968D03*
X895140Y265236D03*
X886059Y284644D03*
X885918Y289500D03*
X885989Y309368D03*
Y305368D03*
Y317368D03*
X885953Y325368D03*
X885989Y313368D03*
X885953Y321368D03*
Y329368D03*
Y333368D03*
X896592Y358369D03*
Y354369D03*
X888812Y357372D03*
X883552Y357276D03*
X896592Y374369D03*
X891251Y387484D03*
X890553Y392038D03*
X887266Y400158D03*
Y405158D03*
Y402658D03*
X896579Y404043D03*
X893779D03*
X889979Y405743D03*
X890903Y454634D03*
Y457434D03*
Y460234D03*
X891454Y486303D03*
X892931Y534093D03*
X885931D03*
X891449Y547363D03*
X893949D03*
X886549Y553963D03*
X885556Y543664D03*
X887417Y566713D03*
X891673Y600049D03*
X891933Y618143D03*
X895933Y609696D03*
X883309Y666608D03*
X892461Y666671D03*
X886304Y666650D03*
X884903Y696678D03*
X884911Y690279D03*
X886836Y715970D03*
X893241Y704656D03*
X883686Y729778D03*
X889525Y722060D03*
X882098Y741565D03*
X884976Y740891D03*
X884463Y744757D03*
X881637Y744154D03*
X883126Y766124D03*
X883413Y759855D03*
X892040Y784511D03*
X889763Y788159D03*
X898737Y792289D03*
X889516Y792851D03*
X891916Y799605D03*
X884002Y797616D03*
X887916Y800815D03*
X895916Y808965D03*
X883916D03*
X887916D03*
X895829Y800660D03*
X883916Y800815D03*
X890326Y828548D03*
X895050D03*
X889178Y905619D03*
X884628Y915242D03*
Y918042D03*
X896553D03*
X892628Y915242D03*
X888628D03*
Y918042D03*
X882763Y933472D03*
X891367Y941126D03*
X888400Y994579D03*
X894660Y994330D03*
X891343Y994378D03*
X885099Y1021685D03*
X881887Y1023208D03*
X888743Y1019931D03*
X895394Y1026985D03*
X893147Y1020025D03*
X893887Y1023208D03*
X887887D03*
X890887Y1026762D03*
X884887D03*
X882779Y1074104D03*
Y1071604D03*
X887979Y1074104D03*
X885379D03*
X890579D03*
Y1071604D03*
X885379D03*
X887979D03*
X882615Y1084666D03*
X887862Y1088067D03*
X894004Y1081231D03*
X892856Y1102760D03*
X894249Y1114103D03*
X891549D03*
X888949D03*
X886349D03*
Y1123803D03*
X888949D03*
X891549D03*
X894249D03*
X895275Y1132870D03*
X892575D03*
X895547Y1145169D03*
X894713Y1210419D03*
X898878Y1214182D03*
X899286Y1219469D03*
X892532Y1220112D03*
X897169Y1225259D03*
X886888Y1263058D03*
X889388D03*
X891888D03*
X889388Y1260558D03*
X886888D03*
X891888D03*
X886926Y1298712D03*
X889729Y1295516D03*
X891107Y1314305D03*
X887342Y1314990D03*
X889244Y1444859D03*
X892244Y1449636D03*
Y1440859D03*
X889944Y1457959D03*
X889244Y1460859D03*
X895244Y1457510D03*
X889336Y1452554D03*
X893919Y1462132D03*
X889244Y1472859D03*
Y1468859D03*
X903035Y141247D03*
X907522Y143518D03*
X906622Y152373D03*
X909772Y152562D03*
X899573Y158195D03*
X910977Y243307D03*
Y248032D03*
Y262205D03*
X898048Y269387D03*
X913057Y311046D03*
X915653Y307438D03*
X899352Y308560D03*
Y311960D03*
X909298Y302347D03*
X905898D03*
X898533Y334498D03*
X908521Y356708D03*
X908625Y359317D03*
X905483Y355262D03*
X905000Y362158D03*
X898869Y351114D03*
X906161Y367191D03*
X913288Y372752D03*
X910646Y376084D03*
X906344Y372524D03*
X911072Y386992D03*
X897736Y383125D03*
X901747Y398492D03*
Y403492D03*
Y400992D03*
X910250Y457262D03*
Y454462D03*
X907450D03*
Y457262D03*
X910250Y451662D03*
X907450D03*
X910250Y460062D03*
X907450D03*
X910236Y465272D03*
X910759Y475511D03*
X899931Y534093D03*
X899530Y530753D03*
X914296Y558143D03*
X913728Y550495D03*
X899407Y560019D03*
X908846Y560124D03*
X910789Y598726D03*
X898207Y599891D03*
X900676Y621536D03*
X904076D03*
X909508Y621616D03*
X912908D03*
X900753Y656925D03*
X912462Y683770D03*
X909265Y677795D03*
X912462Y687770D03*
X906886Y702285D03*
X902236Y689332D03*
Y694332D03*
X908699Y709387D03*
X913247Y714204D03*
X902841Y703665D03*
X910836Y721570D03*
X913858Y721289D03*
X907866Y795572D03*
X911028Y796598D03*
X909785Y810778D03*
X903916Y810809D03*
X913716Y811954D03*
X899916Y808965D03*
X902641Y800748D03*
X907884Y829866D03*
X908920Y905630D03*
X900628Y918042D03*
X912628Y915242D03*
X908628Y918042D03*
X900628Y915242D03*
X912628Y918042D03*
X904838D03*
X908628Y915242D03*
X900983Y940895D03*
X903759Y951358D03*
X909811Y962400D03*
X913005Y969605D03*
X912690Y994350D03*
X897825Y994413D03*
X909166Y994188D03*
X897717Y1019915D03*
X899887Y1023208D03*
Y1026762D03*
X908422Y1023103D03*
X908856Y1017677D03*
X902389Y1081764D03*
X908799Y1093659D03*
Y1088659D03*
X908278Y1083484D03*
X908799Y1096659D03*
Y1100659D03*
X902353Y1104333D03*
X898278Y1136426D03*
X898047Y1145169D03*
X903959Y1207823D03*
X906784Y1216607D03*
X913784Y1221057D03*
X910633Y1222799D03*
X906309Y1226647D03*
X909077Y1232724D03*
X899699Y1283872D03*
X910788Y1299456D03*
X906506Y1299188D03*
X902908Y1299828D03*
X911117Y1314130D03*
X902875Y1309301D03*
X905740Y1309264D03*
X908700Y1316300D03*
X911135Y1345560D03*
X904177Y1359955D03*
X899944Y1432359D03*
X908944Y1426359D03*
Y1429359D03*
Y1432359D03*
X911944Y1426359D03*
Y1429359D03*
Y1432359D03*
X905944Y1426359D03*
X899944D03*
X902944D03*
Y1429359D03*
X899944D03*
X902944Y1432359D03*
X905944Y1429359D03*
Y1432359D03*
X902944Y1438359D03*
X899944D03*
Y1441359D03*
X902944Y1435359D03*
X899944D03*
X908944Y1438359D03*
Y1441359D03*
X911944Y1438359D03*
Y1441359D03*
X902944D03*
X905944Y1438359D03*
Y1441359D03*
X908944Y1435359D03*
X911944D03*
X905944D03*
X919175Y116594D03*
X930118Y110784D03*
X925118D03*
X919175Y119594D03*
X924675Y124879D03*
X929697Y124663D03*
X919609Y124283D03*
X931041Y138838D03*
X918016Y161306D03*
X915267Y157370D03*
X916453Y167975D03*
X927898Y203256D03*
X925098D03*
X919577Y240945D03*
Y250394D03*
Y271654D03*
X919616Y268462D03*
X919577Y264567D03*
X923732Y304585D03*
X917882Y328216D03*
Y324816D03*
X915954Y344150D03*
X916229Y336333D03*
X919354Y344150D03*
X919629Y336333D03*
X927964Y344041D03*
X924564D03*
X923311Y349959D03*
X929943Y372600D03*
X921343Y376888D03*
X916330Y377748D03*
X929947Y376821D03*
X915072Y386992D03*
X914323Y398551D03*
Y403551D03*
Y401051D03*
X927563Y424445D03*
X924763D03*
X921963D03*
X927280Y436716D03*
X921680D03*
X924480D03*
X917541Y441280D03*
Y443780D03*
X927766Y456442D03*
X927596Y447453D03*
X921973Y469328D03*
X927401Y469059D03*
X916593Y469140D03*
X928999Y477948D03*
X920999D03*
X924999D03*
X917811Y544325D03*
X923453Y569578D03*
X923642Y561578D03*
X919080Y587640D03*
X921507Y578791D03*
X919038Y579378D03*
X923599Y581578D03*
X921217Y589216D03*
X913998Y597103D03*
X925949Y612363D03*
Y608863D03*
X922626Y633772D03*
X915800Y629700D03*
X918300D03*
X929690Y666593D03*
X920090Y666714D03*
X928353Y686342D03*
X928704Y680261D03*
X921061Y715386D03*
X926961Y723797D03*
X914202Y797460D03*
X923872Y798271D03*
X922352Y800809D03*
X917803Y811365D03*
X927916Y800909D03*
X929790Y828603D03*
X927916Y817015D03*
X925228Y816934D03*
X929181Y895029D03*
X921451Y903800D03*
X920628Y918042D03*
X916628D03*
X924628D03*
X928628D03*
X924628Y915242D03*
X920628D03*
X928628D03*
X916628D03*
X914193Y945318D03*
X928227Y951125D03*
X921364Y951251D03*
X918265Y969745D03*
X923289Y965780D03*
X926796Y966297D03*
X929741Y967006D03*
X916932Y994405D03*
X924956Y994321D03*
X924864Y1026762D03*
Y1023208D03*
X925024Y1018909D03*
X927861Y1024768D03*
X916749Y1084659D03*
X916992Y1076659D03*
X916749Y1092664D03*
X916875Y1098643D03*
X916749Y1104659D03*
X914637Y1210568D03*
Y1214838D03*
X930754Y1310564D03*
X924650Y1327819D03*
Y1324419D03*
X914033Y1345613D03*
X927193Y1361547D03*
X931159Y1379427D03*
X920360Y1387039D03*
X920255Y1383264D03*
X931199Y1371951D03*
X931159Y1390827D03*
Y1406027D03*
X914944Y1426359D03*
Y1429359D03*
Y1432359D03*
Y1438359D03*
Y1441359D03*
Y1435359D03*
X921498Y1446692D03*
X925697Y1460109D03*
X917744Y1453573D03*
X920244Y1451605D03*
X919285Y1456226D03*
X924803Y1474743D03*
X925435Y1478114D03*
X940761Y97667D03*
X945011Y95111D03*
X931144Y116594D03*
X936417Y102495D03*
X931144Y119594D03*
X942561Y118342D03*
Y132515D03*
Y121742D03*
X934678Y125107D03*
X942561Y135915D03*
X936151Y142862D03*
X943292Y143762D03*
X937192Y148717D03*
X945406Y180347D03*
X940406D03*
X942906D03*
X947424Y184419D03*
X944424Y186919D03*
X944760Y191977D03*
X942260D03*
X940487Y195680D03*
X942987D03*
X944424Y184419D03*
X934411Y202141D03*
X931698Y201556D03*
X934411Y207141D03*
X934477Y211491D03*
X934411Y204641D03*
X946234Y213390D03*
X942179Y215727D03*
X937438Y213817D03*
X936395Y218142D03*
X933403Y245507D03*
X936962Y249807D03*
X944248Y239844D03*
X945018Y276051D03*
X943183Y281652D03*
X930727Y302571D03*
X937000Y312284D03*
Y315684D03*
X942731Y324044D03*
X939331D03*
X940997Y331912D03*
Y335312D03*
X942700Y346363D03*
X939300D03*
X934128Y355168D03*
X934464Y358618D03*
X944238Y360828D03*
X934047Y369160D03*
X936175Y364823D03*
X931072Y386992D03*
X941872Y440942D03*
X933424Y458455D03*
X933161Y451442D03*
X933404Y463462D03*
X933412Y468942D03*
X936653Y526836D03*
X944351Y534211D03*
X948532Y541135D03*
X939992Y527726D03*
Y548726D03*
Y544726D03*
X948598Y546553D03*
X948621Y552726D03*
X931627Y557641D03*
Y569578D03*
Y581578D03*
Y577578D03*
Y573578D03*
X933725Y585936D03*
X933741Y598087D03*
Y594687D03*
X933725Y589336D03*
X944296Y611071D03*
X941859Y621311D03*
Y629311D03*
X943181Y632536D03*
X945434Y634325D03*
X941859Y625311D03*
X946128Y666522D03*
X935281Y680945D03*
X936026Y727450D03*
X933974Y719371D03*
X942676Y789286D03*
X933201Y798297D03*
X946970Y786366D03*
X944916Y808965D03*
X938357Y808856D03*
X931916Y817015D03*
X942858Y819430D03*
X945736Y819397D03*
X935124Y831382D03*
X940100Y830700D03*
X935262Y825135D03*
X932418D03*
X940716Y840074D03*
X944297Y839975D03*
X933021Y840893D03*
X933054Y843804D03*
X937200Y841000D03*
X936450Y858327D03*
X937551Y860801D03*
X932770Y878233D03*
X935765Y878317D03*
X934928Y871727D03*
X932319Y871626D03*
X938729Y874396D03*
X932300Y890200D03*
X942194Y891216D03*
X930800Y904840D03*
X941592Y900908D03*
X936628Y915242D03*
X940628D03*
X932628D03*
X936628Y918042D03*
X932628D03*
X936371Y951484D03*
X940716Y951733D03*
X946363Y951179D03*
X935255Y962725D03*
X945671Y982191D03*
X940015Y1020176D03*
X934911Y1023579D03*
X945864Y1023208D03*
X930864Y1026762D03*
X936864D03*
X942864D03*
X939864Y1023208D03*
X930864D03*
X930883Y1018751D03*
X936822Y1018988D03*
X942760Y1018751D03*
X943093Y1021769D03*
X932289Y1074182D03*
Y1071682D03*
X937489Y1074182D03*
X934889D03*
X940089D03*
Y1071682D03*
X934889D03*
X937489D03*
X944092Y1084666D03*
X931628Y1091409D03*
Y1088909D03*
X936828Y1091409D03*
X934228D03*
X939428D03*
Y1088909D03*
X934228D03*
X936828D03*
X943241Y1120636D03*
X940541D03*
X937941D03*
X935341D03*
X937941Y1130336D03*
X940541D03*
X943241D03*
X932641Y1139336D03*
X935341Y1130336D03*
Y1139336D03*
X934500Y1147708D03*
X932000D03*
X939298Y1207654D03*
X943891Y1306608D03*
X944207Y1320739D03*
X947308Y1325035D03*
X931137Y1375878D03*
X931159Y1383227D03*
X939559Y1398427D03*
X931159Y1394627D03*
Y1387027D03*
Y1398427D03*
Y1402227D03*
X939559D03*
X944235Y1406262D03*
X943725Y1430744D03*
Y1427744D03*
X934725Y1430744D03*
X940725Y1427744D03*
Y1430744D03*
X934725Y1427744D03*
X937725D03*
Y1430744D03*
X943725Y1433744D03*
Y1439744D03*
Y1436744D03*
X940725Y1433744D03*
Y1439744D03*
Y1436744D03*
X934725Y1433744D03*
X937725D03*
X934725Y1439744D03*
X937725D03*
X934725Y1436744D03*
X937725D03*
X937671Y1492139D03*
Y1488139D03*
X949221Y103411D03*
X949615Y97667D03*
X960411Y90650D03*
X960161Y95236D03*
X949861Y111255D03*
Y114655D03*
X949380Y106561D03*
X949861Y125428D03*
Y128828D03*
X947906Y180347D03*
X947424Y187219D03*
X950177Y215730D03*
X947040Y223885D03*
X948741Y229468D03*
X948785Y242464D03*
X951278Y250583D03*
X946482Y255940D03*
X949974Y291554D03*
X947733Y319680D03*
X950953Y317947D03*
X960376Y392807D03*
X962769Y451419D03*
X959816Y472905D03*
X955816Y473419D03*
Y464919D03*
X963816Y464419D03*
X962563Y485128D03*
X954182Y481467D03*
X958124Y492354D03*
X958736Y482165D03*
X958974Y504825D03*
X956474D03*
X953974D03*
X949823Y491982D03*
X959600Y496486D03*
X949823Y495982D03*
X957977Y500202D03*
X958915Y517401D03*
X956415D03*
X953915D03*
X959466Y522569D03*
Y525369D03*
X958081Y531882D03*
X955581D03*
X961166Y529169D03*
X952531Y531948D03*
X960581Y531882D03*
X948905Y534909D03*
X958016Y555194D03*
X960816D03*
X958016Y563194D03*
X960816D03*
Y571194D03*
X958016D03*
X959573Y581222D03*
X962373D03*
X959573Y591215D03*
X962373D03*
X962545Y607762D03*
X959745D03*
Y610562D03*
X962545D03*
X950479Y622285D03*
X954535Y610548D03*
X950667Y616905D03*
X963365Y628078D03*
X961352Y633736D03*
X950865Y633724D03*
X950748Y627713D03*
X956345Y633716D03*
X949137Y666660D03*
X954526Y666671D03*
X947556Y699550D03*
X956023Y706907D03*
X951151Y730111D03*
X963869Y725057D03*
X955950Y734178D03*
X957763Y725336D03*
X959950Y734178D03*
X957579Y744168D03*
X953837Y763025D03*
X950699Y779711D03*
X956017Y770300D03*
X957500Y780800D03*
X955076Y784861D03*
X950475Y789361D03*
X955225Y788984D03*
X949609Y796051D03*
X957487Y798553D03*
X951461Y812223D03*
X951791Y808121D03*
X957379Y826586D03*
X954760Y826734D03*
X951708Y818894D03*
X955712Y833988D03*
X956239Y829577D03*
X960100Y846665D03*
X954700Y837700D03*
X961175Y838525D03*
X955343Y866850D03*
X955850Y862902D03*
X957900Y856300D03*
X950300Y877800D03*
X953240Y876834D03*
X954567Y927654D03*
X964280Y927777D03*
X958567Y927654D03*
X947029Y915242D03*
X959545Y918306D03*
X951863Y936168D03*
X957235Y936398D03*
X962329Y936229D03*
X957671Y977921D03*
X949671D03*
X961671Y991564D03*
X953671D03*
X949671D03*
X953671Y982191D03*
X954937Y1021998D03*
X948864Y1026762D03*
X954864D03*
X951864Y1023208D03*
X957864D03*
X957678Y1018555D03*
X961208Y1018592D03*
X960636Y1021917D03*
X959371Y1026985D03*
X948975Y1021325D03*
X951956Y1071604D03*
X949356D03*
X954556D03*
Y1074104D03*
X949356D03*
X951956D03*
X946756Y1071604D03*
Y1074104D03*
X946592Y1084666D03*
X957981Y1081231D03*
X951839Y1088067D03*
X956833Y1102760D03*
X950326Y1114103D03*
Y1123803D03*
X952926D03*
X955526D03*
Y1114103D03*
X958226D03*
X952926D03*
X958226Y1123803D03*
X956552Y1132870D03*
X959252D03*
X962255Y1136426D03*
X962024Y1145169D03*
X959524D03*
X958690Y1210419D03*
X963263Y1219469D03*
X962855Y1214182D03*
X956509Y1220112D03*
X961146Y1225259D03*
X950865Y1263058D03*
X953365D03*
X955865D03*
X953365Y1260558D03*
X950865D03*
X955865D03*
X948259Y1295965D03*
X948832Y1371654D03*
X951832D03*
X952561Y1383465D03*
X952417Y1379528D03*
X949469D03*
X949385Y1375591D03*
X952385D03*
X952514Y1391339D03*
X952395Y1395276D03*
X952716Y1387402D03*
X952180Y1407087D03*
X950239Y1409555D03*
X948235Y1406262D03*
X946725Y1427744D03*
Y1430744D03*
X949725D03*
Y1427744D03*
X960883Y1427997D03*
Y1430997D03*
X946725Y1433744D03*
X949725D03*
X946725Y1439744D03*
X949725D03*
X946725Y1436744D03*
X949725D03*
X960883Y1433997D03*
Y1436997D03*
Y1439997D03*
X952695Y1444139D03*
X979002Y92874D03*
X965723Y90615D03*
X970094Y95236D03*
X970044Y99961D03*
X978051Y162368D03*
X968906Y207978D03*
Y212978D03*
Y215478D03*
Y210478D03*
X970865Y264068D03*
X973365D03*
X972160Y258880D03*
X977150Y331972D03*
Y338972D03*
X975631Y343112D03*
Y346612D03*
X971721Y407762D03*
X968348Y402369D03*
X971826Y430187D03*
X966694Y427599D03*
X968462Y429368D03*
X970840Y457339D03*
X968340D03*
X962816Y442919D03*
X972030Y446071D03*
X979910Y445603D03*
X970840Y459839D03*
Y462339D03*
X968340D03*
Y459839D03*
X963816Y472905D03*
X976397Y473045D03*
X972397Y465004D03*
X977327Y462371D03*
X965412Y485138D03*
X969297Y478625D03*
Y475825D03*
X970997Y482425D03*
X970412Y485138D03*
X967912D03*
X976873Y491214D03*
Y493714D03*
X970745Y539731D03*
X967042Y537658D03*
X970745Y542231D03*
X978303Y541895D03*
X975803D03*
X967042Y540458D03*
X975503Y544895D03*
X978303D03*
X978581Y582747D03*
X965173Y581222D03*
X978032Y590801D03*
X965173Y591215D03*
X977857Y597130D03*
X976027Y620653D03*
Y617853D03*
X968145Y610562D03*
X965345Y607762D03*
Y610562D03*
X968145Y607762D03*
X977857Y605443D03*
X973857D03*
X972354Y627908D03*
X968365Y633473D03*
X978865Y642184D03*
X966797Y667653D03*
X970197D03*
X965774Y706907D03*
X973712Y722064D03*
X968589Y722434D03*
X970839Y729923D03*
X965042Y722234D03*
X971081Y722637D03*
X978352Y730766D03*
X963950Y734178D03*
X973450Y747280D03*
X965983Y763567D03*
X966127Y776382D03*
X968094Y799792D03*
X976186Y789819D03*
X967562Y802982D03*
X978978Y817618D03*
X978214Y821224D03*
X967337Y828901D03*
X970040Y842903D03*
X969309Y839334D03*
X974437Y849140D03*
X973510Y834991D03*
X967842Y864801D03*
X970299Y853773D03*
X978880Y869552D03*
X967510Y868971D03*
X966813Y904556D03*
X973988Y910038D03*
X968507Y937615D03*
X971443Y938828D03*
X965671Y991564D03*
Y982191D03*
X963864Y1026762D03*
Y1023208D03*
X966366Y1081764D03*
X972776Y1093659D03*
X972255Y1083484D03*
X972776Y1088659D03*
Y1096659D03*
X966330Y1104333D03*
X972776Y1100659D03*
X967936Y1207823D03*
X978614Y1210568D03*
X970761Y1216607D03*
X978614Y1214838D03*
X978169Y1221268D03*
X974985Y1290950D03*
X979996Y1386100D03*
X963883Y1430997D03*
Y1427997D03*
X966883Y1430997D03*
Y1427997D03*
X969883D03*
Y1430997D03*
X975883Y1427997D03*
Y1430997D03*
X972883D03*
Y1427997D03*
X963883Y1433997D03*
X966883D03*
X969883D03*
X963883Y1436997D03*
Y1439997D03*
X966883Y1436997D03*
Y1439997D03*
X969883Y1436997D03*
Y1439997D03*
X975883Y1433997D03*
X972883D03*
X975883Y1436997D03*
X972883D03*
X975883Y1439997D03*
X972883D03*
X977547Y1546081D03*
X974547D03*
X971547D03*
X978958Y85193D03*
Y82593D03*
Y77393D03*
Y74793D03*
Y79993D03*
X987283Y98551D03*
X990178Y114623D03*
Y111223D03*
X990833Y103783D03*
X981029Y104249D03*
Y107649D03*
X990178Y128796D03*
Y125396D03*
X985595Y147540D03*
X989367Y141247D03*
X996834Y143740D03*
X994214Y148277D03*
X980651Y162368D03*
X987751Y162793D03*
Y165393D03*
Y167993D03*
Y170493D03*
X995256Y172190D03*
X994675Y177616D03*
X989959Y181366D03*
X986748Y181426D03*
X992754Y181009D03*
X986956Y184221D03*
X989573Y184012D03*
X994695Y213132D03*
X979362Y208213D03*
Y210713D03*
Y213213D03*
X986234Y208695D03*
X983434D03*
X985934Y211695D03*
X990992Y213859D03*
Y211359D03*
X983434Y211695D03*
X979362Y215713D03*
X994695Y215632D03*
X994939Y256303D03*
X989611Y265701D03*
X994698Y265896D03*
X986429Y270026D03*
X983929D03*
X981129D03*
X983929Y267526D03*
X986429D03*
X981129D03*
X991246Y281716D03*
X997187Y281982D03*
X987517Y314092D03*
X993552Y318175D03*
X990420Y340454D03*
Y337954D03*
X989630Y343862D03*
X983717Y341665D03*
X983956Y346652D03*
X993026Y353813D03*
X981719Y352217D03*
X988631Y349496D03*
X980045Y366559D03*
X986373Y370467D03*
X991392Y409230D03*
X985303Y464652D03*
Y462152D03*
Y459652D03*
X987803Y464652D03*
Y462152D03*
Y459652D03*
X981843Y464818D03*
X992206Y491133D03*
Y498633D03*
X988134Y495151D03*
X985634D03*
X980576Y492987D03*
X985334Y498151D03*
X980576Y495487D03*
X988134Y498151D03*
X992206Y493633D03*
Y496133D03*
X982375Y537877D03*
X992306Y555897D03*
Y553297D03*
X989888Y548366D03*
X987388D03*
X982388D03*
X984888D03*
X982375Y542877D03*
Y545377D03*
Y540377D03*
X992306Y561097D03*
Y563697D03*
Y566797D03*
Y558497D03*
X986301Y570686D03*
X989096Y570478D03*
X989513Y576484D03*
X989156Y573689D03*
X986510Y573303D03*
X992906Y578405D03*
X981857Y597232D03*
X991907Y596782D03*
X986688Y596089D03*
X983843Y619513D03*
Y616713D03*
Y613913D03*
X993857Y605443D03*
X981857Y605637D03*
X980703Y625013D03*
X986600Y717641D03*
X987461Y745796D03*
X981876Y745179D03*
X988371Y764143D03*
X983786Y765647D03*
X984357Y777555D03*
X997051Y778833D03*
X990699Y778630D03*
X987990Y774005D03*
X987394Y787490D03*
X987501Y812573D03*
X985921Y805135D03*
X994051Y810871D03*
X996385Y816141D03*
X979203Y829159D03*
X994094Y829000D03*
X982300Y821200D03*
X987702Y829159D03*
X989700Y846500D03*
X987202Y846395D03*
X987319Y843589D03*
X979203Y833159D03*
X989800Y843900D03*
X987200Y848940D03*
X987703Y837159D03*
X990457Y852043D03*
X983269Y853883D03*
X981700Y856300D03*
X979891Y876589D03*
X992441Y870398D03*
X988054Y888283D03*
X990300Y897500D03*
X979592Y902849D03*
X982783Y909995D03*
X979498Y907500D03*
X989311Y920364D03*
X983227Y968565D03*
X988240Y1020015D03*
Y1016923D03*
Y1023968D03*
X984909Y1081071D03*
X983751Y1078675D03*
X980969Y1076659D03*
X980726Y1084659D03*
X980852Y1098643D03*
X980726Y1104659D03*
Y1092664D03*
X986645Y1108465D03*
X989513Y1097683D03*
X995009Y1131223D03*
X991763Y1140378D03*
Y1128378D03*
Y1134378D03*
X984558Y1140774D03*
X988112Y1137774D03*
X984558Y1128774D03*
Y1134774D03*
X987804Y1131619D03*
X984817Y1303297D03*
X979001Y1288925D03*
X990613Y1324248D03*
Y1327048D03*
X993413Y1324248D03*
Y1327048D03*
X990501Y1320756D03*
X988784Y1361974D03*
X980139Y1381496D03*
X980166Y1373622D03*
X980203Y1377559D03*
X980047Y1397245D03*
X985448Y1398271D03*
X980092Y1389370D03*
X980139Y1393308D03*
X984136Y1401636D03*
X987136D03*
X986949Y1430997D03*
Y1427997D03*
X983949D03*
X989949Y1430997D03*
Y1427997D03*
X983949Y1430997D03*
X992949Y1427997D03*
Y1430997D03*
X986949Y1433997D03*
X983949D03*
X989949D03*
X992949D03*
X986949Y1436997D03*
X983949D03*
X986949Y1439997D03*
X983949D03*
X989949Y1436997D03*
Y1439997D03*
X992949Y1436997D03*
Y1439997D03*
X978934Y1444392D03*
X978987Y1489832D03*
X982241Y1489637D03*
X986773Y1546081D03*
X983773D03*
X980773D03*
X1011284Y68581D03*
X1011297Y80581D03*
X1003379Y72615D03*
Y76587D03*
X1004818Y100625D03*
X997837Y97475D03*
X1013480Y103621D03*
X997768Y106186D03*
X1009191Y112083D03*
X1000580Y121735D03*
Y118335D03*
Y132509D03*
Y135909D03*
X1005397Y141247D03*
X1009884Y143518D03*
X1008984Y152373D03*
X1012936Y178560D03*
X997929Y168697D03*
X1012826Y183834D03*
X1012999Y172665D03*
X999017Y191941D03*
X1003029Y192300D03*
X1012346Y190185D03*
X1007071Y192490D03*
X1013116Y200864D03*
X1003526Y206767D03*
X1006026D03*
X1001026D03*
X1010291Y199582D03*
X1013139Y207037D03*
X1013205Y212455D03*
X1002271Y228221D03*
Y231021D03*
X1010506Y221642D03*
X1003656Y221708D03*
X1006156D03*
X1000571Y224421D03*
X1001156Y221708D03*
X1002822Y236189D03*
X1005322D03*
X1007822D03*
X1002763Y248765D03*
X1005263D03*
X1007763D03*
X999714Y266114D03*
X1008260Y268195D03*
X1005460D03*
X1002960D03*
X1008260Y270695D03*
X1002960D03*
X1005460D03*
X1000698Y300276D03*
X1002580Y309619D03*
X1010499Y309062D03*
X1003181Y323057D03*
X1001105Y318006D03*
X1009770Y344486D03*
X997020Y345354D03*
X1003076Y332496D03*
X1000420Y353954D03*
X996024Y352132D03*
X1001825Y581659D03*
X998332Y578986D03*
X997857Y596729D03*
X995913Y619758D03*
Y616958D03*
Y614158D03*
X1001857Y605443D03*
X1003900Y628700D03*
X1001605Y627605D03*
X1005800Y637600D03*
X1002883Y622521D03*
X1001676Y678015D03*
X1011185Y724519D03*
X1009562Y722438D03*
X1003990Y765899D03*
X1007990D03*
X1002751Y757169D03*
X999990Y764566D03*
X1013151Y756726D03*
X1012695Y776728D03*
X999990Y774671D03*
X1013319Y785929D03*
X1007027Y792973D03*
X998376Y810970D03*
X1006054Y810969D03*
X1010699Y803454D03*
X1002699Y819475D03*
X1011144Y844340D03*
X1010977Y841737D03*
X1012703Y837659D03*
X1001187Y850084D03*
X1004577Y853679D03*
X1004713Y871389D03*
X998313Y888295D03*
X1005413Y905295D03*
X1004953Y923995D03*
X1008935Y924007D03*
X1004994Y955372D03*
X1007919Y948822D03*
X1011019D03*
X1004719D03*
X1012219Y954222D03*
X1006222Y980337D03*
X1009564Y988874D03*
X999879Y998507D03*
X1001805Y1007522D03*
X1008571Y1006648D03*
X1008759Y1023900D03*
X1002180Y1013678D03*
X1002652Y1023731D03*
X1005938Y1018307D03*
X995317Y1137378D03*
X996213Y1324248D03*
Y1327048D03*
X1009333Y1346693D03*
Y1343293D03*
X998600Y1369200D03*
X1008387Y1380797D03*
X998600Y1373400D03*
X997401Y1381200D03*
X999283Y1377400D03*
X1007850Y1368835D03*
X998643Y1398271D03*
X1008138Y1407186D03*
Y1409986D03*
X1005338Y1407186D03*
Y1409986D03*
X1008138Y1415586D03*
Y1412786D03*
X1005338Y1415586D03*
Y1412786D03*
X1008138Y1418386D03*
X1005338D03*
X998949Y1427997D03*
Y1430997D03*
X995949D03*
Y1427997D03*
X1009981Y1431097D03*
Y1428097D03*
X1006981D03*
Y1431097D03*
X998949Y1433997D03*
X995949D03*
X998949Y1436997D03*
X995949D03*
X998949Y1439997D03*
X995949D03*
X1009981Y1434097D03*
X1006981D03*
X1009981Y1437097D03*
X1006981D03*
X1009981Y1440097D03*
X1006981D03*
X1002194Y1444392D03*
X1015059Y55513D03*
X1020519Y60438D03*
X1017659Y60513D03*
X1026200Y86012D03*
X1017787Y85731D03*
X1026200Y94374D03*
X1015427Y88801D03*
X1022293Y94279D03*
X1018344Y94351D03*
X1021341Y86046D03*
X1021537Y116594D03*
X1027480Y110784D03*
X1021537Y119594D03*
X1021971Y124283D03*
X1027037Y124879D03*
X1020378Y161306D03*
X1012134Y152562D03*
X1017629Y157370D03*
X1021713Y176665D03*
Y168665D03*
X1013812Y186629D03*
X1021713Y196665D03*
X1021826Y186778D03*
X1021713Y192665D03*
X1021745Y204864D03*
Y208864D03*
X1026794Y218085D03*
X1017386Y219379D03*
X1018014Y228631D03*
X1023502Y248371D03*
X1014420Y265897D03*
X1011920D03*
X1027216Y289440D03*
X1022604Y290262D03*
X1016635Y300276D03*
X1012635D03*
X1025749D03*
X1020635D03*
X1022435Y312865D03*
X1021848Y310396D03*
X1020406Y350772D03*
X1012188Y443421D03*
X1015659Y679654D03*
Y683054D03*
X1021885Y698974D03*
X1022937Y691421D03*
X1014641Y724436D03*
X1012851Y722417D03*
X1026916Y719769D03*
X1018015Y751565D03*
X1013486Y750773D03*
X1024684Y756485D03*
X1017664Y779101D03*
X1014064Y793660D03*
X1018071Y798490D03*
X1013821Y813520D03*
X1014781Y810319D03*
X1017955Y812097D03*
X1021895Y818974D03*
X1020703Y837659D03*
X1013918Y851306D03*
X1017800Y867065D03*
X1016973Y877196D03*
X1016574Y874537D03*
X1016798Y890299D03*
X1021408Y895008D03*
X1024913Y884000D03*
X1012842Y910685D03*
X1022346Y917669D03*
X1029570Y917718D03*
X1018419Y917575D03*
X1014719Y938322D03*
X1027319D03*
X1027719Y958822D03*
X1014009Y980356D03*
X1018009D03*
X1014009Y988813D03*
X1018009D03*
X1021924Y980456D03*
X1026009Y988813D03*
X1022009D03*
X1017998Y1009655D03*
X1015198D03*
X1024570Y1024003D03*
X1011782Y1016591D03*
X1022143Y1030672D03*
X1019143D03*
X1016143D03*
X1025143D03*
X1023144Y1109564D03*
X1017297D03*
X1023144Y1122164D03*
X1017297D03*
X1023144Y1134764D03*
X1017297D03*
X1023144Y1147364D03*
X1017297D03*
X1023144Y1159964D03*
X1017297D03*
Y1172564D03*
X1023162Y1174445D03*
X1023139Y1184856D03*
X1017297Y1185164D03*
X1026221Y1214372D03*
X1021976Y1218169D03*
X1023358Y1363921D03*
X1013991Y1360842D03*
X1019391Y1377061D03*
X1012981Y1431097D03*
Y1428097D03*
X1015981D03*
Y1431097D03*
X1021981Y1428097D03*
Y1431097D03*
X1018981D03*
Y1428097D03*
X1012981Y1434097D03*
X1015981D03*
X1012981Y1437097D03*
Y1440097D03*
X1015981Y1437097D03*
Y1440097D03*
X1021981Y1434097D03*
X1018981D03*
X1021981Y1437097D03*
X1018981D03*
X1021981Y1440097D03*
X1018981D03*
X1025615Y1444492D03*
X1020023Y1489637D03*
X1016769Y1489832D03*
X1043123Y97667D03*
X1033506Y116594D03*
X1038779Y102495D03*
X1032480Y110784D03*
X1033506Y119594D03*
X1037040Y125107D03*
X1032059Y124663D03*
X1038513Y142862D03*
X1045654Y143762D03*
X1039554Y148717D03*
X1033403Y138838D03*
X1042102Y195176D03*
X1042183Y210509D03*
X1029594Y218085D03*
X1036107Y221970D03*
X1036173Y226320D03*
X1036107Y219470D03*
Y216970D03*
X1033394Y216385D03*
X1043875Y230556D03*
X1039134Y228646D03*
X1042860Y242078D03*
X1038091Y232971D03*
X1034741Y244571D03*
X1032121Y249108D03*
X1042084Y256394D03*
X1037290Y296293D03*
X1033890D03*
X1045650Y300093D03*
X1029639Y300141D03*
X1041783Y321114D03*
X1030220Y313554D03*
X1042948Y333696D03*
X1043106Y340230D03*
X1031259Y350427D03*
X1029885Y711762D03*
X1033200Y731700D03*
X1035619Y755809D03*
X1038344Y756476D03*
X1043016Y782161D03*
X1038678Y776750D03*
X1039251Y812340D03*
X1042414Y801443D03*
X1043425Y830800D03*
X1043626Y836563D03*
X1041100Y838500D03*
X1037527Y836486D03*
X1031813Y850273D03*
X1046045Y841217D03*
X1040822Y841339D03*
X1044390Y861210D03*
X1035185Y862793D03*
X1037685Y862789D03*
X1038363Y875288D03*
X1037709Y886209D03*
X1038010Y902565D03*
X1033019Y933022D03*
Y935822D03*
X1030819Y938422D03*
X1033370Y953994D03*
X1038009Y988813D03*
X1030009D03*
X1042009D03*
X1034009D03*
X1028943Y1016827D03*
X1034790D03*
X1028943Y1029427D03*
X1034790D03*
X1039499Y1098758D03*
X1039053Y1105091D03*
X1044553D03*
X1039098Y1102091D03*
X1039053Y1117691D03*
X1044553D03*
X1039098Y1114691D03*
Y1127291D03*
X1039053Y1130291D03*
X1044553D03*
Y1142891D03*
X1039098Y1139891D03*
X1039053Y1142891D03*
Y1155491D03*
X1044553D03*
X1039098Y1152491D03*
X1044553Y1168091D03*
X1039053D03*
X1039098Y1165091D03*
X1044553Y1180691D03*
X1039053D03*
X1039098Y1177691D03*
X1032831Y1207950D03*
X1029797Y1220921D03*
X1040606Y1230407D03*
X1043588Y1227300D03*
X1032867Y1431213D03*
Y1428213D03*
X1029867D03*
X1035867Y1431213D03*
Y1428213D03*
X1029867Y1431213D03*
X1038867Y1428213D03*
Y1431213D03*
X1041867D03*
Y1428213D03*
X1032867Y1434213D03*
X1029867D03*
X1035867D03*
X1038867D03*
X1032867Y1437213D03*
X1029867D03*
X1032867Y1440213D03*
X1029867D03*
X1035867Y1437213D03*
Y1440213D03*
X1038867Y1437213D03*
Y1440213D03*
X1041867Y1434213D03*
Y1437213D03*
Y1440213D03*
X1051583Y103411D03*
X1051977Y97667D03*
X1047373Y95111D03*
X1052223Y111255D03*
Y114655D03*
X1051742Y106561D03*
X1044923Y118342D03*
X1052223Y125428D03*
Y128828D03*
X1044923Y132515D03*
Y121742D03*
Y135915D03*
X1047102Y195176D03*
X1046120Y199248D03*
X1044602Y195176D03*
X1049120Y199248D03*
X1049602Y195176D03*
X1046120Y201748D03*
X1049120Y202048D03*
X1044683Y210509D03*
X1046456Y206806D03*
X1043956D03*
X1052720Y230117D03*
X1048130Y227824D03*
X1048736Y238714D03*
X1048217Y246874D03*
X1050437Y244297D03*
X1045364Y279895D03*
X1051796Y279965D03*
X1050164Y302748D03*
X1050076Y305512D03*
X1061387Y343509D03*
X1060679Y356151D03*
X1054863Y401513D03*
Y398113D03*
X1052463Y412287D03*
Y415687D03*
Y426460D03*
Y440633D03*
Y429860D03*
Y444033D03*
X1059549Y458711D03*
X1052463Y469387D03*
Y472787D03*
Y486960D03*
Y483560D03*
Y513521D03*
Y516921D03*
Y531094D03*
Y527694D03*
X1055885Y554555D03*
X1046068Y792742D03*
X1046930Y796557D03*
X1048314Y833102D03*
X1053392Y832788D03*
X1051550Y823146D03*
X1055700Y840900D03*
X1053913Y837718D03*
X1050358Y837793D03*
X1052500Y841200D03*
X1049087Y856033D03*
X1053909Y855472D03*
X1045300Y872352D03*
X1054900Y879321D03*
X1058155Y887635D03*
X1050295Y891100D03*
X1054009Y988813D03*
X1046009D03*
X1050009D03*
X1058009D03*
X1056199Y1012354D03*
X1050744Y1009354D03*
X1056199Y1024954D03*
X1050699D03*
Y1012354D03*
X1050744Y1021954D03*
X1046485Y1034538D03*
X1057212Y1040356D03*
X1049930Y1221407D03*
X1050605Y1224472D03*
X1049770Y1229402D03*
X1049720Y1234921D03*
X1052660Y1293257D03*
X1050002Y1293283D03*
X1049204Y1337377D03*
X1049670Y1347462D03*
X1046075Y1350650D03*
X1049493Y1350694D03*
X1044867Y1428213D03*
Y1431213D03*
Y1434213D03*
Y1437213D03*
Y1440213D03*
X1048403Y1444608D03*
X1062773Y90650D03*
X1068085Y90615D03*
X1072456Y95236D03*
X1072406Y99961D03*
X1062523Y95236D03*
X1071268Y207978D03*
Y212978D03*
Y215478D03*
Y210478D03*
X1074597Y264180D03*
X1074522Y258880D03*
X1076571Y310574D03*
X1060679Y368276D03*
X1062865Y391001D03*
X1062234Y378600D03*
Y382600D03*
X1062865Y408574D03*
Y405174D03*
Y394401D03*
Y422747D03*
Y419347D03*
Y436921D03*
Y433521D03*
X1062349Y458711D03*
X1064876Y453682D03*
X1063113Y455921D03*
X1061693Y463600D03*
X1062865Y476499D03*
Y479899D03*
Y490673D03*
Y494073D03*
Y520633D03*
Y524033D03*
Y534806D03*
Y538206D03*
X1062098Y603600D03*
X1061342Y610269D03*
X1061496Y612786D03*
X1062098Y619600D03*
X1063642Y634190D03*
X1062098Y623600D03*
X1066931Y645389D03*
X1060698Y931619D03*
X1069685Y933391D03*
X1066878Y931909D03*
X1070009Y988813D03*
X1069607Y980131D03*
X1066009Y980330D03*
X1062009Y988813D03*
X1065823Y988773D03*
X1074009Y988813D03*
X1070009Y997860D03*
X1073525Y1012428D03*
X1076110Y1029535D03*
X1065079Y1036920D03*
X1076577Y1041332D03*
X1074232Y1055836D03*
X1067866Y1051037D03*
X1060768Y1053457D03*
X1074650Y1070006D03*
X1069642Y1445541D03*
X1068861Y1451311D03*
X1081320Y85193D03*
Y82593D03*
Y79993D03*
Y77393D03*
Y74793D03*
X1089645Y98551D03*
X1081364Y92874D03*
X1092540Y111223D03*
Y114623D03*
X1083391Y104249D03*
Y107649D03*
X1092540Y128796D03*
Y125396D03*
X1087957Y147540D03*
X1091729Y141247D03*
X1083013Y162368D03*
X1090113Y165393D03*
Y162793D03*
X1080413Y162368D03*
X1090113Y170493D03*
Y167993D03*
X1092321Y181366D03*
X1089110Y181426D03*
X1091935Y184012D03*
X1089318Y184221D03*
X1081724Y208213D03*
X1085796Y208695D03*
Y211695D03*
X1081724Y210713D03*
Y213213D03*
X1088596Y208695D03*
X1088296Y211695D03*
X1081724Y215713D03*
X1077097Y264180D03*
X1091973Y265701D03*
X1083491Y267526D03*
X1088791D03*
X1086291D03*
X1083491Y270026D03*
X1086291D03*
X1088791D03*
X1093608Y281716D03*
X1080351Y328256D03*
X1079748Y322743D03*
Y319343D03*
X1080351Y331656D03*
X1082297Y340770D03*
X1092554Y340318D03*
X1085615Y339815D03*
X1092561Y353374D03*
X1082787Y348501D03*
X1091031Y374810D03*
X1089788Y550907D03*
X1087288D03*
X1089788Y553407D03*
X1087288D03*
X1089096Y541863D03*
Y545263D03*
X1091558Y566929D03*
X1091272Y569426D03*
X1088949Y568475D03*
X1089206Y570962D03*
X1086859Y569928D03*
X1085512Y572070D03*
X1078920Y856700D03*
X1090375Y899047D03*
X1076800Y1012900D03*
X1078755Y1031518D03*
X1079178Y1037884D03*
X1076868Y1047293D03*
X1079910Y1045264D03*
X1079822Y1151870D03*
X1083562Y1155610D03*
X1079822Y1159350D03*
X1083283Y1526583D03*
X1084000Y1529600D03*
X1091529Y1528718D03*
X1091525Y1546300D03*
X1090876Y1554183D03*
X1091569Y1561300D03*
X1092527Y1579422D03*
X1086469Y1588435D03*
X1090469D03*
X1083900Y1593206D03*
X1082176Y1600598D03*
X1090904Y1599047D03*
X1088021Y1606949D03*
X1093778Y1599574D03*
X1086904Y1599004D03*
X1090093Y1628297D03*
X1085474Y1629028D03*
X1089474Y1638213D03*
X1105741Y76587D03*
Y72615D03*
X1100199Y97475D03*
X1107180Y100625D03*
X1100130Y106186D03*
X1093195Y103783D03*
X1102942Y118335D03*
Y132509D03*
Y121735D03*
Y135909D03*
X1107759Y141247D03*
X1099196Y143740D03*
X1096576Y148277D03*
X1095116Y181009D03*
X1100291Y168697D03*
X1097618Y172190D03*
X1109903Y171523D03*
X1097037Y177616D03*
X1101379Y191941D03*
X1109433Y192490D03*
X1105888Y206767D03*
X1108388D03*
X1103388D03*
X1093354Y213859D03*
Y211359D03*
X1097057Y213132D03*
X1104633Y228221D03*
X1106018Y221708D03*
X1108518D03*
X1102933Y224421D03*
X1103518Y221708D03*
X1104633Y231021D03*
X1097057Y215632D03*
X1105184Y236189D03*
X1107684D03*
X1105125Y248765D03*
X1107625D03*
X1097301Y256303D03*
X1102076Y266114D03*
X1097060Y265896D03*
X1107822Y268195D03*
X1105322D03*
Y270695D03*
X1107822D03*
X1099549Y281982D03*
X1093478Y310305D03*
X1108779Y327705D03*
X1103432Y340544D03*
X1097976Y340477D03*
X1105012Y353504D03*
X1098845Y353404D03*
X1093841Y371335D03*
X1099501Y545528D03*
X1108236Y577716D03*
X1105298Y610400D03*
X1108045Y668153D03*
X1092769Y936975D03*
X1095080Y1513398D03*
X1096780Y1526700D03*
X1101402Y1531702D03*
X1095250Y1531600D03*
X1098617Y1546183D03*
X1096780Y1535400D03*
X1100876Y1554183D03*
X1099371Y1561153D03*
X1100476Y1579318D03*
X1102904Y1566668D03*
X1093682Y1582433D03*
X1098498Y1590435D03*
X1104233Y1587983D03*
X1100233Y1588000D03*
X1107620Y1603602D03*
X1098904Y1602138D03*
X1101946Y1614709D03*
X1096941Y1627905D03*
X1105474Y1629450D03*
X1101474Y1637820D03*
X1093474Y1638213D03*
X1105474Y1638426D03*
X1097474Y1637753D03*
X1114781Y58013D03*
X1113646Y68581D03*
X1120021Y60513D03*
X1122881Y60438D03*
X1113659Y80581D03*
X1120149Y85731D03*
X1117789Y88801D03*
X1123703Y86046D03*
X1120706Y94351D03*
X1124655Y94279D03*
X1115842Y103621D03*
X1123899Y116594D03*
X1111553Y112083D03*
X1123899Y119594D03*
X1124333Y124283D03*
X1112246Y143518D03*
X1111346Y152373D03*
X1122740Y161306D03*
X1114496Y152562D03*
X1119991Y157370D03*
X1124075Y168665D03*
Y176665D03*
X1115188Y183834D03*
X1115298Y178560D03*
X1115361Y172665D03*
X1116174Y186629D03*
X1124075Y192665D03*
Y196665D03*
X1115478Y200864D03*
X1114708Y190185D03*
X1124188Y186778D03*
X1124107Y204864D03*
X1115501Y207037D03*
X1115567Y212455D03*
X1124107Y208864D03*
X1112868Y221642D03*
X1119748Y219379D03*
X1120376Y228631D03*
X1110184Y236189D03*
X1110125Y248765D03*
X1116782Y265897D03*
X1114282D03*
X1110622Y268195D03*
Y270695D03*
X1115000Y329000D03*
Y334000D03*
Y339000D03*
X1118848Y382109D03*
X1118847Y551683D03*
Y561420D03*
Y558917D03*
X1122705Y588515D03*
X1114668Y577937D03*
X1117673Y606929D03*
X1122673Y595500D03*
X1122173Y604567D03*
X1122705Y591015D03*
X1123331Y610072D03*
X1123267Y616317D03*
X1117633Y618400D03*
X1117914Y612592D03*
X1115151Y650119D03*
X1115320Y646449D03*
X1115054Y662981D03*
X1116296Y691851D03*
X1111785Y686971D03*
X1118105Y707592D03*
X1128562Y86012D03*
Y94374D03*
X1135868Y116594D03*
X1141141Y102495D03*
X1129842Y110784D03*
X1134842D03*
X1135868Y119594D03*
X1139402Y125107D03*
X1129399Y124879D03*
X1134421Y124663D03*
X1140875Y142862D03*
X1141916Y148717D03*
X1135765Y138838D03*
X1129156Y218085D03*
X1131956D03*
X1138469Y221970D03*
X1138535Y226320D03*
X1138469Y219470D03*
Y216970D03*
X1135756Y216385D03*
X1141496Y228646D03*
X1140453Y232971D03*
X1137103Y244571D03*
X1134483Y249108D03*
X1125864Y248371D03*
X1137830Y336230D03*
X1135548Y455804D03*
X1134629Y465551D03*
X1126622Y506256D03*
X1139673Y530000D03*
X1139173Y540500D03*
X1138373Y549800D03*
X1138173Y547075D03*
X1137673Y568000D03*
X1138213Y558800D03*
X1138277Y562800D03*
X1129471Y732571D03*
X1153945Y103411D03*
X1145485Y97667D03*
X1154339D03*
X1149735Y95111D03*
X1154585Y114655D03*
Y111255D03*
X1154104Y106561D03*
X1154585Y128828D03*
X1147285Y118342D03*
Y121742D03*
Y132515D03*
X1154585Y125428D03*
X1147285Y135915D03*
X1148016Y143762D03*
X1149464Y195176D03*
X1148482Y199248D03*
X1151482D03*
X1144464Y195176D03*
X1146964D03*
X1151964D03*
X1151482Y202048D03*
X1146318Y206806D03*
X1144545Y210509D03*
X1147045D03*
X1148818Y206806D03*
X1148482Y201748D03*
X1146237Y230556D03*
X1155082Y230117D03*
X1150492Y227824D03*
X1151098Y238714D03*
X1145222Y242078D03*
X1150579Y246874D03*
X1152799Y244297D03*
X1147590Y253198D03*
X1145587Y339148D03*
X1142440Y396718D03*
X1157451Y618288D03*
X1156275Y656321D03*
X1155146Y699491D03*
X1152512Y728543D03*
X1148962Y747253D03*
X1152485Y764552D03*
X1147468Y766093D03*
X1154652Y791056D03*
X1145910Y803642D03*
X1153485Y813142D03*
X1154985Y802897D03*
X1153229Y848581D03*
X1170447Y90615D03*
X1165135Y90650D03*
X1174768Y99961D03*
X1164885Y95236D03*
X1173630Y207978D03*
Y210478D03*
Y212978D03*
Y215478D03*
X1173559Y304948D03*
X1171445Y422088D03*
X1166868Y442956D03*
X1168685Y438323D03*
X1168398Y456309D03*
X1168851Y445873D03*
X1163298Y465874D03*
X1159535Y546712D03*
Y542712D03*
X1165400Y553300D03*
X1167900D03*
X1161451Y618288D03*
X1160275Y656321D03*
X1164275D03*
X1162863Y678519D03*
X1159173Y678462D03*
X1170465Y677836D03*
X1157646Y699491D03*
X1162646D03*
X1160146D03*
X1169256Y694983D03*
X1163774Y713347D03*
X1166115Y718469D03*
X1171934Y733857D03*
X1173034Y765060D03*
X1169697Y791935D03*
X1164925Y791607D03*
X1164732Y802269D03*
X1173122Y802759D03*
X1163579Y850774D03*
X1161535Y844167D03*
X1159887Y869106D03*
X1174461Y914515D03*
X1183682Y85193D03*
Y82593D03*
Y74793D03*
Y79993D03*
Y77393D03*
X1183726Y92874D03*
X1174818Y95236D03*
X1185753Y107649D03*
Y104249D03*
X1182775Y162368D03*
X1185375D03*
X1188158Y211695D03*
X1184086Y210713D03*
Y213213D03*
Y208213D03*
X1190958Y208695D03*
X1188158D03*
X1184086Y215713D03*
X1176959Y264180D03*
X1179459D03*
X1177035Y257919D03*
X1185853Y267526D03*
X1188653D03*
X1185853Y270026D03*
X1188653D03*
X1179901Y306366D03*
X1181706Y310131D03*
X1178045Y312193D03*
X1181379Y316049D03*
X1174929Y319167D03*
X1179761Y336380D03*
X1187996Y331992D03*
X1191748Y392676D03*
X1188598Y381500D03*
X1178083Y442856D03*
X1189122Y442606D03*
X1176699Y451108D03*
X1176138Y458455D03*
X1179184Y453881D03*
Y446595D03*
X1188739Y446606D03*
X1190046Y463479D03*
X1174595Y771744D03*
X1176500Y784933D03*
X1185516Y844248D03*
X1190968Y848703D03*
X1184340Y851072D03*
X1183012Y856553D03*
X1190213Y856816D03*
X1187431Y868340D03*
X1180239Y868430D03*
X1179858Y883455D03*
X1179727Y886197D03*
X1181654Y894671D03*
X1185058Y883475D03*
X1187151Y921000D03*
X1182000Y936500D03*
X1189219Y940703D03*
X1192007Y98551D03*
X1202561Y97475D03*
X1194902Y114623D03*
Y111223D03*
X1195557Y103783D03*
X1202492Y106186D03*
X1205304Y118335D03*
Y121735D03*
X1194902Y128796D03*
X1205304Y132509D03*
X1194902Y125396D03*
X1205304Y135909D03*
X1190319Y147540D03*
X1194091Y141247D03*
X1201558Y143740D03*
X1198938Y148277D03*
X1192475Y165393D03*
Y162793D03*
Y167993D03*
Y170493D03*
X1199980Y172190D03*
X1194683Y181366D03*
X1191472Y181426D03*
X1197478Y181009D03*
X1202653Y168697D03*
X1199399Y177616D03*
X1203741Y191941D03*
X1194297Y184012D03*
X1191680Y184221D03*
X1205750Y206767D03*
X1195716Y211359D03*
Y213859D03*
X1199419Y213132D03*
X1190658Y211695D03*
X1205295Y224421D03*
X1205880Y221708D03*
X1199419Y215632D03*
X1199663Y256303D03*
X1199422Y265896D03*
X1204438Y266114D03*
X1194335Y265701D03*
X1191153Y267526D03*
Y270026D03*
X1201911Y281982D03*
X1195970Y281716D03*
X1201113Y315039D03*
X1190127Y324142D03*
X1195800Y324000D03*
X1206531Y393858D03*
X1208173Y398583D03*
X1192702Y440489D03*
X1192957Y435158D03*
X1193000Y444841D03*
X1192686Y449961D03*
X1196403Y458572D03*
X1192431Y868620D03*
X1192152Y884399D03*
X1192367Y903785D03*
X1190210Y900909D03*
X1191151Y936296D03*
X1193219Y940703D03*
X1197173Y940645D03*
X1196352Y951033D03*
X1191219Y967757D03*
X1191928Y987314D03*
X1198644Y985289D03*
X1195757Y988131D03*
X1203419Y1011161D03*
X1200008D03*
X1196300Y998600D03*
X1202028Y998349D03*
X1199700Y1013661D03*
X1201800Y1019431D03*
X1219783Y55513D03*
X1216008Y68581D03*
X1222383Y60513D03*
X1216021Y80581D03*
X1208103Y72615D03*
Y76587D03*
X1222511Y85731D03*
X1220151Y88801D03*
X1218204Y103621D03*
X1209542Y100625D03*
X1213915Y112083D03*
X1210121Y141247D03*
X1214608Y143518D03*
X1213708Y152373D03*
X1216858Y152562D03*
X1222353Y157370D03*
X1217550Y183834D03*
X1212265Y171523D03*
X1217723Y172665D03*
X1217660Y178560D03*
X1218536Y186629D03*
X1211795Y192490D03*
X1210268Y198671D03*
X1217840Y200864D03*
X1217070Y190185D03*
X1207753Y192300D03*
X1208250Y206767D03*
X1210750D03*
X1217863Y207037D03*
X1217929Y212455D03*
X1215230Y221642D03*
X1206995Y228221D03*
X1208380Y221708D03*
X1210880D03*
X1206995Y231021D03*
X1222110Y219379D03*
X1222738Y228631D03*
X1207546Y236189D03*
X1210046D03*
X1212546D03*
X1207487Y248765D03*
X1209987D03*
X1212487D03*
X1219144Y265897D03*
X1216644D03*
X1212984Y268195D03*
X1210184D03*
X1207684D03*
X1212984Y270695D03*
X1207684D03*
X1210184D03*
X1220723Y324466D03*
X1211892Y339559D03*
X1215776Y331072D03*
X1213173Y377912D03*
X1217177Y369925D03*
X1206693Y384410D03*
X1213173Y386500D03*
X1209872Y382047D03*
X1212173Y391496D03*
X1213261Y397912D03*
X1210173Y403500D03*
X1212173Y409000D03*
X1209426Y433069D03*
Y430469D03*
Y435669D03*
Y440869D03*
Y438269D03*
X1206626Y433069D03*
Y430469D03*
Y435669D03*
Y440869D03*
Y438269D03*
X1209980Y451677D03*
X1207480Y454177D03*
X1209980D03*
X1207480Y451677D03*
X1209184Y463618D03*
Y460218D03*
X1225243Y60438D03*
X1230924Y86012D03*
Y94374D03*
X1226065Y86046D03*
X1227017Y94279D03*
X1223068Y94351D03*
X1238230Y116594D03*
X1226261D03*
X1232204Y110784D03*
X1237204D03*
X1238230Y119594D03*
X1226261D03*
X1236783Y124663D03*
X1226695Y124283D03*
X1231761Y124879D03*
X1238127Y138838D03*
X1225102Y161306D03*
X1226437Y176665D03*
Y168665D03*
Y192665D03*
X1226550Y186778D03*
X1226469Y204864D03*
Y208864D03*
X1231518Y218085D03*
X1234318D03*
X1238118Y216385D03*
X1239465Y244571D03*
X1236845Y249108D03*
X1228226Y248371D03*
X1229252Y314890D03*
X1229028Y311740D03*
X1226436Y324518D03*
X1229922Y324550D03*
X1234904Y316942D03*
X1232197Y316964D03*
X1238293Y317296D03*
X1229438Y332584D03*
X1235589Y348015D03*
X1229942Y347937D03*
X1231506Y353470D03*
X1223431Y377912D03*
X1225755Y369391D03*
X1229122Y369355D03*
X1222601Y369251D03*
X1223431Y381912D03*
Y397912D03*
X1235166Y470706D03*
Y467306D03*
Y484879D03*
Y481479D03*
Y514839D03*
Y511439D03*
Y529013D03*
Y525613D03*
X1232833Y539315D03*
X1232149Y550137D03*
X1234941D03*
X1235166Y564879D03*
Y561479D03*
Y575652D03*
Y579052D03*
Y593225D03*
Y603999D03*
Y589825D03*
Y607399D03*
X1235930Y626229D03*
X1235292Y622912D03*
X1237500Y632405D03*
X1238034Y629961D03*
X1238695Y627313D03*
X1256307Y103411D03*
X1247847Y97667D03*
X1256701D03*
X1252097Y95111D03*
X1243503Y102495D03*
X1249647Y118342D03*
Y132515D03*
Y121742D03*
X1241764Y125107D03*
X1249647Y135915D03*
X1243237Y142862D03*
X1250378Y143762D03*
X1244278Y148717D03*
X1251826Y195176D03*
X1254326D03*
X1253844Y199248D03*
X1249326Y195176D03*
X1250844Y199248D03*
X1246826Y195176D03*
X1249407Y210509D03*
X1253844Y202048D03*
X1250844Y201748D03*
X1251180Y206806D03*
X1248680D03*
X1246907Y210509D03*
X1240831Y221970D03*
X1240897Y226320D03*
X1240831Y219470D03*
Y216970D03*
X1248599Y230556D03*
X1252854Y227824D03*
X1243858Y228646D03*
X1253460Y238714D03*
X1247584Y242078D03*
X1252941Y246874D03*
X1242815Y232971D03*
X1246808Y256394D03*
X1241205Y303962D03*
X1253245Y416888D03*
Y419488D03*
Y422088D03*
X1245568Y474418D03*
Y488591D03*
Y477818D03*
Y491991D03*
Y521952D03*
Y518552D03*
Y536125D03*
Y532725D03*
X1253087Y553101D03*
X1241629Y550065D03*
X1245568Y568591D03*
Y571991D03*
Y582765D03*
Y586165D03*
Y596938D03*
Y600338D03*
Y611111D03*
Y614511D03*
X1248106Y1004700D03*
X1245400Y1003700D03*
X1246000Y1014800D03*
X1252148Y1026223D03*
X1252500Y1014288D03*
X1246300Y1027800D03*
X1253424Y1138130D03*
X1250928Y1142828D03*
X1254200Y1146600D03*
X1249363Y1173065D03*
X1256218Y1175987D03*
X1249363Y1166065D03*
X1255439Y1172008D03*
X1255628Y1188345D03*
X1253056Y1194917D03*
X1254275Y1531334D03*
X1249894Y1527805D03*
X1253904Y1519645D03*
X1254275Y1539334D03*
X1250434Y1535334D03*
X1267497Y90650D03*
X1267247Y95236D03*
X1256947Y114655D03*
Y111255D03*
X1256466Y106561D03*
X1256947Y128828D03*
Y125428D03*
X1257444Y230117D03*
X1255161Y244297D03*
X1266962Y302167D03*
X1262665Y302730D03*
X1263328Y309003D03*
X1262075Y324075D03*
X1261659Y318258D03*
X1264088Y320382D03*
X1266616Y322456D03*
X1257000Y333500D03*
X1264215Y333215D03*
X1262500Y330655D03*
X1256000Y338000D03*
X1259991Y340691D03*
X1256000Y340500D03*
X1263500Y336000D03*
X1264659Y377173D03*
X1267944Y371767D03*
X1261764Y391533D03*
X1263484Y385644D03*
X1268659Y385123D03*
X1268067Y406060D03*
X1261231Y399918D03*
X1264336Y412106D03*
X1268328Y421489D03*
Y418889D03*
Y416289D03*
X1270397Y447081D03*
X1259223Y454334D03*
X1267540Y459330D03*
X1267493Y454214D03*
X1267836Y449045D03*
X1267843Y473571D03*
Y481071D03*
Y478571D03*
Y476071D03*
X1269629Y848124D03*
X1270892Y856343D03*
X1271121Y892513D03*
X1270276Y897062D03*
X1269221Y894760D03*
X1270586Y905324D03*
X1272661Y929858D03*
X1260539Y1134729D03*
X1267921D03*
X1266718Y1142666D03*
X1263921Y1134729D03*
X1268593Y1157544D03*
X1267104Y1167768D03*
X1272123D03*
X1271246Y1178240D03*
X1271256Y1185205D03*
X1262605Y1187215D03*
X1262298Y1180175D03*
X1260800Y1191096D03*
X1268571Y1201043D03*
X1264575D03*
X1261538Y1199814D03*
X1255296Y1196056D03*
X1263449Y1217228D03*
X1266113Y1219895D03*
X1269388Y1223170D03*
X1267333Y1531334D03*
X1262891Y1527334D03*
X1267183Y1539334D03*
X1262891Y1535334D03*
X1286044Y85539D03*
Y82939D03*
Y75139D03*
Y80339D03*
Y77739D03*
X1286088Y92874D03*
X1272809Y90615D03*
X1277130Y99961D03*
X1277180Y95236D03*
X1285137Y162368D03*
X1275992Y215478D03*
Y212978D03*
Y210478D03*
Y207978D03*
X1286448Y213213D03*
Y210713D03*
Y208213D03*
Y215713D03*
X1281821Y264180D03*
X1279321D03*
X1279246Y258880D03*
X1271571Y281185D03*
X1289345Y330655D03*
X1284419Y359377D03*
X1287437Y379429D03*
X1280699Y377173D03*
X1284659D03*
X1274436Y377350D03*
X1276659Y385123D03*
X1273659D03*
X1280659D03*
X1284333Y391569D03*
X1282760Y401066D03*
X1272421Y403300D03*
X1271828Y405889D03*
Y408489D03*
Y413689D03*
Y411089D03*
Y416289D03*
Y421489D03*
Y418889D03*
Y424089D03*
X1272215Y432718D03*
Y435518D03*
X1282092Y442118D03*
Y439318D03*
X1271828Y426689D03*
X1272927Y450091D03*
X1275927D03*
X1273397Y447081D03*
X1281737Y461034D03*
Y456034D03*
X1272927Y462060D03*
X1275927D03*
X1286005Y485580D03*
X1280631Y480194D03*
Y477694D03*
X1277897Y478876D03*
Y476376D03*
X1274415Y477053D03*
X1271915D03*
X1284900Y678800D03*
X1283400Y715500D03*
X1278255Y722241D03*
X1283400Y719700D03*
X1282539Y746076D03*
X1279539Y748576D03*
X1282539Y751076D03*
X1279539Y763576D03*
X1282539Y766076D03*
X1279539Y758576D03*
X1282539Y756076D03*
Y761076D03*
X1279539Y753576D03*
Y768576D03*
Y780576D03*
Y784576D03*
X1285092Y819500D03*
X1285500Y827500D03*
X1281388Y827388D03*
X1281777Y823500D03*
X1285500Y843500D03*
X1281331Y843331D03*
X1281269Y835492D03*
X1285500Y835500D03*
X1283025Y848305D03*
X1271438Y861846D03*
X1285500Y863500D03*
Y859500D03*
Y855500D03*
Y851500D03*
X1279460Y854487D03*
Y859487D03*
Y864487D03*
X1274396Y866896D03*
X1285500Y867500D03*
X1279460Y874487D03*
Y869487D03*
Y879487D03*
X1285302Y877283D03*
X1282285Y865602D03*
X1274264Y898591D03*
X1279460Y884487D03*
X1285302Y885783D03*
X1279299Y898813D03*
X1279460Y889487D03*
X1285302Y881783D03*
X1281075Y911075D03*
X1282184Y898854D03*
X1274400Y914123D03*
X1283494Y907176D03*
X1275493Y929858D03*
X1279493D03*
X1283493D03*
X1279693Y919800D03*
X1274670Y919808D03*
X1281400Y940256D03*
X1289547Y941000D03*
X1281733Y949475D03*
X1275788Y1124088D03*
X1282421Y1137129D03*
X1271921Y1134729D03*
X1275794D03*
X1282830Y1150087D03*
X1275050Y1157404D03*
X1280306Y1170767D03*
X1275965Y1187232D03*
X1280602Y1185238D03*
X1280395Y1180235D03*
X1272541Y1201043D03*
X1276575Y1201039D03*
X1280575Y1200969D03*
X1280694Y1208993D03*
X1274446Y1228226D03*
X1272235Y1226016D03*
X1297687Y-33656D03*
Y-30256D03*
X1297785Y33768D03*
X1302139Y26325D03*
X1302785Y31168D03*
X1294369Y98551D03*
X1304923Y97475D03*
X1297264Y114623D03*
Y111223D03*
X1297919Y103783D03*
X1288115Y104249D03*
Y107649D03*
X1297264Y128796D03*
Y125396D03*
X1294837Y162793D03*
X1287737Y162368D03*
X1294837Y165393D03*
Y167993D03*
Y170493D03*
X1301761Y177616D03*
X1302342Y172190D03*
X1299840Y181009D03*
X1293834Y181426D03*
X1297045Y181366D03*
X1294042Y184221D03*
X1296659Y184012D03*
X1301781Y213132D03*
X1298078Y211359D03*
Y213859D03*
X1290520Y211695D03*
X1293020D03*
X1290520Y208695D03*
X1293320D03*
X1301781Y215632D03*
X1302025Y256303D03*
X1296697Y265701D03*
X1301784Y265896D03*
X1293515Y270026D03*
X1291015D03*
X1288215D03*
Y267526D03*
X1293515D03*
X1291015D03*
X1304273Y281982D03*
X1298332Y281716D03*
X1294000Y324000D03*
X1303000Y326692D03*
X1293000Y338500D03*
X1303000Y331000D03*
X1302896Y343797D03*
Y340397D03*
X1292500Y335000D03*
X1299959Y356954D03*
X1294080Y349820D03*
X1291410Y371060D03*
X1295410Y371076D03*
X1293048Y379088D03*
X1298346Y379028D03*
X1293100Y409539D03*
X1296100D03*
X1293100Y406739D03*
X1296100Y407039D03*
X1295764Y401981D03*
X1298264D03*
X1300037Y398278D03*
X1297537D03*
X1292618Y413611D03*
X1295118D03*
X1300118D03*
X1297618D03*
X1292383Y424067D03*
X1294883D03*
X1299883D03*
X1297383D03*
X1299757Y438293D03*
Y441093D03*
X1290092Y442118D03*
Y439318D03*
X1299757Y443893D03*
X1287719Y470001D03*
X1290219D03*
X1299867Y477318D03*
X1299466Y466409D03*
X1299807Y472020D03*
X1288144Y489036D03*
X1291005Y485580D03*
X1288505D03*
X1301314Y484882D03*
X1299304Y487382D03*
X1290380Y495636D03*
Y492836D03*
X1300817Y568635D03*
X1301194Y565518D03*
X1305836Y660009D03*
X1298963Y659609D03*
X1289811Y677612D03*
X1289317Y706932D03*
X1291604Y781576D03*
Y776576D03*
Y771435D03*
X1295491Y798821D03*
X1298720Y798975D03*
X1289730Y806845D03*
X1302140Y812625D03*
X1302501Y824747D03*
X1297667Y832150D03*
X1293500Y827500D03*
X1296770Y828775D03*
X1293500Y843500D03*
Y835500D03*
X1296687Y839500D03*
X1293500Y851500D03*
X1294000Y863500D03*
X1293500Y879800D03*
Y871800D03*
Y875800D03*
X1288164Y892354D03*
X1296866Y894993D03*
X1305250Y889250D03*
X1293272Y887800D03*
X1293500Y883800D03*
X1291129Y892267D03*
X1294264Y905595D03*
X1301657Y899129D03*
X1288500Y901254D03*
X1298966Y899610D03*
X1296466D03*
X1298000Y917000D03*
X1294075D03*
X1304949Y928546D03*
X1292500Y928000D03*
X1295453Y928047D03*
X1291059Y917000D03*
X1302000D03*
X1302500Y939500D03*
X1300882Y937144D03*
X1296500Y961500D03*
X1289500Y949500D03*
X1300500Y960000D03*
X1290792Y961363D03*
X1300500Y970187D03*
X1297558Y970216D03*
X1292836Y975244D03*
X1292631Y979845D03*
X1299717Y1024136D03*
X1297852Y1014475D03*
X1295815Y1124943D03*
X1295893Y1122182D03*
X1310853Y37543D03*
X1314887Y45448D03*
X1318859D03*
X1311904Y100625D03*
X1320566Y103621D03*
X1304854Y106186D03*
X1316277Y112083D03*
X1307666Y118335D03*
Y132509D03*
Y121735D03*
Y135909D03*
X1305015Y168697D03*
X1319912Y183834D03*
X1314627Y171523D03*
X1320085Y172665D03*
X1320022Y178560D03*
X1306103Y191941D03*
X1319432Y190185D03*
X1314157Y192490D03*
X1320202Y200864D03*
X1310115Y192300D03*
X1308112Y206767D03*
X1313112D03*
X1310612D03*
X1320225Y207037D03*
X1320291Y212455D03*
X1313242Y221708D03*
X1310742D03*
X1309357Y231021D03*
Y228221D03*
X1317592Y221642D03*
X1308242Y221708D03*
X1307657Y224421D03*
X1309908Y236189D03*
X1314908D03*
X1312408D03*
X1312349Y248765D03*
X1309849D03*
X1314849D03*
X1306800Y266114D03*
X1310046Y268195D03*
X1312546D03*
X1315346D03*
X1319006Y265897D03*
X1312546Y270695D03*
X1310046D03*
X1315346D03*
X1318362Y310562D03*
X1305928Y318250D03*
X1308428D03*
X1315256Y336510D03*
X1313103Y339606D03*
X1312240Y334681D03*
X1315397Y333709D03*
X1308012Y348109D03*
X1305910Y377581D03*
X1310172Y367956D03*
X1308410Y379591D03*
X1311283Y370801D03*
X1308826Y389402D03*
X1306113Y383817D03*
X1312626Y387702D03*
X1315426D03*
X1306113Y386317D03*
Y388817D03*
X1309750Y438293D03*
Y441093D03*
Y443893D03*
X1311488Y471560D03*
X1307819Y474382D03*
X1307835Y470382D03*
X1319474Y467560D03*
X1319974Y475560D03*
X1311488D03*
X1318160Y520053D03*
X1317945Y523058D03*
X1319000Y562500D03*
Y558500D03*
Y586500D03*
Y574500D03*
Y578500D03*
Y605000D03*
Y590500D03*
X1319323Y598454D03*
X1319000Y621000D03*
Y609000D03*
Y633000D03*
Y625000D03*
Y637000D03*
Y653500D03*
Y649500D03*
Y641000D03*
Y669500D03*
Y665500D03*
Y681500D03*
Y677500D03*
X1313979Y677726D03*
X1319000Y685500D03*
Y696500D03*
Y700500D03*
Y712500D03*
Y716500D03*
Y724500D03*
Y728500D03*
Y732500D03*
X1321000Y796000D03*
X1313000D03*
X1317000Y799000D03*
Y788000D03*
X1313000D03*
X1315000Y811620D03*
X1319000D03*
X1317000Y804000D03*
X1313000D03*
X1321000D03*
X1310715Y820491D03*
Y822991D03*
Y817991D03*
X1310687Y830206D03*
Y832706D03*
Y827706D03*
X1310971Y842319D03*
X1305786Y867704D03*
X1310994Y866859D03*
X1309753Y877589D03*
X1305740Y877534D03*
X1310535Y870775D03*
X1308220Y889253D03*
X1311061Y889361D03*
X1314500Y911500D03*
X1319500Y901500D03*
X1314500Y905000D03*
X1305356Y902597D03*
X1319500Y905000D03*
X1309103Y917000D03*
X1313867Y925605D03*
X1311325Y928918D03*
X1319554Y925585D03*
X1309103Y936559D03*
X1306500Y936500D03*
X1315779Y943743D03*
X1313152Y936605D03*
X1312575Y943974D03*
X1321256Y943815D03*
X1311000Y961500D03*
X1307000Y960500D03*
X1315441Y960000D03*
X1307000Y970000D03*
X1311000Y970124D03*
X1307707Y979870D03*
X1317254Y990777D03*
X1317053Y988111D03*
X1319874Y989856D03*
X1307561Y986951D03*
X1315606Y1042825D03*
X1315756Y1039344D03*
X1312873Y1036543D03*
X1306385Y1036646D03*
X1319221Y1058097D03*
Y1060697D03*
X1316869Y1107997D03*
X1319069Y1112397D03*
X1318969Y1109397D03*
X1316869Y1113797D03*
Y1110897D03*
X1317437Y1160834D03*
X1318178Y1192621D03*
Y1190121D03*
X1319237Y1221428D03*
X1311237D03*
X1315237D03*
X1311237Y1233428D03*
Y1229428D03*
Y1225428D03*
X1315237Y1237428D03*
Y1233428D03*
Y1229428D03*
Y1225428D03*
X1319237Y1237428D03*
Y1233428D03*
Y1229428D03*
Y1225428D03*
X1315237Y1241428D03*
X1319237D03*
X1308107Y1283395D03*
X1310773Y1282411D03*
X1303900Y1288000D03*
X1318287Y1295381D03*
Y1291381D03*
X1324120Y22742D03*
X1331073Y33400D03*
X1328003Y32403D03*
X1328318Y27333D03*
X1336623Y30483D03*
X1322853Y37530D03*
X1328799Y168665D03*
Y176665D03*
X1320898Y186629D03*
X1328799Y192665D03*
Y196665D03*
X1328912Y186778D03*
X1328831Y204864D03*
Y208864D03*
X1324472Y219379D03*
X1325100Y228631D03*
X1321506Y265897D03*
X1334110Y310562D03*
X1321762D03*
X1329636Y307562D03*
X1326236D03*
X1332563Y326356D03*
X1325573Y326719D03*
X1332359Y322685D03*
X1326489Y356945D03*
X1331005Y356670D03*
X1331922Y359836D03*
X1325007Y370951D03*
X1334109Y373401D03*
X1334285Y386567D03*
X1331606D03*
X1328896D03*
X1320594Y387151D03*
Y382151D03*
Y384651D03*
X1329097Y435321D03*
Y438121D03*
X1326297Y435321D03*
Y438121D03*
X1329097Y440921D03*
X1326297D03*
X1329097Y443721D03*
X1326297D03*
X1335440Y452799D03*
X1329083Y448931D03*
X1329606Y459170D03*
X1332974Y474513D03*
X1321450Y520268D03*
X1321164Y523130D03*
X1326993Y556788D03*
X1331096Y549931D03*
X1327043Y573346D03*
X1327000Y562500D03*
X1326946Y567906D03*
X1338000Y562500D03*
X1327000Y578500D03*
Y583826D03*
X1335000Y594500D03*
X1327000Y605000D03*
Y594500D03*
Y609000D03*
X1333224Y615484D03*
X1327000Y613000D03*
Y621000D03*
X1335532Y622260D03*
X1338000Y609000D03*
X1327000Y629000D03*
X1327003Y623940D03*
X1335000Y641000D03*
X1338000Y653500D03*
X1327000Y641000D03*
X1327011Y646064D03*
X1327000Y657500D03*
X1335000Y685500D03*
X1327000D03*
Y695500D03*
Y700500D03*
X1338000D03*
X1327000Y711500D03*
Y716500D03*
X1335000Y732500D03*
X1327000D03*
X1330295Y746328D03*
X1326970Y736464D03*
X1336661Y753675D03*
Y745675D03*
Y737675D03*
X1330295Y751328D03*
X1330086Y763758D03*
X1330324Y779030D03*
X1336746Y781675D03*
X1329000Y796000D03*
X1325000Y799000D03*
X1337000Y796000D03*
X1333000Y799000D03*
Y788000D03*
X1329000D03*
X1321000D03*
X1325000D03*
X1331000Y811620D03*
X1327000D03*
X1329000Y804000D03*
X1325000D03*
X1333000D03*
X1323000Y811620D03*
X1335000D03*
X1335803Y826500D03*
X1331056Y904557D03*
X1336096Y905042D03*
X1336000Y900500D03*
X1324000Y901000D03*
X1331078Y900500D03*
X1330500Y925500D03*
X1334500D03*
X1326500D03*
X1333425Y930925D03*
X1324000D03*
X1333132Y933781D03*
X1336000Y943500D03*
X1329199Y933825D03*
X1323000Y934075D03*
X1326500Y943500D03*
X1335343Y961727D03*
X1321028Y961749D03*
X1332500Y961500D03*
X1325550Y960445D03*
X1332000Y969500D03*
X1327000D03*
X1329503Y991088D03*
X1334909Y990340D03*
X1332404Y988215D03*
X1329834Y988132D03*
X1324735Y989966D03*
X1327267Y988271D03*
X1322427Y988221D03*
X1333974Y1033483D03*
X1320549Y1037876D03*
X1322773Y1040599D03*
X1329221Y1058097D03*
X1321721D03*
X1324221D03*
X1326721D03*
Y1060697D03*
X1329221D03*
X1321721D03*
X1324221D03*
X1326163Y1082501D03*
X1326189Y1085205D03*
X1329163Y1082501D03*
X1329189Y1085205D03*
X1326189Y1088205D03*
X1326471Y1091227D03*
X1329189Y1088205D03*
X1323189Y1085205D03*
Y1087705D03*
X1323163Y1082501D03*
X1323021Y1090956D03*
X1337514Y1104335D03*
X1334956Y1105552D03*
X1321069Y1107997D03*
X1323021Y1093956D03*
X1331162Y1104792D03*
X1332669Y1106867D03*
X1321169Y1110597D03*
X1321954Y1113648D03*
X1326254D03*
X1328754D03*
X1323405Y1118801D03*
Y1116101D03*
X1325635Y1172384D03*
Y1162384D03*
Y1164884D03*
Y1167384D03*
Y1169884D03*
X1323135Y1172384D03*
Y1162384D03*
Y1164884D03*
Y1167384D03*
Y1169884D03*
X1334793Y1179421D03*
Y1181921D03*
Y1184421D03*
Y1186921D03*
X1320493Y1186709D03*
Y1184209D03*
Y1181709D03*
Y1179209D03*
X1325635Y1174884D03*
X1323135D03*
X1331643Y1192621D03*
Y1190121D03*
X1327237Y1221428D03*
X1331237D03*
X1335237D03*
X1323237D03*
X1327237Y1237428D03*
Y1233428D03*
Y1229428D03*
Y1225428D03*
X1331237Y1237428D03*
Y1233428D03*
Y1229428D03*
Y1225428D03*
X1335237Y1237428D03*
Y1233428D03*
Y1229428D03*
Y1225428D03*
X1323237Y1237428D03*
Y1233428D03*
Y1229428D03*
Y1225428D03*
X1335237Y1241428D03*
X1323237Y1245428D03*
Y1241428D03*
X1327237Y1245428D03*
Y1241428D03*
X1331237Y1245428D03*
Y1241428D03*
X1335237Y1245428D03*
X1333876Y1257160D03*
Y1260160D03*
X1337687Y-69306D03*
Y-72706D03*
X1336646Y22627D03*
X1336551Y26534D03*
X1340320Y147540D03*
X1344092Y141247D03*
X1351559Y143740D03*
X1348939Y148277D03*
X1348419Y265222D03*
X1340104Y279117D03*
X1344007Y279054D03*
X1337510Y310562D03*
X1347990Y322539D03*
X1341169Y325926D03*
X1346009Y336080D03*
X1346093Y340805D03*
X1349636Y340862D03*
X1346065Y347106D03*
X1338471Y356959D03*
X1337509Y373401D03*
X1349763Y371908D03*
X1342810Y408104D03*
X1345610D03*
X1348410D03*
X1336388Y424939D03*
X1342527Y420375D03*
X1345327D03*
X1348127D03*
X1336388Y427439D03*
X1346443Y431112D03*
X1352008Y435101D03*
X1352271Y442114D03*
X1346613Y440101D03*
X1352251Y447121D03*
X1346248Y452718D03*
X1340820Y452987D03*
X1352259Y452601D03*
X1347846Y461607D03*
X1339846D03*
X1339049Y471334D03*
X1343846Y461607D03*
X1346738Y564492D03*
X1339289Y568461D03*
X1342053Y579339D03*
X1346533Y576780D03*
X1340522Y586133D03*
X1343000Y590458D03*
X1346533Y581898D03*
X1344129Y606914D03*
X1344433Y601201D03*
X1339289Y614961D03*
X1344680Y619085D03*
X1346738Y611192D03*
X1346533Y628398D03*
X1346378Y623734D03*
X1342053Y625839D03*
X1340522Y632633D03*
X1343000Y636958D03*
X1346738Y655492D03*
X1339289Y659461D03*
X1346533Y667780D03*
X1342053Y670339D03*
X1346533Y672898D03*
X1340522Y677133D03*
X1343000Y681458D03*
X1350929Y687043D03*
X1340299Y686243D03*
X1346738Y702492D03*
X1346533Y719898D03*
X1339289Y706461D03*
X1342053Y717339D03*
X1346533Y714780D03*
X1340522Y724133D03*
X1343000Y728458D03*
X1344768Y737675D03*
Y741675D03*
Y745675D03*
Y749675D03*
Y753675D03*
Y761675D03*
Y757675D03*
X1336450Y765675D03*
X1344768Y773675D03*
Y781350D03*
X1345226Y777675D03*
X1341000Y799000D03*
X1345000Y796000D03*
X1341000Y788000D03*
X1345000D03*
X1337000D03*
X1348917Y796000D03*
Y788000D03*
X1352817Y796000D03*
X1349000Y804000D03*
X1351000Y811620D03*
X1347000D03*
X1343000D03*
X1337000Y804000D03*
X1345000D03*
X1341000D03*
X1349976Y829000D03*
X1350000Y825500D03*
X1340000Y900000D03*
X1351500Y903000D03*
Y906500D03*
X1340000Y906000D03*
Y903000D03*
X1351511Y900000D03*
X1350500Y925500D03*
X1338500D03*
X1342500D03*
X1346500D03*
X1353948Y943603D03*
X1345948D03*
X1349848Y936755D03*
X1338500Y930500D03*
X1350500D03*
X1342500D03*
X1346500D03*
X1337514Y988259D03*
X1343465Y1026123D03*
X1340665D03*
X1343465Y1028923D03*
X1340665D03*
X1347552Y1091816D03*
Y1089316D03*
X1345052Y1081816D03*
Y1084316D03*
Y1086816D03*
X1347552D03*
Y1084316D03*
X1350418Y1090288D03*
X1347552Y1081816D03*
X1344241Y1106298D03*
X1348997Y1107997D03*
X1350418Y1093088D03*
X1339234Y1101917D03*
X1339169Y1106897D03*
X1341984Y1110092D03*
X1345650Y1115896D03*
X1348997Y1113797D03*
Y1110897D03*
X1351197Y1112397D03*
X1351097Y1109397D03*
X1345650Y1118396D03*
X1347300Y1128332D03*
X1343725Y1128738D03*
X1343905Y1162384D03*
Y1164884D03*
Y1167384D03*
Y1169884D03*
Y1172384D03*
X1341405D03*
Y1169884D03*
Y1167384D03*
Y1164884D03*
Y1162384D03*
X1350963Y1172384D03*
Y1169884D03*
Y1167384D03*
Y1164884D03*
Y1162384D03*
X1351149Y1158200D03*
X1347423Y1186709D03*
Y1184209D03*
Y1181709D03*
Y1179209D03*
X1343905Y1174884D03*
X1341405D03*
X1350963D03*
X1337108Y1192621D03*
Y1190121D03*
X1345108D03*
Y1192621D03*
X1347237Y1221428D03*
X1343237D03*
X1339237D03*
X1347237Y1237428D03*
Y1233428D03*
Y1229428D03*
X1343237D03*
Y1233428D03*
Y1237428D03*
X1339237D03*
Y1233428D03*
Y1229428D03*
Y1225428D03*
X1347237Y1245428D03*
Y1241428D03*
X1343237D03*
Y1245428D03*
X1339237D03*
Y1241428D03*
X1339876Y1257160D03*
X1342876D03*
X1345876Y1260160D03*
Y1257160D03*
X1348876Y1260160D03*
Y1257160D03*
X1351876Y1260160D03*
Y1257160D03*
X1336876Y1260160D03*
Y1257160D03*
X1342876Y1260160D03*
X1339876D03*
X1360122Y141247D03*
X1364609Y143518D03*
X1363709Y152373D03*
X1366859Y152562D03*
X1363535Y327877D03*
X1366535Y335751D03*
Y339151D03*
X1363535Y331277D03*
Y343625D03*
X1366535Y354899D03*
Y351499D03*
X1363535Y347025D03*
X1360719Y424601D03*
X1352817Y788000D03*
X1367000Y811620D03*
X1365000Y804000D03*
X1355000Y811620D03*
X1363000D03*
X1353000Y804000D03*
X1359000Y811620D03*
X1357000Y804000D03*
X1361000D03*
X1354185Y906498D03*
X1367000Y904500D03*
X1363000Y900500D03*
X1367000D03*
X1354500Y925500D03*
X1366500D03*
X1358500D03*
X1362500D03*
X1365948Y939475D03*
X1357948Y938842D03*
X1361948Y943603D03*
X1369948D03*
X1362500Y930500D03*
X1366500D03*
X1354500D03*
X1358500D03*
X1364765Y1004766D03*
X1367444Y1003763D03*
X1357765Y1019766D03*
X1361265D03*
X1365049Y1028416D03*
X1365314Y1021793D03*
X1357265Y1026266D03*
Y1034266D03*
X1366265Y1039880D03*
X1369642Y1104335D03*
X1367084Y1105552D03*
X1353197Y1107997D03*
X1363290Y1104792D03*
X1364797Y1106867D03*
X1353297Y1110597D03*
X1354082Y1113648D03*
X1355533Y1116101D03*
Y1118801D03*
X1360882Y1113648D03*
X1358382D03*
X1353463Y1172384D03*
Y1169884D03*
Y1167384D03*
Y1164884D03*
Y1162384D03*
X1361723Y1179421D03*
Y1181921D03*
Y1184421D03*
Y1186921D03*
X1353463Y1174884D03*
X1364038Y1190121D03*
Y1192621D03*
X1363876Y1260160D03*
Y1257160D03*
X1354876Y1260160D03*
X1357876D03*
X1360876D03*
Y1257160D03*
X1357876D03*
X1354876D03*
X1366876Y1260160D03*
Y1257160D03*
X1376262Y116594D03*
X1382205Y110784D03*
X1387205D03*
X1376262Y119594D03*
X1386784Y124663D03*
X1376696Y124283D03*
X1381762Y124879D03*
X1375103Y161306D03*
X1372354Y157370D03*
X1384319Y218085D03*
X1381519D03*
X1386846Y249108D03*
X1378227Y248371D03*
X1384265Y320871D03*
Y325371D03*
X1383551Y337808D03*
X1384265Y329871D03*
X1383634Y342766D03*
X1384265Y334371D03*
X1375073Y356871D03*
Y361371D03*
X1383505Y349437D03*
X1384265Y352371D03*
X1372232Y361298D03*
X1383963Y366675D03*
X1377024Y397713D03*
X1375108Y420838D03*
X1375171Y424741D03*
X1375400Y435192D03*
X1375360Y432234D03*
X1383343Y508228D03*
X1383907Y516591D03*
X1383556Y554388D03*
X1378415Y558795D03*
X1383608Y571927D03*
X1378415Y563984D03*
Y569776D03*
X1378957Y584457D03*
X1383000Y584500D03*
X1382997Y581317D03*
X1383425Y590425D03*
X1378415Y605295D03*
X1383608Y618427D03*
X1378415Y610484D03*
Y616276D03*
X1383425Y636925D03*
X1378957Y630957D03*
X1384657Y631620D03*
X1378957Y627988D03*
X1378415Y649795D03*
Y654984D03*
Y660776D03*
X1386289Y672488D03*
X1383425Y681425D03*
X1378957Y675457D03*
X1383000Y675500D03*
X1378415Y696795D03*
Y701984D03*
X1378957Y719488D03*
X1378415Y707776D03*
X1383425Y728425D03*
X1378957Y722457D03*
X1385290Y722400D03*
X1371000Y811620D03*
X1381000Y804000D03*
X1373000D03*
X1369000D03*
X1385360Y811757D03*
X1381428Y812287D03*
X1375193Y811724D03*
X1376708Y901000D03*
X1378500Y925500D03*
X1374369Y925499D03*
X1370500Y925500D03*
X1382500D03*
X1382775Y930281D03*
X1373948Y940103D03*
X1374500Y930500D03*
X1370500D03*
X1378500D03*
X1381519Y996280D03*
X1383162Y991829D03*
X1373534Y1012325D03*
Y1004680D03*
X1378938Y1000586D03*
X1374034Y1015825D03*
X1374059Y1018860D03*
X1376359Y1016825D03*
X1378559Y1038534D03*
X1384784Y1033783D03*
X1385929Y1038665D03*
X1373874Y1032266D03*
Y1035716D03*
X1385152Y1046591D03*
X1377087Y1106365D03*
X1371362Y1101917D03*
X1371297Y1106897D03*
X1382456Y1107997D03*
X1374112Y1110092D03*
X1377778Y1115896D03*
X1384656Y1112397D03*
X1382456Y1110897D03*
Y1113797D03*
X1384556Y1109397D03*
X1377778Y1118396D03*
X1369233Y1169884D03*
Y1172384D03*
X1371733D03*
Y1169884D03*
Y1167384D03*
Y1164884D03*
Y1162384D03*
X1369233D03*
Y1164884D03*
Y1167384D03*
X1376861Y1160834D03*
X1383024D03*
X1369233Y1174884D03*
X1371733D03*
X1375459Y1197471D03*
Y1193471D03*
X1379959Y1197471D03*
Y1193471D03*
X1397848Y97667D03*
X1388231Y116594D03*
X1393504Y102495D03*
X1388231Y119594D03*
X1399648Y132515D03*
Y121742D03*
Y118342D03*
X1391765Y125107D03*
X1399648Y135915D03*
X1393238Y142862D03*
X1400379Y143762D03*
X1394279Y148717D03*
X1388128Y138838D03*
X1399327Y195176D03*
X1396827D03*
X1400845Y199248D03*
Y201748D03*
X1398681Y206806D03*
X1401181D03*
X1399408Y210509D03*
X1396908D03*
X1390832Y216970D03*
Y219470D03*
X1390898Y226320D03*
X1390832Y221970D03*
X1388119Y216385D03*
X1402855Y227824D03*
X1398600Y230556D03*
X1393859Y228646D03*
X1397585Y242078D03*
X1392816Y232971D03*
X1389466Y244571D03*
X1396809Y256394D03*
X1395726Y320529D03*
X1395568Y325529D03*
X1395726Y330529D03*
X1395736Y335529D03*
X1395726Y340529D03*
Y345529D03*
Y360529D03*
Y350529D03*
Y355529D03*
X1391896Y365529D03*
X1399884Y367165D03*
X1387847Y366710D03*
X1400231Y390256D03*
X1396528Y397454D03*
X1399571Y397418D03*
X1393575Y397310D03*
X1390553Y397436D03*
X1391623Y409900D03*
X1387125Y417312D03*
X1393177Y424804D03*
X1389557Y424678D03*
X1389431Y421593D03*
X1390271Y417578D03*
X1393208Y428109D03*
X1393336Y431100D03*
X1403085Y460565D03*
X1393944Y507856D03*
X1394044Y510990D03*
X1397079Y527726D03*
Y548726D03*
Y544726D03*
X1395605Y556217D03*
X1390741Y561000D03*
Y569000D03*
Y565000D03*
X1391087Y581317D03*
X1398946Y621311D03*
X1390741Y611500D03*
Y607500D03*
Y615500D03*
X1391586Y623692D03*
X1398946Y629311D03*
Y625311D03*
X1397000Y652000D03*
Y656000D03*
Y660000D03*
Y699000D03*
Y707000D03*
Y703000D03*
X1391040Y812027D03*
X1386335Y803704D03*
X1390537Y803679D03*
X1394537Y803653D03*
X1398530Y811717D03*
X1402417Y811692D03*
X1400069Y827515D03*
X1401300Y820485D03*
X1395955Y832697D03*
X1402000Y840000D03*
Y848000D03*
X1399872Y845109D03*
X1402000Y864000D03*
X1391316Y857849D03*
X1388488Y857822D03*
X1402000Y876000D03*
X1390182Y873460D03*
X1387582Y873487D03*
X1402000Y884000D03*
Y892000D03*
X1388479Y892923D03*
X1385979D03*
X1390979D03*
X1402000Y900000D03*
X1387520Y905307D03*
X1387753Y912629D03*
X1394891Y914783D03*
X1402187Y908270D03*
X1387504Y899931D03*
X1390541Y900086D03*
X1388980Y921075D03*
X1401000Y925789D03*
X1396869Y958707D03*
X1402064Y965913D03*
X1389192Y992568D03*
X1398854Y987277D03*
X1394885Y999941D03*
X1392031Y1004375D03*
X1385732Y1029482D03*
X1389762Y1043055D03*
X1387813Y1030952D03*
X1399807Y1036155D03*
X1399852Y1039779D03*
X1388523Y1090090D03*
X1392691Y1089224D03*
X1392086Y1092743D03*
X1392691Y1086724D03*
Y1084224D03*
Y1081724D03*
X1390191D03*
Y1084224D03*
Y1086724D03*
X1403101Y1104335D03*
X1400543Y1105552D03*
X1396749Y1104792D03*
X1388451Y1093048D03*
X1386656Y1107997D03*
X1398256Y1106867D03*
X1386756Y1110597D03*
X1394341Y1113648D03*
X1388992Y1118801D03*
Y1116101D03*
X1387541Y1113648D03*
X1391841D03*
X1388722Y1162384D03*
Y1164884D03*
Y1167384D03*
Y1169884D03*
Y1172384D03*
X1391222Y1162384D03*
Y1164884D03*
Y1167384D03*
Y1169884D03*
Y1172384D03*
X1388722Y1174884D03*
X1391222D03*
X1393695Y1186709D03*
Y1184209D03*
Y1181709D03*
Y1179209D03*
X1391380Y1190121D03*
Y1192621D03*
X1385821Y1260160D03*
X1391821Y1257160D03*
X1394821D03*
X1385821D03*
X1388821D03*
X1397821Y1260160D03*
Y1257160D03*
X1400821Y1260160D03*
Y1257160D03*
X1388821Y1260160D03*
X1394821D03*
X1391821D03*
X1385052Y1303139D03*
X1389052D03*
X1406308Y103411D03*
X1406702Y97667D03*
X1417498Y90650D03*
X1417248Y95236D03*
X1402098Y95111D03*
X1406948Y111255D03*
Y114655D03*
X1406467Y106561D03*
X1406948Y128828D03*
Y125428D03*
X1403845Y199248D03*
X1401827Y195176D03*
X1404327D03*
X1403845Y202048D03*
X1407445Y230117D03*
X1403461Y238714D03*
X1402942Y246874D03*
X1405162Y244297D03*
X1402921Y322403D03*
X1409830Y347649D03*
X1404690Y362209D03*
X1416912Y386903D03*
X1408854Y381207D03*
X1416470Y381397D03*
X1402968Y390177D03*
X1414369Y398056D03*
X1408254Y398041D03*
X1407844Y411033D03*
X1415610Y417644D03*
X1415674Y421278D03*
X1417856Y448419D03*
X1414903Y469905D03*
X1410903Y470419D03*
Y461919D03*
X1418903Y461419D03*
X1411269Y481467D03*
X1415623Y492268D03*
X1415823Y482165D03*
X1416061Y504825D03*
X1413561D03*
X1411061D03*
X1415064Y500202D03*
X1406910Y495982D03*
X1416413Y495649D03*
X1406910Y491982D03*
X1416002Y517401D03*
X1413502D03*
X1411002D03*
X1416553Y522569D03*
Y525369D03*
X1415168Y531882D03*
X1412668D03*
X1409618Y531948D03*
X1401438Y534211D03*
X1405992Y534909D03*
X1405619Y541135D03*
X1405685Y546553D03*
X1405708Y552726D03*
X1415103Y555194D03*
Y563194D03*
Y571194D03*
X1416660Y581222D03*
Y591215D03*
X1401383Y611071D03*
X1416832Y610562D03*
Y607762D03*
X1411622Y610548D03*
X1407566Y622285D03*
X1407754Y616905D03*
X1418439Y633736D03*
X1407952Y633724D03*
X1413432Y633716D03*
X1407835Y627713D03*
X1405229Y652028D03*
X1405000Y660000D03*
X1410000Y685000D03*
Y681000D03*
X1404500Y675000D03*
X1410000Y701000D03*
Y697000D03*
X1418000Y696000D03*
Y701000D03*
X1410000Y709000D03*
Y713000D03*
X1405000Y707000D03*
Y703000D03*
X1418000Y717000D03*
X1410000D03*
X1404500Y722000D03*
X1410000Y729000D03*
Y725000D03*
X1418000Y724000D03*
Y729000D03*
X1404249Y735858D03*
X1410000Y745000D03*
Y741000D03*
X1418000Y740000D03*
Y745000D03*
X1407482Y750853D03*
X1410000Y757000D03*
Y753000D03*
Y761000D03*
X1418000D03*
X1406867Y783273D03*
X1409115Y773520D03*
X1414597Y792375D03*
X1406483Y811717D03*
X1413500Y832000D03*
Y828000D03*
X1413449Y823934D03*
X1405402Y819917D03*
X1405500Y844000D03*
Y836000D03*
X1413500Y848000D03*
Y840000D03*
Y836000D03*
Y844000D03*
X1405500Y860000D03*
X1413500Y864000D03*
Y860000D03*
Y856000D03*
Y852000D03*
X1405500Y880000D03*
Y868000D03*
X1413500Y876000D03*
X1417797Y879501D03*
X1413500Y872000D03*
Y868000D03*
X1405500Y888000D03*
Y896000D03*
X1417081D03*
X1413500Y892000D03*
Y884000D03*
Y888000D03*
X1413733Y911137D03*
X1412376Y907848D03*
X1414876D03*
X1417376D03*
X1409876D03*
X1405500Y904000D03*
X1404760Y915186D03*
X1413500Y904000D03*
Y900000D03*
X1417284Y911009D03*
X1416802Y936845D03*
X1416244Y942285D03*
X1419337D03*
X1405214Y965074D03*
X1419446Y977192D03*
X1416618Y992307D03*
X1401265Y989465D03*
X1407265D03*
X1414143Y985486D03*
X1412698Y997590D03*
X1412609Y1008766D03*
X1412759Y1016266D03*
X1402215Y1020440D03*
X1414851Y1058097D03*
X1412351D03*
X1407351D03*
X1409851D03*
X1417351D03*
X1414851Y1060697D03*
X1412351D03*
X1407351D03*
X1409851D03*
X1417351D03*
X1405677Y1086796D03*
X1408177D03*
X1410677D03*
X1413177D03*
X1415677D03*
Y1084296D03*
X1413177D03*
X1410677D03*
X1408177D03*
X1405677D03*
X1416005Y1090288D03*
X1410546Y1106298D03*
X1404821Y1101917D03*
X1404756Y1106897D03*
X1416005Y1093088D03*
X1414584Y1107997D03*
X1411237Y1115896D03*
X1407571Y1110092D03*
X1414584Y1113797D03*
X1416784Y1112397D03*
X1414584Y1110897D03*
X1416684Y1109397D03*
X1411237Y1118396D03*
X1409425Y1129238D03*
X1413177Y1128894D03*
X1409492Y1167384D03*
Y1169884D03*
Y1172384D03*
X1406992D03*
Y1169884D03*
X1416550Y1162384D03*
Y1164884D03*
Y1167384D03*
Y1169884D03*
Y1172384D03*
X1406992Y1167384D03*
Y1164884D03*
Y1162384D03*
X1409492D03*
Y1164884D03*
X1416736Y1158200D03*
X1416550Y1174884D03*
X1409492D03*
X1406992D03*
X1407995Y1179421D03*
Y1181921D03*
Y1184421D03*
Y1186921D03*
X1410310Y1192621D03*
Y1190121D03*
X1404845D03*
Y1192621D03*
X1408736Y1222194D03*
X1412736D03*
X1416736D03*
X1408736Y1238194D03*
Y1234194D03*
Y1230194D03*
Y1226194D03*
X1412736Y1238194D03*
Y1234194D03*
Y1230194D03*
Y1226194D03*
X1416736Y1238194D03*
Y1234194D03*
Y1230194D03*
Y1226194D03*
X1412736Y1246194D03*
Y1242194D03*
X1416736Y1246194D03*
Y1242194D03*
X1408736D03*
Y1246194D03*
X1409821Y1260160D03*
X1412821D03*
Y1257160D03*
X1409821D03*
X1406821D03*
X1403821D03*
X1415821Y1260160D03*
Y1257160D03*
X1403821Y1260160D03*
X1406821D03*
X1417711Y1301729D03*
X1410817Y1305417D03*
X1407825Y1426975D03*
X1408536Y1536570D03*
X1407747Y1549054D03*
X1408044Y1559306D03*
X1407255Y1571732D03*
X1422810Y90615D03*
X1427131Y99961D03*
X1427181Y95236D03*
X1425993Y212978D03*
Y207978D03*
Y210478D03*
Y215478D03*
X1429322Y264180D03*
X1431822D03*
X1429247Y258880D03*
X1434166Y325361D03*
X1434164Y339232D03*
X1434038Y334114D03*
X1435818Y352361D03*
X1421005Y407616D03*
X1417903Y439919D03*
X1434997Y442603D03*
X1427117Y443071D03*
X1423427Y456839D03*
X1425927D03*
X1423427Y454339D03*
X1425927D03*
X1432414Y459371D03*
X1423427Y459339D03*
X1425927D03*
X1418903Y469905D03*
X1431484Y470045D03*
X1427484Y462004D03*
X1422499Y485138D03*
X1419650Y485128D03*
X1426384Y478625D03*
X1428084Y482425D03*
X1427499Y485138D03*
X1424999D03*
X1426384Y476125D03*
X1418253Y529169D03*
X1417668Y531882D03*
X1424129Y537658D03*
X1427832Y539731D03*
X1424129Y540458D03*
X1432590Y544895D03*
X1435390D03*
X1427832Y542231D03*
X1432890Y541895D03*
X1417903Y555194D03*
Y563194D03*
Y571194D03*
X1422260Y581222D03*
X1419460D03*
X1435119Y590801D03*
X1422260Y591215D03*
X1419460D03*
X1431000Y591000D03*
X1434944Y597130D03*
X1433114Y620653D03*
Y617853D03*
X1419632Y607762D03*
X1422432D03*
X1425232Y610562D03*
Y607762D03*
X1422432Y610562D03*
X1419632D03*
X1430944Y605443D03*
X1420452Y628078D03*
X1430175Y627852D03*
X1425452Y633473D03*
X1430481Y658153D03*
X1433529Y660564D03*
X1426615Y674112D03*
X1429000Y685000D03*
X1418000D03*
Y681000D03*
X1425909Y691120D03*
X1433464Y692658D03*
X1418000Y689000D03*
X1433053Y701839D03*
X1426000Y717000D03*
X1418000Y705000D03*
X1431522Y708633D03*
X1434000Y712958D03*
X1430289Y734961D03*
X1418000Y733000D03*
X1417969Y720894D03*
X1429000Y729000D03*
X1434000Y751958D03*
X1433153Y745839D03*
X1427000Y766500D03*
X1426000Y761000D03*
X1435000Y765500D03*
X1434000Y756958D03*
X1418023Y765343D03*
X1427000Y781834D03*
Y770500D03*
X1435000D03*
X1427000Y794500D03*
X1435000Y802500D03*
X1427000Y810500D03*
Y814500D03*
X1435000D03*
Y809500D03*
X1427000Y802500D03*
Y830500D03*
Y826500D03*
X1434975Y830500D03*
X1435000Y825500D03*
X1427000Y842500D03*
Y838500D03*
X1435000Y846500D03*
X1427000D03*
X1435043Y874694D03*
X1435082Y869475D03*
X1423190Y905295D03*
X1429059Y908579D03*
X1426085Y910281D03*
X1429907Y936998D03*
X1424897Y936777D03*
X1435516Y936000D03*
X1420699Y958452D03*
X1430839Y965546D03*
X1420740Y1008766D03*
X1428740Y1000766D03*
X1420740Y996766D03*
X1428864D03*
X1420740Y1012266D03*
X1428740Y1016266D03*
X1428823Y1020266D03*
X1435229Y1104335D03*
X1432671Y1105552D03*
X1428877Y1104792D03*
X1418784Y1107997D03*
X1430384Y1106867D03*
X1418884Y1110597D03*
X1421120Y1116101D03*
Y1118801D03*
X1426469Y1113648D03*
X1423969D03*
X1419669D03*
X1419050Y1162384D03*
Y1164884D03*
Y1167384D03*
Y1169884D03*
Y1172384D03*
Y1174884D03*
X1420625Y1186709D03*
Y1184209D03*
Y1181709D03*
Y1179209D03*
X1418310Y1192621D03*
Y1190121D03*
X1420736Y1222194D03*
X1424736D03*
X1428736D03*
X1432736D03*
X1420736Y1238194D03*
Y1234194D03*
Y1230194D03*
Y1226194D03*
X1424736Y1238194D03*
Y1234194D03*
Y1230194D03*
Y1226194D03*
X1428736Y1238194D03*
Y1234194D03*
Y1230194D03*
Y1226194D03*
X1432736Y1234194D03*
Y1230194D03*
Y1226194D03*
X1420736Y1246194D03*
Y1242194D03*
X1424736Y1246194D03*
Y1242194D03*
X1428736Y1246194D03*
Y1242194D03*
X1421821Y1257160D03*
X1418821D03*
Y1260160D03*
X1421821D03*
X1431080Y1301702D03*
X1421238Y1301712D03*
X1428009Y1301760D03*
X1424732Y1301603D03*
X1432258Y1414600D03*
X1430374Y1492474D03*
X1420877Y1494706D03*
X1421964Y1502813D03*
X1423930Y1520364D03*
X1429587Y1527450D03*
X1433405Y1546001D03*
X1432913Y1568679D03*
X1449685Y34228D03*
X1436045Y77393D03*
Y74793D03*
Y85193D03*
Y82593D03*
Y79993D03*
X1444370Y98551D03*
X1436089Y92874D03*
X1447265Y111223D03*
Y114623D03*
X1447920Y103783D03*
X1438116Y107649D03*
Y104249D03*
X1447265Y125396D03*
Y128796D03*
X1442682Y147540D03*
X1446454Y141247D03*
X1451301Y148277D03*
X1435138Y162368D03*
X1437738D03*
X1444838Y162793D03*
Y165393D03*
Y170493D03*
Y167993D03*
X1451762Y177616D03*
X1449841Y181009D03*
X1447046Y181366D03*
X1443835Y181426D03*
X1444043Y184221D03*
X1446660Y184012D03*
X1448079Y211359D03*
Y213859D03*
X1436449Y213213D03*
Y210713D03*
X1440521Y211695D03*
X1443021D03*
X1440521Y208695D03*
X1443321D03*
X1436449Y208213D03*
Y215713D03*
X1451785Y265896D03*
X1446698Y265701D03*
X1441016Y267526D03*
Y270026D03*
X1443516D03*
X1438216D03*
X1443516Y267526D03*
X1438216D03*
X1448333Y281716D03*
X1449060Y329861D03*
X1448948Y326448D03*
X1449060Y320861D03*
X1438829Y329861D03*
X1437064Y320861D03*
X1448822Y345324D03*
X1448734Y332910D03*
X1448500Y340575D03*
X1439712Y336673D03*
X1440420Y346833D03*
X1449060Y356861D03*
X1441180Y354909D03*
X1448572Y349441D03*
X1449060Y352361D03*
X1447502Y360785D03*
X1434697Y347125D03*
X1439719Y350387D03*
X1443041Y363648D03*
X1434608Y362584D03*
X1438768Y371655D03*
X1442633Y371502D03*
X1445906Y366030D03*
X1440523Y382747D03*
X1435424Y430361D03*
X1440390Y456652D03*
X1442890D03*
Y459152D03*
Y461652D03*
X1440390Y459152D03*
Y461652D03*
X1436930Y461818D03*
X1433960Y491214D03*
X1449293Y491133D03*
X1442721Y495151D03*
X1437663Y492987D03*
X1442421Y498151D03*
X1433960Y493714D03*
X1437663Y495487D03*
X1445221Y498151D03*
X1449293Y493633D03*
Y496133D03*
Y498633D03*
X1445221Y495151D03*
X1439462Y537877D03*
X1449393Y553297D03*
Y555897D03*
X1446988Y548418D03*
X1439462Y540377D03*
X1435390Y541895D03*
X1444488Y548418D03*
X1439488D03*
X1441988D03*
X1439462Y542877D03*
Y545377D03*
X1449393Y558497D03*
Y566797D03*
Y563697D03*
Y561097D03*
X1443388Y570686D03*
X1446183Y570478D03*
X1435668Y582747D03*
X1446600Y576484D03*
X1446243Y573689D03*
X1443597Y573303D03*
X1449993Y578405D03*
X1438944Y597232D03*
X1443775Y596089D03*
X1448994Y596782D03*
X1440930Y613913D03*
Y616713D03*
Y619513D03*
X1434944Y605443D03*
X1438944Y605637D03*
X1437790Y625013D03*
X1435952Y642184D03*
X1446323Y673183D03*
X1437738Y686992D03*
X1448991Y694392D03*
X1451976Y693844D03*
X1437533Y704398D03*
Y699280D03*
X1438930Y716363D03*
X1446860Y730735D03*
X1446538Y719548D03*
X1437738Y730992D03*
X1446717Y735536D03*
X1437533Y743280D03*
Y748398D03*
X1447289Y776461D03*
X1446000Y770500D03*
X1451000Y793458D03*
Y798458D03*
X1450253Y787339D03*
X1443000Y802500D03*
X1447000Y810500D03*
Y818500D03*
X1435000D03*
X1448000Y834500D03*
X1443000Y846500D03*
X1435000Y834500D03*
X1449000Y844500D03*
X1435212Y854042D03*
X1448726Y864400D03*
X1439891Y873821D03*
X1445367Y891888D03*
X1441223Y891957D03*
X1435745Y901500D03*
X1443231Y899006D03*
X1439103Y898564D03*
X1447261Y898571D03*
X1446022Y927000D03*
X1448137Y949440D03*
X1439031Y957683D03*
X1441088Y976409D03*
X1433996Y981437D03*
X1440700Y981763D03*
X1435669Y1005366D03*
X1440869Y1010256D03*
X1435197Y1028372D03*
X1442674Y1106365D03*
X1436949Y1101917D03*
X1436884Y1106897D03*
X1439699Y1110092D03*
X1443365Y1115896D03*
Y1118396D03*
X1442448Y1160834D03*
X1434820Y1162384D03*
Y1164884D03*
Y1167384D03*
Y1169884D03*
Y1172384D03*
X1437320D03*
Y1169884D03*
Y1167384D03*
Y1164884D03*
Y1162384D03*
X1434925Y1179421D03*
Y1181921D03*
Y1184421D03*
Y1186921D03*
X1434820Y1174884D03*
X1437320D03*
X1437240Y1192621D03*
Y1190121D03*
X1436736Y1222194D03*
Y1226194D03*
X1443660Y1310698D03*
X1440260D03*
X1446817Y1335846D03*
X1441200Y1338700D03*
X1435900Y1340800D03*
X1439258Y1414600D03*
X1446135Y1530876D03*
X1443103Y1527201D03*
X1441145Y1540415D03*
X1440153Y1563093D03*
X1443769Y1562173D03*
X1452717Y34052D03*
X1457347Y31518D03*
X1457829Y26425D03*
X1455013Y43128D03*
X1460466Y76587D03*
Y72615D03*
X1461905Y100625D03*
X1454924Y97475D03*
X1454855Y106186D03*
X1457667Y118335D03*
Y121735D03*
Y132509D03*
Y135909D03*
X1462484Y141247D03*
X1466971Y143518D03*
X1453921Y143740D03*
X1466071Y152373D03*
X1455016Y168697D03*
X1452343Y172190D03*
X1464628Y171523D03*
X1456104Y191941D03*
X1464158Y192490D03*
X1458113Y206767D03*
X1463113D03*
X1460613D03*
X1451782Y213132D03*
X1463243Y221708D03*
X1460743D03*
X1458243D03*
X1457658Y224421D03*
X1459358Y231021D03*
Y228221D03*
X1451782Y215632D03*
X1459909Y236189D03*
X1464909D03*
X1462409D03*
X1459850Y248765D03*
X1464850D03*
X1462350D03*
X1452026Y256303D03*
X1456801Y266114D03*
X1460047Y270695D03*
Y268195D03*
X1462547Y270695D03*
Y268195D03*
X1465347Y270695D03*
Y268195D03*
X1454274Y281982D03*
X1459060Y320861D03*
Y325361D03*
Y329861D03*
Y338861D03*
Y343361D03*
Y334361D03*
Y347861D03*
Y352361D03*
X1459873Y391705D03*
X1463145Y391579D03*
X1458214Y406231D03*
X1464536Y433114D03*
X1458912Y581659D03*
X1455419Y578986D03*
X1454944Y596729D03*
X1453000Y614158D03*
Y616958D03*
Y619758D03*
X1450944Y605443D03*
X1458944D03*
X1461474Y655807D03*
X1455761Y683448D03*
X1468372Y673812D03*
X1460111Y683536D03*
X1451428Y673252D03*
X1460816Y727964D03*
X1455291Y759656D03*
X1455159Y763714D03*
X1454504Y777575D03*
X1454533Y784780D03*
X1454738Y772492D03*
X1454533Y789898D03*
X1453102Y821102D03*
X1454541Y831339D03*
X1453102Y826500D03*
X1452619Y836457D03*
X1461113Y871389D03*
X1457218Y888764D03*
X1452641Y888033D03*
X1451286Y898549D03*
X1462500Y905295D03*
X1461888Y936055D03*
X1462000Y957000D03*
X1458202Y960288D03*
X1457937Y966712D03*
X1457352Y976277D03*
X1459519Y989432D03*
X1467096Y988813D03*
X1456966Y998507D03*
X1458892Y1007522D03*
X1465658Y1006648D03*
X1465846Y1023900D03*
X1463025Y1018307D03*
X1459267Y1013678D03*
X1456280Y1023405D03*
X1459683Y1028377D03*
X1481905Y-69278D03*
Y-72678D03*
X1479972Y40780D03*
X1472146Y55513D03*
X1468371Y68581D03*
X1474746Y60513D03*
X1477606Y60438D03*
X1468384Y80581D03*
X1474874Y85731D03*
X1483287Y86012D03*
X1472514Y88801D03*
X1478428Y86046D03*
X1475431Y94351D03*
X1479380Y94279D03*
X1470567Y103621D03*
X1478624Y116594D03*
X1466278Y112083D03*
X1484567Y110784D03*
X1478624Y119594D03*
X1479058Y124283D03*
X1484124Y124879D03*
X1477465Y161306D03*
X1469221Y152562D03*
X1474716Y157370D03*
X1478800Y168665D03*
Y176665D03*
X1469913Y183834D03*
X1470023Y178560D03*
X1470086Y172665D03*
X1470899Y186629D03*
X1469433Y190185D03*
X1478800Y192665D03*
Y196665D03*
X1470203Y200864D03*
X1478913Y186778D03*
X1478832Y204864D03*
X1470292Y212455D03*
X1470226Y207037D03*
X1478832Y208864D03*
X1467593Y221642D03*
X1474473Y219379D03*
X1475101Y228631D03*
X1480589Y248371D03*
X1471507Y265897D03*
X1469007D03*
X1477549Y327200D03*
Y322700D03*
Y345200D03*
Y340700D03*
Y331700D03*
Y358700D03*
Y349700D03*
Y354200D03*
X1480702Y368516D03*
X1468309Y408861D03*
X1475236Y412482D03*
X1466231Y423671D03*
X1469538Y416795D03*
X1466653Y428582D03*
X1471375Y433115D03*
X1477597Y682997D03*
X1475264Y680933D03*
X1474713Y685247D03*
X1479297Y693630D03*
X1476794Y691447D03*
X1476716Y704398D03*
X1479500Y689630D03*
Y697630D03*
X1474425Y712925D03*
X1479759Y720885D03*
X1469957Y706957D03*
X1474000Y707000D03*
X1479794Y709388D03*
X1472000Y727500D03*
X1469116Y719055D03*
X1480000Y731500D03*
X1479759Y743500D03*
X1479657Y735500D03*
X1469957Y750957D03*
X1476716Y748398D03*
X1480000Y739500D03*
X1471006Y744818D03*
X1470801Y739280D03*
X1474425Y756925D03*
X1479665Y754555D03*
X1474000Y753093D03*
X1476677Y827626D03*
X1473489Y861354D03*
X1474060Y877196D03*
X1473468Y874267D03*
X1482387Y872940D03*
X1474883Y868206D03*
X1473433Y891043D03*
X1473387Y897425D03*
X1482195Y885807D03*
X1470925Y920575D03*
X1480343Y914776D03*
X1480109Y943496D03*
X1480144Y946880D03*
X1479441Y961941D03*
X1480414Y952214D03*
X1476500Y974000D03*
X1482237Y966028D03*
X1479196Y970000D03*
X1480414Y975064D03*
X1475096Y980330D03*
X1471096D03*
X1479096Y988813D03*
X1471296D03*
X1475096D03*
X1483096D03*
X1475062Y1008300D03*
Y1002453D03*
X1482535Y1024254D03*
X1468869Y1018469D03*
X1476230Y1030672D03*
X1473230D03*
X1471374Y1118654D03*
X1474384Y1109564D03*
X1480231D03*
X1474384Y1122164D03*
X1480231D03*
X1474384Y1134764D03*
X1480231D03*
X1474384Y1147364D03*
X1480231D03*
X1474384Y1172564D03*
X1480231D03*
X1474384Y1159964D03*
X1480231D03*
X1474384Y1185164D03*
X1480231D03*
X1483308Y1214372D03*
X1479063Y1218169D03*
X1498621Y19043D03*
X1489556Y17645D03*
X1498621Y31043D03*
Y23043D03*
X1489829Y29424D03*
X1490563Y23043D03*
X1500210Y97667D03*
X1483287Y94374D03*
X1490593Y116594D03*
X1495866Y102495D03*
X1489567Y110784D03*
X1490593Y119594D03*
X1494127Y125107D03*
X1489146Y124663D03*
X1495600Y142862D03*
X1496641Y148717D03*
X1490490Y138838D03*
X1493260Y226320D03*
X1493194Y221970D03*
X1490481Y216385D03*
X1493194Y216970D03*
Y219470D03*
X1486681Y218085D03*
X1483881D03*
X1496221Y228646D03*
X1495178Y232971D03*
X1491828Y244571D03*
X1489208Y249108D03*
X1499171Y256394D03*
X1497446Y295877D03*
X1486860Y327200D03*
X1500659Y330024D03*
X1495605Y322700D03*
X1487318Y318200D03*
X1486360Y322700D03*
Y345200D03*
X1500386Y344642D03*
X1486913Y340327D03*
X1487152Y331272D03*
X1495689Y332534D03*
X1495521Y340700D03*
X1486360Y349700D03*
X1495521Y349681D03*
X1495925Y358700D03*
X1499839Y354001D03*
X1486890Y368576D03*
X1494286Y372699D03*
X1488000Y731500D03*
X1495500Y750500D03*
X1488731Y739500D03*
X1496629Y765000D03*
X1496763Y777000D03*
X1493301Y776911D03*
X1496814Y773000D03*
X1497000Y781000D03*
X1496756Y785000D03*
X1491425Y798425D03*
X1499633Y787794D03*
X1493716Y789898D03*
X1486957Y792457D03*
X1495170Y796670D03*
X1487050Y809413D03*
X1496845Y809000D03*
X1496806Y817000D03*
X1496621Y829000D03*
X1496447Y821000D03*
X1486386Y825296D03*
X1493092Y820444D03*
X1493038Y833898D03*
X1495240Y825000D03*
X1491425Y842425D03*
X1486957Y836457D03*
X1492625Y837324D03*
X1488138Y878339D03*
Y872839D03*
X1482566Y882154D03*
X1494954Y895264D03*
X1484824Y927324D03*
X1487240Y924453D03*
X1497063Y934000D03*
X1496072Y940201D03*
X1483324Y939324D03*
X1482921Y931324D03*
X1485500Y932500D03*
X1497075Y961000D03*
X1487240Y952012D03*
X1496072Y953981D03*
X1495500Y972500D03*
X1489500D03*
X1487096Y988813D03*
X1491096D03*
X1495096D03*
X1499096D03*
X1490235Y1004816D03*
X1487266Y1002046D03*
X1486030Y1016827D03*
X1491877D03*
X1486030Y1029427D03*
X1491877D03*
X1496140Y1105091D03*
X1496185Y1102091D03*
X1496140Y1117691D03*
X1496185Y1114691D03*
Y1127291D03*
X1496140Y1130291D03*
X1496185Y1139891D03*
X1496140Y1155491D03*
Y1142891D03*
X1496185Y1152491D03*
X1496140Y1168091D03*
X1496185Y1165091D03*
X1496140Y1180691D03*
X1496185Y1177691D03*
X1482705Y1200001D03*
X1489793Y1207737D03*
X1497693Y1230407D03*
X1508670Y103411D03*
X1509064Y97667D03*
X1504460Y95111D03*
X1509310Y114655D03*
Y111255D03*
X1508829Y106561D03*
X1502010Y121742D03*
X1509310Y125428D03*
Y128828D03*
X1502010Y118342D03*
Y132515D03*
Y135915D03*
X1502741Y143762D03*
X1506689Y195176D03*
X1506207Y199248D03*
X1501689Y195176D03*
X1503207Y199248D03*
X1499189Y195176D03*
X1504189D03*
X1506207Y202048D03*
X1503207Y201748D03*
X1499270Y210509D03*
X1501043Y206806D03*
X1501770Y210509D03*
X1503543Y206806D03*
X1509807Y230117D03*
X1500962Y230556D03*
X1505217Y227824D03*
X1505823Y238714D03*
X1499947Y242078D03*
X1505304Y246874D03*
X1507524Y244297D03*
X1503884Y295549D03*
X1501500Y321000D03*
X1501000Y317500D03*
X1501684Y336561D03*
X1516838Y347422D03*
X1515909Y354601D03*
X1511950Y401513D03*
Y398113D03*
X1509550Y412287D03*
Y415687D03*
Y426460D03*
Y440633D03*
Y429860D03*
Y444033D03*
X1516636Y458711D03*
X1509550Y472787D03*
Y469387D03*
Y483560D03*
Y486960D03*
Y516921D03*
Y513521D03*
Y527694D03*
Y531094D03*
X1513284Y552466D03*
X1504495Y796844D03*
X1510527Y833500D03*
X1504938Y859711D03*
X1500353Y859855D03*
X1500638Y873839D03*
X1512712Y867418D03*
X1502158Y899479D03*
X1510527Y908951D03*
X1513927D03*
X1504208Y909740D03*
X1509274Y921226D03*
X1505337Y921240D03*
X1509500Y937000D03*
Y944138D03*
X1516500Y947500D03*
X1501812Y938397D03*
X1512161Y957541D03*
X1509500Y950500D03*
X1498973Y975443D03*
X1511000Y970500D03*
X1511096Y988813D03*
X1507096D03*
X1503096D03*
X1515096D03*
X1513286Y1012354D03*
X1507831Y1009354D03*
X1507786Y1012354D03*
Y1024954D03*
X1513286D03*
X1507831Y1021954D03*
X1503572Y1034538D03*
X1501640Y1105091D03*
Y1117691D03*
Y1130291D03*
Y1142891D03*
Y1155491D03*
Y1168091D03*
Y1180691D03*
X1508356Y1220068D03*
X1500675Y1227300D03*
X1506807Y1234921D03*
X1507692Y1224472D03*
X1507058Y1229402D03*
X1517261Y-33758D03*
Y-30358D03*
X1525172Y90615D03*
X1519860Y90650D03*
X1529493Y99961D03*
X1529543Y95236D03*
X1519610D03*
X1528355Y210478D03*
Y215478D03*
Y212978D03*
Y207978D03*
X1519321Y378600D03*
X1519952Y391001D03*
X1519321Y382600D03*
X1519952Y394401D03*
Y408574D03*
Y405174D03*
Y422747D03*
Y419347D03*
Y436921D03*
Y433521D03*
X1519436Y458711D03*
X1521963Y453682D03*
X1520200Y455921D03*
X1518780Y463600D03*
X1519952Y479899D03*
Y476499D03*
Y490673D03*
Y494073D03*
Y520633D03*
Y524033D03*
Y534806D03*
Y538206D03*
X1519185Y603600D03*
Y619600D03*
Y623600D03*
X1520729Y634190D03*
X1524200Y646098D03*
X1518517Y878898D03*
X1518452Y873780D03*
X1525022Y909558D03*
X1522881Y901034D03*
X1522954Y897951D03*
X1521085Y921094D03*
X1515179D03*
X1527267Y932647D03*
X1522209Y937846D03*
X1521500Y947500D03*
X1528500Y947612D03*
X1529128Y952978D03*
X1521085Y957340D03*
X1525583Y968500D03*
X1530767Y972981D03*
X1519863Y977637D03*
X1525005Y974323D03*
X1530594Y979952D03*
X1531096Y988813D03*
X1523096D03*
X1519096D03*
X1527096Y997860D03*
X1526810Y1025090D03*
X1522904Y1021256D03*
X1521939Y1040818D03*
X1522099Y1035521D03*
X1531993Y1056453D03*
X1531961Y1050849D03*
X1524953Y1051037D03*
X1517855Y1053457D03*
X1538407Y85539D03*
Y82939D03*
Y75139D03*
Y80339D03*
Y77739D03*
X1546732Y98551D03*
X1538451Y92874D03*
X1540478Y107649D03*
Y104249D03*
X1545044Y147540D03*
X1540100Y162368D03*
X1537500D03*
X1547200Y162793D03*
Y165393D03*
Y167993D03*
Y170493D03*
X1546197Y181426D03*
X1546405Y184221D03*
X1538811Y213213D03*
Y210713D03*
X1542883Y211695D03*
X1545383D03*
X1542883Y208695D03*
X1545683D03*
X1538811Y208213D03*
Y215713D03*
X1534184Y264180D03*
X1531684D03*
X1531609Y258880D03*
X1549060Y265701D03*
X1545878Y270026D03*
X1543378D03*
X1540578D03*
X1543378Y267526D03*
X1540578D03*
X1545878D03*
X1544736Y305156D03*
X1545583Y316363D03*
X1539140Y320863D03*
X1545636Y325363D03*
X1542797Y329863D03*
X1545846Y334363D03*
X1544951Y343363D03*
X1538133Y354553D03*
X1545434Y352363D03*
X1546183Y541863D03*
Y545263D03*
X1544375Y553407D03*
X1546875D03*
X1544375Y550907D03*
X1546875D03*
X1542704Y572162D03*
X1543946Y569928D03*
X1546293Y570962D03*
X1546036Y568475D03*
X1548080Y910757D03*
X1547644Y903060D03*
X1532067Y1041832D03*
X1531947Y1046212D03*
X1531546Y1062769D03*
X1536909Y1151870D03*
Y1159350D03*
X1540649Y1155610D03*
X1562828Y72615D03*
Y76587D03*
X1564267Y100625D03*
X1557286Y97475D03*
X1549627Y111223D03*
Y114623D03*
X1557217Y106186D03*
X1550282Y103783D03*
X1549627Y128796D03*
X1560029Y132509D03*
Y121735D03*
Y118335D03*
X1549627Y125396D03*
X1560029Y135909D03*
X1548816Y141247D03*
X1564846D03*
X1556283Y143740D03*
X1553663Y148277D03*
X1552203Y181009D03*
X1549408Y181366D03*
X1557378Y168697D03*
X1554705Y172190D03*
X1554124Y177616D03*
X1558466Y191941D03*
X1549022Y184012D03*
X1560475Y206767D03*
X1562975D03*
X1554144Y213132D03*
X1550441Y211359D03*
Y213859D03*
X1560605Y221708D03*
X1560020Y224421D03*
X1563105Y221708D03*
X1561720Y231021D03*
Y228221D03*
X1554144Y215632D03*
X1562271Y236189D03*
X1562212Y248765D03*
X1554388Y256303D03*
X1559163Y266114D03*
X1554147Y265896D03*
X1562409Y268195D03*
Y270695D03*
X1556636Y281982D03*
X1550695Y281716D03*
X1550931Y305158D03*
X1554403Y316363D03*
X1553534Y327337D03*
X1553910Y331798D03*
X1553597Y336601D03*
X1553862Y344867D03*
X1551175Y347283D03*
X1556588Y545528D03*
X1548359Y569426D03*
X1548645Y566929D03*
X1562385Y610400D03*
X1564670Y650122D03*
X1565132Y668153D03*
X1561552Y665455D03*
X1548629Y927836D03*
X1548504Y915689D03*
X1548616Y931602D03*
X1551163Y952888D03*
X1552000Y969850D03*
X1571895Y58013D03*
X1570733Y68581D03*
X1577108Y60513D03*
X1570746Y80581D03*
X1577236Y85731D03*
X1574876Y88801D03*
X1581742Y94279D03*
X1577793Y94351D03*
X1572929Y103621D03*
X1568640Y112083D03*
X1581420Y124283D03*
X1569333Y143518D03*
X1568433Y152373D03*
X1579827Y161306D03*
X1571583Y152562D03*
X1577078Y157370D03*
X1572275Y183834D03*
X1566990Y171523D03*
X1572385Y178560D03*
X1572448Y172665D03*
X1573261Y186629D03*
X1571795Y190185D03*
X1566520Y192490D03*
X1572565Y200864D03*
X1565475Y206767D03*
X1572654Y212455D03*
X1572588Y207037D03*
X1581194Y208864D03*
X1565605Y221708D03*
X1569955Y221642D03*
X1576835Y219379D03*
X1577463Y228631D03*
X1564771Y236189D03*
X1567271D03*
X1564712Y248765D03*
X1567212D03*
X1567709Y270695D03*
X1573869Y265897D03*
X1571369D03*
X1567709Y268195D03*
X1564909Y270695D03*
Y268195D03*
X1563877Y325363D03*
Y316363D03*
X1571625Y344131D03*
X1574775Y333549D03*
X1563877Y329863D03*
Y343363D03*
Y334363D03*
X1578587Y341787D03*
X1578420Y338309D03*
X1574775Y344127D03*
X1563877Y352363D03*
X1575935Y382109D03*
X1577862Y554121D03*
X1575934Y561420D03*
Y558917D03*
X1565323Y577716D03*
X1571755Y577937D03*
X1579760Y595500D03*
X1574760Y606929D03*
X1579260Y604567D03*
X1574720Y618400D03*
X1575001Y612592D03*
X1580418Y610072D03*
X1580354Y616317D03*
X1576297Y627600D03*
X1577077Y631712D03*
X1574880Y645891D03*
X1571888Y649380D03*
X1572141Y662981D03*
X1578000Y678776D03*
X1569434Y677111D03*
X1568872Y686971D03*
X1575192Y707592D03*
X1592187Y-69306D03*
Y-72706D03*
X1582187Y-33786D03*
Y-30386D03*
X1579968Y60438D03*
X1585649Y86012D03*
Y94374D03*
X1580790Y86046D03*
X1592955Y116594D03*
X1580986D03*
X1586929Y110784D03*
X1591929D03*
X1592955Y119594D03*
X1580986D03*
X1596489Y125107D03*
X1586486Y124879D03*
X1591508Y124663D03*
X1592852Y138838D03*
X1581162Y168665D03*
Y176665D03*
Y192665D03*
Y196665D03*
X1581275Y186778D03*
X1581194Y204864D03*
X1586243Y218085D03*
X1595622Y226320D03*
X1592843Y216385D03*
X1595556Y216970D03*
Y219470D03*
Y221970D03*
X1589043Y218085D03*
X1594190Y244571D03*
X1591570Y249108D03*
X1582951Y248371D03*
X1595069Y337361D03*
X1595109Y342663D03*
X1594466Y350984D03*
X1592635Y455911D03*
X1591443Y465332D03*
X1595460Y549800D03*
X1595260Y547075D03*
X1594760Y568000D03*
X1595364Y562800D03*
X1595300Y558800D03*
X1596790Y1442557D03*
X1592643Y1460707D03*
X1593019Y1457557D03*
X1591775Y1473090D03*
X1596038Y1492000D03*
X1591925Y1512075D03*
X1591333Y1501980D03*
X1590748Y1523377D03*
X1602572Y97667D03*
X1611032Y103411D03*
X1611426Y97667D03*
X1606822Y95111D03*
X1611672Y111255D03*
Y114655D03*
X1598228Y102495D03*
X1611191Y106561D03*
X1604372Y118342D03*
X1611672Y125428D03*
X1604372Y121742D03*
X1611672Y128828D03*
X1604372Y132515D03*
Y135915D03*
X1597962Y142862D03*
X1605103Y143762D03*
X1599003Y148717D03*
X1604051Y195176D03*
X1605569Y199248D03*
X1601551Y195176D03*
X1606551D03*
X1609051D03*
X1608569Y199248D03*
X1603405Y206806D03*
X1605905D03*
X1601632Y210509D03*
X1604132D03*
X1608569Y202048D03*
X1605569Y201748D03*
X1603324Y230556D03*
X1607579Y227824D03*
X1612169Y230117D03*
X1598583Y228646D03*
X1608185Y238714D03*
X1602309Y242078D03*
X1607666Y246874D03*
X1597540Y232971D03*
X1609886Y244297D03*
X1604677Y253198D03*
X1596691Y287397D03*
X1596197Y293477D03*
X1607947Y332326D03*
X1605966Y343794D03*
X1602138Y351047D03*
X1596253Y375633D03*
X1596534Y379760D03*
X1599527Y396718D03*
X1596760Y530000D03*
X1596260Y540500D03*
X1611316Y685800D03*
X1611027Y722427D03*
X1611327Y735973D03*
X1611627Y780327D03*
X1609500Y776100D03*
X1611873Y795127D03*
X1606190Y803774D03*
X1606709Y819165D03*
X1600333Y1440504D03*
X1596836Y1446488D03*
X1600333Y1449068D03*
X1601968Y1453442D03*
X1597457Y1460662D03*
X1605430Y1468023D03*
X1597039Y1475100D03*
X1599726Y1474990D03*
X1600008Y1488492D03*
X1601500Y1514500D03*
X1608500Y1506000D03*
Y1515000D03*
X1613790Y1531334D03*
X1609348Y1527334D03*
X1613790Y1523334D03*
X1604000Y1519000D03*
X1600732Y1539334D03*
X1609348Y1535334D03*
X1598574Y1543373D03*
X1622222Y90650D03*
X1627534Y90615D03*
X1621972Y95236D03*
X1626147Y351033D03*
X1628636Y422088D03*
X1623955Y442956D03*
X1625772Y438323D03*
X1621596Y456386D03*
X1625938Y445873D03*
X1620385Y465874D03*
X1616622Y546712D03*
Y542712D03*
X1618538Y618288D03*
X1614538D03*
X1627224Y643252D03*
X1613362Y656321D03*
X1621362D03*
X1617362D03*
X1616260Y678462D03*
X1619950Y678519D03*
X1615913Y692245D03*
X1628200Y711417D03*
X1612800Y705900D03*
X1620600D03*
X1620500Y723200D03*
X1628343Y747288D03*
X1616683Y744517D03*
X1620100Y738300D03*
X1624000Y760900D03*
X1612573Y761427D03*
X1628027Y801427D03*
X1613117Y828117D03*
X1640769Y85539D03*
Y82939D03*
Y75139D03*
Y80339D03*
Y77739D03*
X1640813Y92874D03*
X1631905Y95236D03*
X1631855Y99961D03*
X1642840Y104249D03*
Y107649D03*
X1639862Y162368D03*
X1642462D03*
X1641173Y213213D03*
Y210713D03*
Y208213D03*
X1630717Y210478D03*
Y215478D03*
Y212978D03*
Y207978D03*
X1641173Y215713D03*
X1634046Y264180D03*
X1636546D03*
X1633971Y258880D03*
X1642940Y267526D03*
Y270026D03*
X1629553Y329067D03*
X1629302Y334402D03*
X1640030Y335550D03*
X1636561Y343072D03*
X1629514Y331727D03*
X1630691Y347432D03*
X1640197Y374690D03*
X1638340Y379536D03*
X1641615Y379600D03*
X1635170Y442856D03*
X1632439Y452265D03*
X1633225Y458455D03*
X1636271Y453881D03*
X1635185Y446595D03*
X1635283Y728117D03*
X1630327Y774627D03*
X1629927Y787327D03*
X1644552Y871353D03*
X1635176Y886761D03*
X1644718Y909263D03*
X1635000Y919263D03*
X1644325Y942120D03*
X1637771Y952120D03*
X1640581Y1551907D03*
X1649094Y98551D03*
X1659648Y97475D03*
X1651989Y114623D03*
Y111223D03*
X1652644Y103783D03*
X1659579Y106186D03*
X1651989Y125396D03*
Y128796D03*
X1647406Y147540D03*
X1651178Y141247D03*
X1658645Y143740D03*
X1656025Y148277D03*
X1649562Y162793D03*
Y165393D03*
Y167993D03*
Y170493D03*
X1656486Y177616D03*
X1654565Y181009D03*
X1648559Y181426D03*
X1651770Y181366D03*
X1659740Y168697D03*
X1657067Y172190D03*
X1660828Y191941D03*
X1651384Y184012D03*
X1648767Y184221D03*
X1647745Y211695D03*
X1645245Y208695D03*
X1648045D03*
X1656506Y213132D03*
X1652803Y211359D03*
Y213859D03*
X1645245Y211695D03*
X1656506Y215632D03*
X1656750Y256303D03*
X1656509Y265896D03*
X1661525Y266114D03*
X1651422Y265701D03*
X1648240Y267526D03*
X1645740D03*
Y270026D03*
X1648240D03*
X1653057Y281716D03*
X1658998Y281982D03*
X1658200Y315039D03*
X1654771Y352088D03*
X1645685Y381500D03*
X1648835Y390500D03*
X1650044Y435158D03*
X1649789Y440489D03*
X1646209Y442606D03*
X1650087Y444841D03*
X1649773Y449961D03*
X1653490Y458572D03*
X1645826Y446606D03*
X1647133Y463479D03*
X1647604Y467367D03*
X1656112Y768669D03*
X1657042Y773604D03*
X1647402Y881460D03*
X1648375Y886766D03*
X1650205Y925911D03*
X1647763Y919268D03*
X1648387Y945554D03*
X1647470Y952125D03*
X1651443Y981515D03*
X1647565Y981432D03*
X1652944Y993796D03*
X1653414Y990590D03*
X1676870Y55513D03*
X1673095Y68581D03*
X1679470Y60513D03*
X1673108Y80581D03*
X1665190Y76587D03*
Y72615D03*
X1679598Y85731D03*
X1677238Y88801D03*
X1675291Y103621D03*
X1666629Y100625D03*
X1671002Y112083D03*
X1662391Y118335D03*
Y121735D03*
Y132509D03*
Y135909D03*
X1667208Y141247D03*
X1671695Y143518D03*
X1670795Y152373D03*
X1673945Y152562D03*
X1674637Y183834D03*
X1669352Y171523D03*
X1674810Y172665D03*
X1674747Y178560D03*
X1675623Y186629D03*
X1674157Y190185D03*
X1668882Y192490D03*
X1667318Y198828D03*
X1674927Y200864D03*
X1664840Y192300D03*
X1662837Y206767D03*
X1667837D03*
X1665337D03*
X1674950Y207037D03*
X1675016Y212455D03*
X1667967Y221708D03*
X1665467D03*
X1664082Y231021D03*
Y228221D03*
X1672317Y221642D03*
X1662967Y221708D03*
X1662382Y224421D03*
X1669633Y236189D03*
X1667133D03*
X1664633D03*
X1667074Y248765D03*
X1664574D03*
X1669574D03*
X1676231Y265897D03*
X1673731D03*
X1670071Y268195D03*
Y270695D03*
X1667271Y268195D03*
X1664771D03*
Y270695D03*
X1667271D03*
X1673203Y328867D03*
X1668979Y339559D03*
X1666860Y353661D03*
X1663650Y353283D03*
X1673723Y353881D03*
X1670323Y353534D03*
X1670260Y377912D03*
X1669260Y391496D03*
X1663618Y393858D03*
X1663780Y384410D03*
X1666959Y382047D03*
X1670260Y386500D03*
X1669260Y409000D03*
X1665260Y398583D03*
X1670348Y397912D03*
X1667260Y403500D03*
X1663713Y440869D03*
Y438269D03*
X1666513Y433069D03*
Y430469D03*
Y435669D03*
Y440869D03*
Y438269D03*
X1663713Y433069D03*
Y430469D03*
Y435669D03*
X1664567Y451677D03*
X1667067D03*
X1664567Y454177D03*
X1667067D03*
X1666271Y460218D03*
Y463618D03*
X1682330Y60438D03*
X1688011Y86012D03*
Y94374D03*
X1683152Y86046D03*
X1680155Y94351D03*
X1684104Y94279D03*
X1683348Y116594D03*
X1694291Y110784D03*
X1689291D03*
X1683348Y119594D03*
X1683782Y124283D03*
X1693870Y124663D03*
X1688848Y124879D03*
X1695214Y138838D03*
X1682189Y161306D03*
X1679440Y157370D03*
X1683524Y168665D03*
Y176665D03*
Y192665D03*
X1683637Y186778D03*
X1683556Y204864D03*
Y208864D03*
X1688605Y218085D03*
X1691405D03*
X1679197Y219379D03*
X1679825Y228631D03*
X1693932Y249108D03*
X1685313Y248371D03*
X1686339Y314890D03*
X1686115Y311740D03*
X1683523Y324518D03*
X1677810Y324466D03*
X1686408Y332584D03*
X1687424Y347937D03*
X1692676Y348015D03*
X1688593Y353470D03*
X1691182Y357016D03*
X1680518Y377912D03*
Y381912D03*
Y397912D03*
X1692253Y467306D03*
Y470706D03*
Y484879D03*
Y481479D03*
Y511439D03*
Y514839D03*
Y529013D03*
Y525613D03*
X1689920Y539315D03*
X1689236Y550137D03*
X1692028D03*
X1692253Y561479D03*
Y564879D03*
Y575652D03*
Y579052D03*
Y593225D03*
Y603999D03*
Y589825D03*
Y607399D03*
X1693000Y626912D03*
X1692379Y622912D03*
X1704934Y97667D03*
X1709184Y95111D03*
X1695317Y116594D03*
X1700590Y102495D03*
X1695317Y119594D03*
X1706734Y118342D03*
Y132515D03*
Y121742D03*
X1698851Y125107D03*
X1706734Y135915D03*
X1700324Y142862D03*
X1707465Y143762D03*
X1701365Y148717D03*
X1708913Y195176D03*
X1710931Y199248D03*
X1706413Y195176D03*
X1703913D03*
X1707931Y199248D03*
Y201748D03*
X1706494Y210509D03*
X1703994D03*
X1705767Y206806D03*
X1708267D03*
X1697984Y226320D03*
X1695205Y216385D03*
X1697918Y216970D03*
Y219470D03*
Y221970D03*
X1705686Y230556D03*
X1709941Y228747D03*
X1700945Y228646D03*
X1704671Y242078D03*
X1699902Y232971D03*
X1696552Y244571D03*
X1703895Y256394D03*
X1700223Y292141D03*
X1703609Y287320D03*
X1698292Y303962D03*
X1702655Y474418D03*
Y477818D03*
Y488591D03*
Y491991D03*
Y521952D03*
Y518552D03*
Y536125D03*
Y532725D03*
X1698716Y550065D03*
X1702655Y571991D03*
Y568591D03*
Y586165D03*
Y582765D03*
Y600338D03*
Y596938D03*
Y611111D03*
Y614511D03*
X1708015Y1142700D03*
X1711333Y1146609D03*
X1706450Y1173065D03*
X1703400Y1174400D03*
X1713394Y103411D03*
X1713788Y97667D03*
X1724584Y90650D03*
X1724334Y95236D03*
X1714034Y111255D03*
Y114655D03*
X1713553Y106561D03*
X1714034Y125428D03*
Y128828D03*
X1711413Y195176D03*
X1710931Y202048D03*
X1714531Y230117D03*
X1710547Y238714D03*
X1710028Y246874D03*
X1712248Y244297D03*
X1716755Y326179D03*
X1712226Y344028D03*
X1715930Y340969D03*
X1715590Y331719D03*
X1721746Y377173D03*
X1715228Y387966D03*
X1718851Y391533D03*
X1720571Y385644D03*
X1725746Y385123D03*
X1718318Y399918D03*
X1725154Y406060D03*
X1725415Y416289D03*
Y418889D03*
Y421489D03*
X1721423Y412106D03*
X1716310Y454334D03*
X1724627Y459330D03*
X1724580Y454214D03*
X1724923Y449045D03*
X1724930Y473571D03*
Y476071D03*
Y478571D03*
Y481071D03*
X1710174Y553101D03*
X1717626Y1134729D03*
X1710511Y1138130D03*
X1721008Y1134729D03*
X1723805Y1142666D03*
X1725008Y1134636D03*
X1725680Y1157544D03*
X1724191Y1167768D03*
X1713239Y1176038D03*
X1712526Y1171950D03*
X1728343Y1185205D03*
X1719692Y1187215D03*
X1719385Y1180175D03*
X1712715Y1188500D03*
X1721662Y1201043D03*
X1725658D03*
X1718625Y1199814D03*
X1712542Y1196600D03*
X1720536Y1217228D03*
X1723200Y1219895D03*
X1710825Y1231688D03*
X1712966Y1229841D03*
X1736405Y-69278D03*
Y-72678D03*
X1743175Y92874D03*
X1729896Y90615D03*
X1734267Y95236D03*
X1734217Y99961D03*
X1742224Y162368D03*
X1733079Y207978D03*
Y210478D03*
Y215478D03*
Y212978D03*
X1736408Y264180D03*
X1738908D03*
X1736333Y258880D03*
X1744524Y379429D03*
X1741746Y377173D03*
X1737786D03*
X1729751D03*
X1733746Y385123D03*
X1730746D03*
X1737746D03*
X1741420Y391569D03*
X1739847Y401066D03*
X1729508Y403300D03*
X1728915Y405889D03*
Y408489D03*
Y413689D03*
Y411089D03*
Y416289D03*
Y421489D03*
Y418889D03*
Y424089D03*
X1729302Y432718D03*
Y435518D03*
X1739179Y439318D03*
X1728915Y426689D03*
X1739179Y442118D03*
X1733014Y450091D03*
X1730014D03*
X1727404Y447209D03*
X1730404D03*
X1738824Y456034D03*
Y461034D03*
X1733014Y462060D03*
X1730014D03*
X1734952Y479217D03*
X1737646Y477213D03*
Y479713D03*
X1729002Y477053D03*
X1731502D03*
X1734952Y476717D03*
X1741800Y917900D03*
X1742029Y1116251D03*
X1739508Y1137129D03*
X1729008Y1134729D03*
X1732881D03*
X1739917Y1150087D03*
X1732137Y1157404D03*
X1737393Y1170767D03*
X1729210Y1167768D03*
X1728333Y1178240D03*
X1733052Y1187310D03*
X1737689Y1185238D03*
X1737482Y1180235D03*
X1733662Y1201039D03*
X1729628Y1201043D03*
X1737662Y1200969D03*
X1737781Y1208993D03*
X1726475Y1223170D03*
X1731533Y1228226D03*
X1729322Y1226016D03*
X1743131Y85539D03*
Y82939D03*
Y75139D03*
Y80339D03*
Y77739D03*
X1751456Y98551D03*
X1754351Y111223D03*
Y114623D03*
X1755006Y103783D03*
X1745202Y104249D03*
Y107649D03*
X1754351Y128796D03*
Y125396D03*
X1744824Y162368D03*
X1751924Y162793D03*
Y165393D03*
Y167993D03*
Y170493D03*
X1758848Y177616D03*
X1759429Y172190D03*
X1756927Y181009D03*
X1750921Y181426D03*
X1754132Y181366D03*
X1751129Y184221D03*
X1753746Y184012D03*
X1747607Y211695D03*
X1755165Y211359D03*
Y213859D03*
X1750107Y211695D03*
X1747607Y208695D03*
X1750407D03*
X1743535Y208213D03*
Y213213D03*
Y210713D03*
Y215713D03*
X1753784Y265701D03*
X1758871Y265896D03*
X1750602Y267526D03*
X1745302D03*
X1748102D03*
X1745302Y270026D03*
X1748102D03*
X1750602D03*
X1755419Y281716D03*
X1748497Y371060D03*
X1752497Y371076D03*
X1750135Y379088D03*
X1755433Y379028D03*
X1744180Y383966D03*
X1750187Y409539D03*
X1753187D03*
X1750187Y406739D03*
X1753187Y407039D03*
X1752851Y401981D03*
X1755351D03*
X1757124Y398278D03*
X1754624D03*
X1749470Y424067D03*
X1751970D03*
X1756970D03*
X1754470D03*
X1749705Y413611D03*
X1752205D03*
X1757205D03*
X1754705D03*
X1756844Y438293D03*
X1747179Y439318D03*
X1756844Y441093D03*
X1747179Y442118D03*
X1756844Y443893D03*
X1747306Y470001D03*
X1744806D03*
X1756894Y472020D03*
X1756553Y466409D03*
X1756954Y477318D03*
X1745231Y489036D03*
X1743092Y485580D03*
X1745592D03*
X1748092D03*
X1758401Y484882D03*
X1756391Y487382D03*
X1747467Y492836D03*
Y495636D03*
X1756089Y542952D03*
X1750879Y541940D03*
X1754906Y824333D03*
Y820737D03*
X1746897Y879199D03*
X1746884Y884649D03*
X1747900Y900160D03*
X1744900D03*
X1750915Y902055D03*
X1749267Y918413D03*
X1751200Y931100D03*
X1746600Y935100D03*
X1751854Y991297D03*
X1749314Y987904D03*
X1745824Y987058D03*
X1748677Y993986D03*
X1753860Y997271D03*
X1759569Y1021944D03*
X1744529Y1116251D03*
X1758390Y1577905D03*
X1759947Y1599029D03*
X1750685Y1621654D03*
X1767552Y76587D03*
Y72615D03*
X1762010Y97475D03*
X1768991Y100625D03*
X1761941Y106186D03*
X1773364Y112083D03*
X1764753Y121735D03*
Y118335D03*
Y132509D03*
Y135909D03*
X1771714Y171523D03*
X1776999Y183834D03*
X1762102Y168697D03*
X1763190Y191941D03*
X1771244Y192490D03*
X1776519Y190185D03*
X1767202Y192300D03*
X1765199Y206767D03*
X1770199D03*
X1767699D03*
X1758868Y213132D03*
X1765329Y221708D03*
X1770329D03*
X1767829D03*
X1764744Y224421D03*
X1766444Y231021D03*
Y228221D03*
X1774679Y221642D03*
X1758868Y215632D03*
X1771995Y236189D03*
X1769495D03*
X1766995D03*
X1771936Y248765D03*
X1769436D03*
X1766936D03*
X1759112Y256303D03*
X1763887Y266114D03*
X1767133Y270695D03*
X1769633D03*
X1772433Y268195D03*
Y270695D03*
X1769633Y268195D03*
X1767133D03*
X1761360Y281982D03*
X1762997Y377581D03*
X1765497Y379591D03*
X1772513Y387702D03*
X1769713D03*
X1765913Y389402D03*
X1763200Y388817D03*
Y383817D03*
Y386317D03*
X1766837Y438293D03*
Y441093D03*
Y443893D03*
X1768586Y467560D03*
X1764903Y470382D03*
X1764906Y474382D03*
X1776561Y467560D03*
X1777061Y475560D03*
X1768575D03*
X1770135Y490711D03*
X1758957Y543036D03*
X1773789Y927663D03*
X1765664Y923724D03*
X1769064D03*
X1773789Y930663D03*
X1774476Y995049D03*
X1773810Y990821D03*
X1762486Y990260D03*
X1760201Y992475D03*
X1758881Y995633D03*
X1769004Y1019395D03*
X1768844Y1023694D03*
Y1027248D03*
X1771773Y1028829D03*
X1772188Y1428369D03*
X1766313Y1580198D03*
X1761072Y1590719D03*
X1765040Y1599511D03*
X1760422Y1640303D03*
X1768422D03*
X1772422D03*
X1762041Y1631511D03*
X1768422Y1632245D03*
X1773820Y1631238D03*
X1779232Y55513D03*
X1775457Y68581D03*
X1785246Y60660D03*
X1781832Y60513D03*
X1775470Y80581D03*
X1781960Y85731D03*
X1790712Y81713D03*
X1790664Y71908D03*
X1779600Y88801D03*
X1790373Y94663D03*
X1786466Y85923D03*
Y94279D03*
X1782517Y94351D03*
X1777653Y103621D03*
X1785886Y168665D03*
Y176665D03*
X1777172Y172665D03*
X1777109Y178560D03*
X1777985Y186629D03*
X1785779Y192665D03*
X1785886Y196665D03*
X1777289Y200864D03*
X1785999Y186778D03*
X1785918Y204864D03*
X1777378Y212455D03*
X1777312Y207037D03*
X1785918Y208864D03*
X1781559Y219379D03*
X1782187Y228631D03*
X1778593Y265897D03*
X1776093D03*
X1787674Y303130D03*
X1777681Y387151D03*
Y382151D03*
Y384651D03*
X1786184Y435321D03*
Y438121D03*
X1783384Y435321D03*
Y438121D03*
X1786184Y440921D03*
X1783384D03*
X1786184Y443721D03*
X1783384D03*
X1786170Y448931D03*
X1792527Y452799D03*
X1786693Y459170D03*
X1790061Y474513D03*
X1779404Y826570D03*
X1791041Y818795D03*
X1780016Y874400D03*
X1775904Y924546D03*
X1778047Y916120D03*
X1789537Y930498D03*
X1780158Y953295D03*
X1785758Y956095D03*
Y953295D03*
X1782958D03*
Y956095D03*
X1780158D03*
X1789363Y969160D03*
X1782563Y979660D03*
X1785663D03*
X1779363D03*
X1786863Y985060D03*
X1779143Y995203D03*
X1779033Y1023432D03*
X1786740Y1019237D03*
X1780802Y1019474D03*
X1774863Y1019237D03*
X1774844Y1023694D03*
X1783844D03*
X1786844Y1027248D03*
X1780844D03*
X1774844D03*
X1789844Y1023694D03*
X1775998Y1074707D03*
Y1072207D03*
X1781198Y1074707D03*
X1778598D03*
X1783798D03*
Y1072207D03*
X1778598D03*
X1781198D03*
X1790736Y1072090D03*
Y1074590D03*
X1780326Y1089851D03*
X1777726D03*
X1782926D03*
Y1092351D03*
X1777726D03*
X1780326D03*
X1775126Y1089851D03*
Y1092351D03*
X1790639Y1082585D03*
X1790572Y1085152D03*
X1780662Y1108413D03*
X1783262D03*
X1778062D03*
X1775462D03*
X1785321Y1121122D03*
X1787921D03*
X1790521D03*
X1780566Y1111038D03*
X1783166D03*
X1777966D03*
X1775366D03*
X1790521Y1130822D03*
X1781874Y1139822D03*
X1787921Y1130822D03*
X1785321D03*
X1784374Y1139822D03*
X1781802Y1147822D03*
X1784302D03*
X1783278Y1208140D03*
X1778227Y1438099D03*
X1786091Y1443715D03*
X1787745Y1437765D03*
X1783178Y1437550D03*
X1778104Y1470289D03*
X1801761Y-33888D03*
Y-30488D03*
X1791088Y77296D03*
X1804758Y294429D03*
X1793524Y303343D03*
X1805196Y300952D03*
X1799897Y408104D03*
X1802697D03*
X1805497D03*
X1793475Y424939D03*
X1799614Y420375D03*
X1802414D03*
X1805214D03*
X1793475Y427439D03*
X1809095Y435101D03*
X1803700Y440101D03*
X1803530Y431112D03*
X1809358Y442114D03*
X1803335Y452718D03*
X1809346Y452601D03*
X1797907Y452987D03*
X1809338Y447121D03*
X1804933Y461607D03*
X1796933D03*
X1796136Y471334D03*
X1800933Y461607D03*
X1802000Y892447D03*
X1797365Y930761D03*
X1793474Y930374D03*
X1805463Y969260D03*
X1801963Y969160D03*
X1802363Y989660D03*
X1803351Y1027471D03*
X1805188Y1019078D03*
X1799646Y1018999D03*
X1793470Y1018762D03*
X1801844Y1023694D03*
X1795844D03*
X1798844Y1027248D03*
X1792844D03*
X1795936Y1072090D03*
X1793336D03*
X1798536D03*
Y1074590D03*
X1793336D03*
X1795936D03*
X1801961Y1081717D03*
X1795819Y1088553D03*
X1800813Y1103246D03*
X1806206Y1114589D03*
X1803506D03*
X1800906D03*
X1798306D03*
X1798702Y1124328D03*
X1801302D03*
X1803902D03*
X1806602D03*
X1793221Y1121122D03*
Y1130822D03*
X1804532Y1133356D03*
X1807232D03*
X1807035Y1136912D03*
Y1144912D03*
X1806835Y1214668D03*
X1800489Y1220598D03*
X1807243Y1219955D03*
X1802670Y1210905D03*
X1805126Y1225745D03*
X1799845Y1261044D03*
X1794845D03*
X1797345D03*
X1799845Y1263544D03*
X1797345D03*
X1794845D03*
X1803885Y1435046D03*
X1806428Y1444543D03*
X1795374D03*
X1802813Y1464015D03*
X1803762Y1467236D03*
X1819900Y906900D03*
X1807663Y966660D03*
Y963860D03*
X1808014Y984832D03*
X1812538Y1026859D03*
X1811468Y1021084D03*
X1807844Y1023694D03*
Y1027248D03*
X1810349Y1031264D03*
X1816756Y1089145D03*
Y1094145D03*
X1816235Y1083970D03*
X1810346Y1082250D03*
X1816756Y1097145D03*
Y1101145D03*
X1810310Y1104819D03*
X1809535Y1136912D03*
Y1144912D03*
X1812130Y1205349D03*
X1822594Y1211054D03*
Y1215324D03*
X1814741Y1217093D03*
X1811482Y1226423D03*
X1810018Y1295944D03*
X1812818D03*
X1815618Y1298744D03*
Y1295944D03*
X1812818Y1298744D03*
X1810018D03*
X1812202Y1432624D03*
X1809342Y1476733D03*
X1824706Y1085145D03*
X1824949Y1077145D03*
X1824706Y1100185D03*
Y1106145D03*
X1828272Y1095968D03*
X1824706Y1093150D03*
X1830915Y1109146D03*
X1834665Y1213239D03*
G54D22*
X51750Y617861D03*
X48207D03*
X44664D03*
X51750Y620661D03*
X48207D03*
X44664D03*
X55294Y617861D03*
Y620661D03*
X146948Y1088287D03*
X143208D03*
X146948Y1099507D03*
X143208D03*
X146948Y1106988D03*
X143208D03*
X146948Y1114468D03*
Y1121948D03*
X143208Y1114468D03*
Y1121948D03*
X146948Y1129429D03*
X143208D03*
X146948Y1136909D03*
X143208D03*
X146948Y1148129D03*
X143208D03*
X146947Y1170570D03*
X143207D03*
X146947Y1178051D03*
X143207D03*
X165649Y1073326D03*
X158169D03*
X150689D03*
X165649Y1092027D03*
X158169D03*
X150689D03*
X165649Y1077066D03*
X161909Y1084547D03*
X158169Y1077066D03*
X154429Y1084547D03*
X161909Y1080807D03*
X154429D03*
X165649Y1095767D03*
X161909Y1103247D03*
X158169Y1095767D03*
X154429Y1103247D03*
X150689Y1095767D03*
X161909Y1099507D03*
X154429D03*
X161909Y1118208D03*
Y1121948D03*
X165649Y1110728D03*
X161909D03*
X154429D03*
Y1118208D03*
X150689Y1110728D03*
Y1118208D03*
X154429Y1125688D03*
X150689D03*
Y1133169D03*
X165649D03*
X161909D03*
X154429D03*
X165649Y1148129D03*
Y1144389D03*
Y1155610D03*
X160039Y1176180D03*
X156299D03*
X169389Y1084547D03*
Y1080807D03*
Y1103247D03*
X173129Y1136909D03*
X169389D03*
X176870Y1151870D03*
Y1148129D03*
Y1144389D03*
X169389Y1151870D03*
Y1148129D03*
X176870Y1166830D03*
Y1159350D03*
X169389D03*
X176870Y1174310D03*
Y1178051D03*
Y1181791D03*
X188090Y1114468D03*
X184350D03*
X191830D03*
X195570D03*
X191830Y1140649D03*
Y1136909D03*
X195570Y1140649D03*
X184350Y1136909D03*
X191830Y1133169D03*
Y1129429D03*
Y1144389D03*
Y1151869D03*
X195570Y1148129D03*
Y1155610D03*
X184350Y1144389D03*
X188090Y1155610D03*
X184350Y1151870D03*
X188090Y1148129D03*
X191830Y1159350D03*
Y1170570D03*
X195570Y1166830D03*
X184350Y1159350D03*
Y1170570D03*
X188090Y1166830D03*
X191830Y1185531D03*
Y1178051D03*
X195570Y1181791D03*
Y1174310D03*
X184350Y1185531D03*
X188090Y1181791D03*
Y1174310D03*
X184350Y1178051D03*
X191830Y1193011D03*
X195570Y1215452D03*
X197440Y1217322D03*
X186220D03*
X189960D03*
Y1213582D03*
X203051Y1114468D03*
X199311D03*
X206791D03*
X210531D03*
X206791Y1136909D03*
X203051D03*
X199311D03*
X214271D03*
X210531D03*
X199311Y1129429D03*
X206791D03*
X214271D03*
X210531D03*
X203051D03*
X210531Y1155610D03*
X203051D03*
X206791Y1144389D03*
X203051D03*
X199311D03*
X214271D03*
X210531D03*
X214271Y1151870D03*
X210531D03*
X206791D03*
X203051D03*
X199311D03*
X214271Y1170570D03*
X210531Y1166830D03*
X214271Y1159350D03*
X206791Y1170570D03*
X203051Y1166830D03*
X199311Y1170570D03*
X206791Y1159350D03*
X199311D03*
X203051Y1174310D03*
X210531D03*
X203051Y1185531D03*
X199311D03*
X206791D03*
X214271D03*
X210531D03*
X206791Y1178051D03*
X203051D03*
X199311D03*
X214271D03*
X210531D03*
X214271Y1193011D03*
X210531D03*
X199311D03*
X203051D03*
X206791D03*
X214271Y1200491D03*
X210531D03*
X199311D03*
X206791D03*
X203051D03*
X201181Y1213582D03*
X214271Y1211712D03*
X208661Y1213582D03*
X203051Y1215452D03*
X214271D03*
X201181Y1217322D03*
X208661D03*
X210531Y1215452D03*
X204921Y1213582D03*
X225492Y1114468D03*
X221752D03*
X218011D03*
X225492Y1136909D03*
X221751D03*
X218011D03*
X229232D03*
Y1129429D03*
X218011D03*
X221751D03*
X225492D03*
X218011Y1155610D03*
X225492D03*
Y1144389D03*
X221751D03*
X218011D03*
X229232D03*
Y1151870D03*
X221752D03*
X218011D03*
X225492D03*
Y1166830D03*
X221751Y1170570D03*
X218011Y1166830D03*
X221751Y1159350D03*
X229232Y1170570D03*
Y1159350D03*
X225492Y1174310D03*
X218011D03*
X225492Y1185531D03*
X218011D03*
X221751D03*
X229232D03*
X225492Y1178051D03*
X221751D03*
X218011D03*
X229232D03*
X218011Y1193011D03*
X221751D03*
X225492D03*
X229232D03*
X218011Y1200491D03*
X221751D03*
X225492D03*
X229232D03*
X218011Y1215452D03*
X229232Y1211712D03*
Y1215452D03*
X225492Y1211712D03*
X221752D03*
Y1215452D03*
X240452Y1114468D03*
X244192D03*
X236712Y1118208D03*
X244192D03*
X236712Y1114468D03*
X240452Y1118208D03*
Y1136909D03*
X236712D03*
X244192D03*
Y1129429D03*
X240452D03*
X236712D03*
Y1155610D03*
X244192D03*
X240452Y1151869D03*
X236712D03*
X244192D03*
X240452Y1144389D03*
X236712D03*
X244192D03*
X236712Y1166830D03*
X240452Y1170570D03*
Y1159350D03*
X244192Y1166830D03*
X236712Y1174310D03*
X244192D03*
X240452Y1185531D03*
X236712D03*
X244192D03*
X240452Y1178051D03*
X236712D03*
X244192D03*
X240452Y1193011D03*
X236712D03*
X244192D03*
X236712Y1200491D03*
X244192D03*
X240452D03*
X244192Y1215452D03*
X240452D03*
X242322Y1217322D03*
X236712Y1211712D03*
Y1215452D03*
X238582Y1217322D03*
X262893Y1118208D03*
X259153Y1114468D03*
X262893D03*
X255413Y1118208D03*
Y1114468D03*
X247933D03*
X259153Y1118208D03*
X251673Y1114468D03*
X247933Y1118208D03*
X251673D03*
X255413Y1136909D03*
X251673D03*
X247933D03*
X259153D03*
X262893D03*
X247933Y1129429D03*
X259153D03*
X262893D03*
X255413D03*
X251673D03*
Y1155610D03*
X259153D03*
X251673Y1144389D03*
X247933D03*
X255413D03*
X259153Y1151869D03*
X262893D03*
X247933D03*
X255413D03*
X251673D03*
X262893Y1144389D03*
X259153D03*
X251673Y1166830D03*
X255413Y1170570D03*
X247933D03*
X255413Y1159350D03*
X247933D03*
X259153Y1166830D03*
X262893Y1170570D03*
Y1159350D03*
X251673Y1174310D03*
X259153D03*
X247933Y1185531D03*
X255413D03*
X251673D03*
X259153D03*
X262893D03*
X251673Y1178051D03*
X247933D03*
X255413D03*
X259153D03*
X262893D03*
X251673Y1193011D03*
X255413D03*
X247933D03*
X262893D03*
X259153D03*
Y1200491D03*
X262893D03*
X251673D03*
X247933D03*
X255413D03*
Y1215452D03*
X262893D03*
X247932Y1215451D03*
X259153Y1215452D03*
X251673D03*
X247932Y1211711D03*
X251673D03*
X270373Y1114468D03*
X274114D03*
X277854D03*
X266633Y1136909D03*
Y1129429D03*
X274114D03*
Y1140649D03*
Y1136909D03*
X266633Y1155610D03*
X277854D03*
X266633Y1151869D03*
Y1144389D03*
X274114D03*
X277854Y1159350D03*
Y1166830D03*
Y1170570D03*
X266633D03*
X270373D03*
X266633Y1159350D03*
X270373D03*
Y1166830D03*
X266633D03*
Y1174310D03*
X277854D03*
X266633Y1185531D03*
Y1178051D03*
X270373Y1181791D03*
X274114Y1185531D03*
Y1189271D03*
Y1178051D03*
X266633Y1193011D03*
Y1200491D03*
X274114D03*
Y1193011D03*
X277854Y1204232D03*
Y1196751D03*
Y1200491D03*
X274114Y1215452D03*
X277854D03*
X266633D03*
X274114Y1211712D03*
X277854Y1207972D03*
X285334Y1118208D03*
X281594D03*
X285334Y1114468D03*
X281594D03*
X289074Y1140649D03*
X285334D03*
Y1136909D03*
X292815Y1140649D03*
X285334Y1155610D03*
X281594Y1144389D03*
X285334Y1148129D03*
Y1144389D03*
X289074Y1148129D03*
X292815D03*
Y1155610D03*
X285334Y1170570D03*
Y1166830D03*
Y1159350D03*
X292815Y1170570D03*
X285334Y1174310D03*
X289074Y1189271D03*
X285334D03*
X281594Y1181791D03*
X285334Y1178051D03*
X289074Y1181791D03*
X285334Y1196751D03*
Y1204232D03*
X281594Y1200491D03*
X285334D03*
Y1207972D03*
Y1215452D03*
Y1211712D03*
X281594Y1215452D03*
Y1207972D03*
X311515Y1140649D03*
X304035Y1144389D03*
Y1151869D03*
X307775Y1144389D03*
Y1151869D03*
X296555Y1155610D03*
X311515Y1148129D03*
Y1155610D03*
X304035Y1166830D03*
Y1159350D03*
X307775Y1166830D03*
X296555Y1170570D03*
X311515D03*
X304035Y1174310D03*
Y1181791D03*
Y1189271D03*
X307775Y1174310D03*
Y1181791D03*
Y1189271D03*
X311515Y1178051D03*
Y1185531D03*
Y1193011D03*
X322736Y1136909D03*
X326476D03*
X315255Y1140649D03*
X322736Y1144389D03*
Y1151870D03*
X326476Y1144389D03*
X315255Y1148129D03*
X326476Y1151870D03*
X315255Y1155610D03*
X322736Y1159350D03*
X326476D03*
X315255Y1170570D03*
X322736Y1174310D03*
Y1181791D03*
Y1189271D03*
X326476Y1174310D03*
X315255Y1178051D03*
X326476Y1181791D03*
X315255Y1185531D03*
X326476Y1189271D03*
X315255Y1193011D03*
X425023Y441086D03*
Y433999D03*
Y437543D03*
X422223Y441086D03*
Y433999D03*
Y437543D03*
X425023Y444629D03*
X422223D03*
X501750Y620661D03*
X505293D03*
X501750Y617861D03*
X505293D03*
X512380D03*
X508836Y620661D03*
Y617861D03*
X512380Y620661D03*
X600295Y1088287D03*
X604035D03*
X600295Y1099507D03*
X604035D03*
X600295Y1106988D03*
X604035D03*
Y1121948D03*
X600295D03*
Y1114468D03*
X604035D03*
X600295Y1136909D03*
X604035D03*
X600295Y1129429D03*
X604035D03*
Y1148129D03*
X600295D03*
X604034Y1170570D03*
X600294D03*
X604034Y1178051D03*
X600294D03*
X615256Y1073326D03*
X607776D03*
X618996Y1084547D03*
Y1080807D03*
X615256Y1077066D03*
X611516Y1080807D03*
Y1084547D03*
X607776Y1092027D03*
X615256D03*
X607776Y1095767D03*
X615256D03*
X618996Y1103247D03*
X611516D03*
X618996Y1099507D03*
X611516D03*
X618996Y1118208D03*
Y1121948D03*
X611516Y1118208D03*
X607776D03*
X611516Y1110728D03*
X618996D03*
X607776D03*
X611516Y1125688D03*
X607776D03*
Y1133169D03*
X615256Y1178051D03*
X611516D03*
X622736Y1073326D03*
Y1077066D03*
X626476Y1084547D03*
X622736Y1092027D03*
X626476Y1080807D03*
X622736Y1095767D03*
X626476Y1103247D03*
X622736Y1118208D03*
X626476Y1114468D03*
X622736Y1110728D03*
X630216Y1114468D03*
X633957Y1151870D03*
Y1148129D03*
Y1144389D03*
X626476Y1148129D03*
X622736Y1144389D03*
Y1148129D03*
X626476Y1151870D03*
X622736Y1155610D03*
X633957Y1166830D03*
Y1159350D03*
X626476D03*
X633957Y1174310D03*
Y1178051D03*
Y1181791D03*
X645177Y1114468D03*
X641437D03*
X648917D03*
X652657D03*
X648917Y1140649D03*
Y1136909D03*
X652657Y1140649D03*
X641437Y1136909D03*
X648917Y1129429D03*
Y1133169D03*
X652657Y1148129D03*
Y1155610D03*
X648917Y1144389D03*
Y1151869D03*
X641437Y1144389D03*
Y1151870D03*
X645177Y1155610D03*
Y1148129D03*
X648917Y1159350D03*
Y1170570D03*
X652657Y1166830D03*
X641437Y1170570D03*
X645177Y1166830D03*
X641437Y1159350D03*
X648917Y1185531D03*
Y1178051D03*
X652657Y1181791D03*
Y1174310D03*
X641437Y1185531D03*
Y1178051D03*
X645177Y1181791D03*
Y1174310D03*
X648917Y1193011D03*
X652657Y1215452D03*
Y1219192D03*
X641437Y1215452D03*
X648917D03*
X645177D03*
X660138Y1114468D03*
X656398D03*
X663878D03*
X667618D03*
Y1129429D03*
X660138D03*
X656398D03*
X663878D03*
Y1136909D03*
X660138D03*
X656398D03*
X667618D03*
X660138Y1155610D03*
X667618D03*
Y1144389D03*
X663878D03*
X660138D03*
X656398D03*
X667618Y1151870D03*
X663878D03*
X660138D03*
X656398D03*
X663878Y1170570D03*
X660138Y1166830D03*
X656398Y1170570D03*
X663878Y1159350D03*
X656398D03*
X667618Y1166830D03*
Y1174310D03*
X660138D03*
X667618Y1185531D03*
X660138D03*
X656398D03*
X663878D03*
X667618Y1178051D03*
X663878D03*
X660138D03*
X656398D03*
X667618Y1200491D03*
X656398D03*
X663878D03*
X660138D03*
X663878Y1193011D03*
X660138D03*
X656398D03*
X667618D03*
X663878Y1211712D03*
X656398D03*
X660138Y1215452D03*
X656398D03*
X663878D03*
X667618D03*
X660138Y1211712D03*
X682579Y1114468D03*
X678839D03*
X675098D03*
Y1129429D03*
X671358D03*
X678838D03*
X682579D03*
Y1136909D03*
X678838D03*
X675098D03*
X671358D03*
X682579Y1155610D03*
X675098D03*
X678839Y1151870D03*
X675098D03*
X671358D03*
X682579D03*
Y1144389D03*
X671358D03*
X678838D03*
X675098D03*
X682579Y1166830D03*
X678838Y1170570D03*
X671358D03*
X675098Y1166830D03*
X671358Y1159350D03*
X678838D03*
X682579Y1174310D03*
X675098D03*
X682579Y1185531D03*
X675098D03*
X671358D03*
X678838D03*
X682579Y1178051D03*
X678838D03*
X675098D03*
X671358D03*
X675098Y1200491D03*
X671358D03*
X678838D03*
X682579D03*
Y1193011D03*
X678838D03*
X675098D03*
X671358D03*
X682579Y1211712D03*
X678839D03*
Y1215452D03*
X671358Y1211712D03*
Y1215452D03*
X675098D03*
X693799Y1114468D03*
Y1118208D03*
X701279Y1114468D03*
X697539Y1118208D03*
Y1114468D03*
X701279Y1118208D03*
Y1129429D03*
X697539D03*
X693799D03*
X686319D03*
X697539Y1136909D03*
X693799D03*
X701279D03*
X686319D03*
X701279Y1155610D03*
X693799D03*
X701279Y1151869D03*
X697539D03*
X693799D03*
X701279Y1144389D03*
X697539D03*
X693799D03*
X686319D03*
Y1151870D03*
X693799Y1166830D03*
X697539Y1170570D03*
Y1159350D03*
X701279Y1166830D03*
X686319Y1170570D03*
Y1159350D03*
X701279Y1174310D03*
X693799D03*
X701279Y1185531D03*
X697539D03*
X693799D03*
X701279Y1178051D03*
X697539D03*
X693799D03*
X686319Y1185531D03*
Y1178051D03*
X701279Y1200491D03*
X697539D03*
X693799D03*
X686319D03*
X701279Y1193011D03*
X697539D03*
X693799D03*
X686319D03*
Y1211712D03*
Y1215452D03*
X699409Y1217322D03*
X697539Y1215452D03*
X693799D03*
Y1211712D03*
X701279Y1215452D03*
X695669Y1217322D03*
X708760Y1114468D03*
X716240Y1118208D03*
X705020Y1114468D03*
X712500D03*
X716240D03*
X705020Y1118208D03*
X712500D03*
X708760D03*
X705020Y1129429D03*
X708760D03*
X712500D03*
X716240D03*
Y1136909D03*
X705020D03*
X708760D03*
X712500D03*
X708760Y1155610D03*
X716240D03*
Y1151869D03*
X708760D03*
X712500D03*
X705020D03*
X712500Y1144389D03*
X705020D03*
X708760D03*
X716240D03*
Y1166830D03*
X705020Y1159350D03*
X712500D03*
X705020Y1170570D03*
X712500D03*
X708760Y1166830D03*
X716240Y1174310D03*
X708760D03*
X716240Y1185531D03*
X708760D03*
X712500D03*
X705020D03*
X716240Y1178051D03*
X712500D03*
X705020D03*
X708760D03*
X712500Y1200491D03*
X705020D03*
X708760D03*
X716240D03*
X708760Y1193011D03*
X712500D03*
X705020D03*
X716240D03*
Y1215452D03*
X708760D03*
X712500D03*
X705019Y1215451D03*
Y1211711D03*
X708760D03*
X731201Y1114468D03*
X734941D03*
X727460D03*
X719980Y1118208D03*
Y1114468D03*
Y1129429D03*
X723720D03*
X731201D03*
X719980Y1136909D03*
X723720D03*
X731201D03*
Y1140649D03*
X723720Y1155610D03*
X719980Y1151869D03*
X723720D03*
Y1144389D03*
X719980D03*
X734941Y1155610D03*
X731201Y1144389D03*
X719980Y1159350D03*
X727460D03*
X723720D03*
Y1166830D03*
X727460D03*
X719980Y1170570D03*
X727460D03*
X723720D03*
X734941Y1159350D03*
Y1166830D03*
Y1170570D03*
X723720Y1174310D03*
X727460Y1181791D03*
X719980Y1185531D03*
Y1178051D03*
X723720D03*
Y1185531D03*
X734941Y1174310D03*
X731201Y1189271D03*
Y1185531D03*
Y1178051D03*
X719980Y1200491D03*
X723720D03*
X731201D03*
X719980Y1193011D03*
X723720D03*
X731201D03*
X734941Y1196751D03*
Y1204232D03*
Y1200491D03*
X731201Y1215452D03*
X734941D03*
X723720D03*
X719980D03*
X731201Y1211712D03*
X734941Y1207972D03*
X727461Y1215452D03*
X738681Y1118208D03*
X742421D03*
X738681Y1114468D03*
X742421D03*
Y1140649D03*
Y1136909D03*
X746161Y1140649D03*
X749902D03*
X742421Y1155610D03*
X746161Y1148129D03*
X738681Y1144389D03*
X742421Y1148129D03*
Y1144389D03*
X749902Y1155610D03*
Y1148129D03*
X742421Y1159350D03*
Y1166830D03*
Y1170570D03*
X749902D03*
X742421Y1189271D03*
X746161D03*
X742421Y1174310D03*
X738681Y1181791D03*
X746161D03*
X742421Y1178051D03*
Y1196751D03*
X738681Y1200491D03*
X742421Y1204232D03*
Y1200491D03*
Y1211712D03*
Y1215452D03*
Y1207972D03*
X738681Y1215452D03*
Y1207972D03*
Y1211712D03*
X761122Y1144389D03*
Y1151869D03*
X753642Y1155610D03*
X764862Y1151869D03*
Y1144389D03*
Y1166830D03*
X761122D03*
Y1159350D03*
X753642Y1170570D03*
X764862Y1174310D03*
X761122Y1181791D03*
X764862D03*
X761122Y1174310D03*
X768602Y1140649D03*
X772342D03*
Y1148129D03*
Y1155610D03*
X783563Y1151870D03*
X779823D03*
Y1144389D03*
X783563D03*
X768602Y1155610D03*
Y1148129D03*
X779823Y1159350D03*
X772342Y1170570D03*
X768602D03*
X783563Y1159350D03*
Y1189271D03*
X768602Y1185531D03*
X772342Y1178051D03*
X779823Y1189271D03*
X772342Y1185531D03*
X783563Y1174310D03*
X779823D03*
X783563Y1181791D03*
X768602Y1178051D03*
X779823Y1181791D03*
X768602Y1193011D03*
X772342D03*
X920349Y450340D03*
X917549D03*
X920349Y453884D03*
Y457427D03*
X917549Y453884D03*
Y457427D03*
X920349Y460970D03*
X917549D03*
X962380Y617861D03*
X958837D03*
X962380Y620661D03*
X958837D03*
X969467D03*
X965923Y617861D03*
Y620661D03*
X969467Y617861D03*
X1057381Y1088287D03*
Y1106988D03*
Y1099507D03*
Y1114468D03*
Y1121948D03*
Y1129429D03*
Y1136909D03*
Y1148129D03*
X1057380Y1170570D03*
Y1178051D03*
X1072342Y1073326D03*
X1064862D03*
Y1092027D03*
X1072342Y1077066D03*
X1068602Y1084547D03*
Y1080807D03*
X1061121Y1088287D03*
X1072342Y1092027D03*
X1068602Y1099507D03*
X1072342Y1095767D03*
X1061121Y1106988D03*
X1068602Y1103247D03*
X1064862Y1095767D03*
X1061121Y1099507D03*
Y1114468D03*
X1068602Y1110728D03*
Y1118208D03*
X1064862Y1110728D03*
Y1118208D03*
X1061121Y1121948D03*
X1064862Y1125688D03*
X1068602D03*
X1061121Y1129429D03*
X1064862Y1133169D03*
X1061121Y1136909D03*
Y1148129D03*
X1061120Y1170570D03*
X1072342Y1178051D03*
X1068602D03*
X1061120D03*
X1079822Y1073326D03*
Y1092027D03*
X1083562Y1084547D03*
X1079822Y1077066D03*
X1076082Y1084547D03*
Y1080807D03*
X1083562D03*
X1076082Y1103247D03*
X1079822Y1095767D03*
X1076082Y1099507D03*
X1083562Y1103247D03*
X1079822Y1118208D03*
X1076082Y1121948D03*
Y1118208D03*
X1079822Y1110728D03*
X1083562Y1114468D03*
X1087302D03*
X1076082Y1110728D03*
X1091043Y1151870D03*
Y1148129D03*
Y1144389D03*
X1083562Y1148129D03*
X1079822Y1144389D03*
Y1148129D03*
X1083562Y1151870D03*
X1079822Y1155610D03*
X1091043Y1166830D03*
Y1159350D03*
X1083562D03*
X1091043Y1181791D03*
Y1178051D03*
Y1174310D03*
X1102263Y1114468D03*
X1098523D03*
X1106003D03*
Y1140649D03*
Y1136909D03*
X1098523D03*
X1106003Y1129429D03*
Y1133169D03*
Y1151869D03*
Y1144389D03*
X1098523D03*
Y1151870D03*
X1102263Y1148129D03*
Y1155610D03*
X1106003Y1170570D03*
Y1159350D03*
X1102263Y1166830D03*
X1098523Y1159350D03*
Y1170570D03*
X1106003Y1178051D03*
Y1185531D03*
X1098523D03*
X1102263Y1174310D03*
X1098523Y1178051D03*
X1102263Y1181791D03*
X1106003Y1193011D03*
Y1215452D03*
X1098523D03*
X1102263D03*
X1117224Y1114468D03*
X1113484D03*
X1120964D03*
X1124704D03*
X1109743D03*
X1120964Y1129429D03*
X1113484D03*
X1117224D03*
X1124704D03*
Y1136909D03*
X1113484D03*
X1117224D03*
X1120964D03*
X1109743Y1140649D03*
X1124704Y1144389D03*
X1113484D03*
X1117224D03*
X1120964D03*
X1113484Y1151870D03*
X1117224D03*
X1120964D03*
X1124704D03*
Y1155610D03*
X1109743D03*
Y1148129D03*
X1117224Y1155610D03*
X1113484Y1159350D03*
X1120964D03*
X1109743Y1166830D03*
X1113484Y1170570D03*
X1117224Y1166830D03*
X1120964Y1170570D03*
X1124704Y1166830D03*
X1113484Y1178051D03*
X1117224D03*
X1120964D03*
X1124704D03*
X1120964Y1185531D03*
X1113484D03*
X1117224D03*
X1124704D03*
X1109743Y1174310D03*
Y1181791D03*
X1117224Y1174310D03*
X1124704D03*
X1117224Y1200491D03*
X1120964D03*
X1113484D03*
X1124704D03*
X1120964Y1193011D03*
X1117224D03*
X1113484D03*
X1124704D03*
Y1215452D03*
X1120964D03*
Y1211712D03*
X1117224Y1215452D03*
X1109743D03*
X1113484Y1211712D03*
X1111613Y1217322D03*
X1115354D03*
X1117224Y1211712D03*
X1139665Y1114468D03*
X1135925D03*
X1132184D03*
Y1129429D03*
X1128444D03*
X1135924D03*
X1139665D03*
Y1136909D03*
X1135924D03*
X1132184D03*
X1128444D03*
Y1144389D03*
X1135924D03*
X1132184D03*
X1139665D03*
X1135925Y1151870D03*
X1132184D03*
X1128444D03*
X1139665D03*
Y1155610D03*
X1132184D03*
X1139665Y1166830D03*
X1135924Y1170570D03*
X1128444D03*
X1132184Y1166830D03*
X1128444Y1159350D03*
X1135924D03*
X1139665Y1178051D03*
X1135924D03*
X1132184D03*
X1128444D03*
X1139665Y1185531D03*
X1132184D03*
X1128444D03*
X1135924D03*
X1139665Y1174310D03*
X1132184D03*
Y1200491D03*
X1128444D03*
X1135924D03*
X1139665D03*
X1128444Y1193011D03*
X1132184D03*
X1135924D03*
X1139665D03*
Y1211712D03*
X1135925D03*
Y1215452D03*
X1128444D03*
X1132184D03*
X1128444Y1211712D03*
X1154625Y1118208D03*
X1150885D03*
X1154625Y1114468D03*
X1150885D03*
X1154625Y1129429D03*
X1150885D03*
X1143405D03*
Y1136909D03*
X1154625D03*
X1150885D03*
X1143405Y1144389D03*
X1150885Y1151869D03*
X1154625D03*
Y1144389D03*
X1150885D03*
X1143405Y1151870D03*
X1150885Y1155610D03*
X1143405Y1170570D03*
X1154625Y1159350D03*
X1143405D03*
X1150885Y1166830D03*
X1154625Y1170570D03*
X1143405Y1178051D03*
Y1185531D03*
X1154625D03*
X1150885D03*
X1154625Y1178051D03*
X1150885D03*
Y1174310D03*
X1143405Y1200491D03*
X1154625D03*
X1150885D03*
Y1193011D03*
X1154625D03*
X1143405D03*
Y1211712D03*
Y1215452D03*
X1150885Y1211712D03*
Y1215452D03*
X1154625D03*
X1156495Y1217322D03*
X1152755D03*
X1162106Y1114468D03*
X1169586D03*
X1162106Y1118208D03*
X1173326Y1114468D03*
X1158365Y1118208D03*
X1173326D03*
X1165846Y1114468D03*
X1158365D03*
X1169586Y1118208D03*
X1165846D03*
X1169586Y1129429D03*
X1165846D03*
X1162106D03*
X1158365D03*
X1173326D03*
Y1136909D03*
X1169586D03*
X1165846D03*
X1158365D03*
X1162106D03*
X1173326Y1151869D03*
X1158365D03*
X1162106D03*
X1169586D03*
X1165846D03*
X1173326Y1144389D03*
X1165846D03*
X1158365D03*
X1162106D03*
X1169586D03*
X1173326Y1155610D03*
X1165846D03*
X1158365D03*
X1173326Y1166830D03*
X1165846D03*
X1169586Y1170570D03*
X1158365Y1166830D03*
X1162106Y1170570D03*
X1169586Y1159350D03*
X1162106D03*
X1158365Y1185531D03*
X1162106D03*
X1169586D03*
X1165846D03*
X1173326D03*
X1165846Y1178051D03*
X1158365D03*
X1162106D03*
X1169586D03*
X1173326D03*
X1165846Y1174310D03*
X1158365D03*
X1173326D03*
Y1200491D03*
X1165846D03*
X1162106D03*
X1158365D03*
X1169586D03*
X1165846Y1193011D03*
X1169586D03*
X1158365D03*
X1162106D03*
X1173326D03*
Y1215452D03*
X1165846D03*
X1169586D03*
X1162105Y1215451D03*
X1158365Y1215452D03*
X1162105Y1211711D03*
X1165846D03*
X1188287Y1114468D03*
X1177066D03*
Y1118208D03*
X1184546Y1114468D03*
X1180806Y1129429D03*
X1177066D03*
X1188287D03*
X1180806Y1136909D03*
X1177066D03*
X1188287D03*
Y1140649D03*
X1180806Y1151869D03*
X1177066D03*
Y1144389D03*
X1180806D03*
Y1155610D03*
X1188287Y1144389D03*
X1180806Y1170570D03*
X1184546D03*
X1177066D03*
X1184546Y1166830D03*
X1180806D03*
X1177066Y1159350D03*
X1180806D03*
X1184546D03*
X1177066Y1185531D03*
Y1178051D03*
X1180806Y1185531D03*
Y1178051D03*
Y1174310D03*
X1184546Y1181791D03*
X1188287Y1185531D03*
Y1189271D03*
Y1178051D03*
X1180806Y1200491D03*
X1177066D03*
X1188287D03*
X1177066Y1193011D03*
X1180806D03*
X1188287D03*
Y1215452D03*
X1180806D03*
X1177066D03*
X1188287Y1211712D03*
X1199507Y1118208D03*
X1195767D03*
Y1114468D03*
X1192027D03*
X1199507D03*
Y1140649D03*
Y1136909D03*
X1203247Y1140649D03*
X1199507Y1155610D03*
X1192027D03*
X1203247Y1148129D03*
X1195767Y1144389D03*
X1199507Y1148129D03*
Y1144389D03*
Y1170570D03*
Y1166830D03*
Y1159350D03*
X1192027Y1166830D03*
Y1170570D03*
Y1159350D03*
X1203247Y1189271D03*
X1199507D03*
Y1174310D03*
X1195767Y1181791D03*
X1192027Y1174310D03*
X1199507Y1178051D03*
X1203247Y1181791D03*
X1199507Y1196751D03*
Y1204232D03*
X1195767Y1200491D03*
X1192027Y1196751D03*
Y1200491D03*
Y1204232D03*
X1199507Y1200491D03*
X1192027Y1215452D03*
X1199507Y1211712D03*
Y1215452D03*
Y1207972D03*
X1195767Y1215452D03*
X1192027Y1207972D03*
X1195767D03*
Y1211712D03*
X1206988Y1140649D03*
X1218208Y1144389D03*
Y1151869D03*
X1206988Y1155610D03*
Y1148129D03*
X1210728Y1155610D03*
X1221948Y1151869D03*
Y1144389D03*
X1218208Y1166830D03*
Y1159350D03*
X1221948Y1166830D03*
X1210728Y1170570D03*
X1206988D03*
X1218208Y1189271D03*
Y1174310D03*
X1221948Y1181791D03*
Y1174310D03*
X1218208Y1181791D03*
X1221948Y1189271D03*
X1236909Y1136909D03*
X1225688Y1140649D03*
X1229428D03*
X1236909Y1151870D03*
X1225688Y1148129D03*
X1229428D03*
X1225688Y1155610D03*
X1236909Y1144389D03*
X1229428Y1155610D03*
Y1170570D03*
X1225688D03*
X1236909Y1159350D03*
Y1181791D03*
X1225688Y1185531D03*
X1236909Y1189271D03*
X1229428Y1178051D03*
Y1185531D03*
X1236909Y1174310D03*
X1225688Y1178051D03*
Y1193011D03*
X1229428D03*
X1240649Y1136909D03*
Y1151870D03*
Y1144389D03*
Y1159350D03*
Y1174310D03*
Y1181791D03*
Y1189271D03*
X1339196Y441086D03*
Y433999D03*
Y437543D03*
X1336396Y441086D03*
Y433999D03*
Y437543D03*
X1339196Y444629D03*
X1336396D03*
X1415924Y620661D03*
Y617861D03*
X1423010Y620661D03*
X1419467Y617861D03*
X1423010D03*
X1426554Y620661D03*
Y617861D03*
X1419467Y620661D03*
X1514468Y1088287D03*
Y1099507D03*
Y1106988D03*
Y1121948D03*
Y1114468D03*
Y1129429D03*
Y1136909D03*
Y1148129D03*
Y1155610D03*
X1514467Y1170570D03*
Y1178051D03*
X1521949Y1073326D03*
X1529429D03*
Y1077066D03*
X1525689Y1084547D03*
X1529429Y1092027D03*
X1521949D03*
X1518208Y1088287D03*
X1525689Y1080807D03*
X1518208Y1099507D03*
X1525689D03*
X1529429Y1095767D03*
X1525689Y1103247D03*
X1518208Y1106988D03*
X1521949Y1095767D03*
Y1110728D03*
X1518208Y1114468D03*
X1525689Y1110728D03*
X1518208Y1121948D03*
X1521949Y1118208D03*
X1525689D03*
Y1125688D03*
X1518208Y1129429D03*
X1521949Y1125688D03*
X1518208Y1136909D03*
X1521949Y1133169D03*
X1518208Y1148129D03*
Y1155610D03*
X1518207Y1170570D03*
X1527559Y1176180D03*
X1518207Y1178051D03*
X1536909Y1073326D03*
X1533169Y1080807D03*
Y1084547D03*
X1540649Y1080807D03*
X1536909Y1077066D03*
X1540649Y1084547D03*
X1536909Y1092027D03*
Y1095767D03*
X1533169Y1099507D03*
X1540649Y1103247D03*
X1533169D03*
X1536909Y1118208D03*
X1533169D03*
Y1121948D03*
X1544389Y1114468D03*
X1536909Y1110728D03*
X1533169D03*
X1540649Y1114468D03*
X1536909Y1148129D03*
X1540649Y1151870D03*
Y1148129D03*
X1536909Y1144389D03*
Y1155610D03*
X1540649Y1159350D03*
Y1170570D03*
Y1174310D03*
Y1178050D03*
X1531299Y1176180D03*
X1559350Y1114468D03*
X1555610D03*
X1563090D03*
Y1140649D03*
Y1136909D03*
X1555610D03*
X1563090Y1129429D03*
Y1133169D03*
Y1144389D03*
Y1151869D03*
X1555610Y1144389D03*
X1548130Y1151870D03*
Y1148129D03*
Y1144389D03*
X1559350Y1155610D03*
X1555610Y1151870D03*
X1559350Y1148129D03*
X1563090Y1159350D03*
Y1170570D03*
X1548130Y1166830D03*
Y1159350D03*
X1555610Y1170570D03*
X1559350Y1166830D03*
X1555610Y1159350D03*
X1548130Y1174310D03*
Y1178051D03*
Y1181791D03*
X1563090Y1185531D03*
Y1178051D03*
X1555610Y1185531D03*
X1559350Y1174310D03*
Y1181791D03*
X1555610Y1178051D03*
X1563090Y1193011D03*
X1555610Y1215452D03*
X1563090D03*
X1559350D03*
X1574311Y1114468D03*
X1570571D03*
X1578051D03*
X1566830D03*
X1578051Y1136909D03*
X1574311D03*
X1570571D03*
X1574311Y1129429D03*
X1570571D03*
X1578051D03*
X1566830Y1140649D03*
X1578051Y1144389D03*
X1574311D03*
X1570571D03*
X1578051Y1151870D03*
X1574311D03*
X1570571D03*
X1574311Y1155610D03*
X1566830Y1148129D03*
Y1155610D03*
X1578051Y1170570D03*
X1574311Y1166830D03*
X1570571Y1170570D03*
X1566830Y1166830D03*
X1578051Y1159350D03*
X1570571D03*
X1574311Y1185531D03*
X1570571D03*
X1578051D03*
Y1178051D03*
X1574311D03*
X1570571D03*
X1574311Y1174310D03*
X1566830Y1181791D03*
Y1174310D03*
X1570571Y1193011D03*
X1574311D03*
X1578051D03*
X1570571Y1200491D03*
X1578051D03*
X1574311D03*
X1578051Y1215452D03*
X1566830D03*
X1570571Y1211712D03*
X1566830Y1219192D03*
X1574311Y1215452D03*
X1570571D03*
X1578051Y1211712D03*
X1574311D03*
X1593012Y1114468D03*
X1589271D03*
X1581791D03*
X1593011Y1136909D03*
X1589271D03*
X1585531D03*
X1581791D03*
X1589271Y1129429D03*
X1585531D03*
X1581791D03*
X1593011D03*
X1585531Y1144389D03*
X1581791D03*
X1593011D03*
X1589271D03*
X1593012Y1151870D03*
X1589271D03*
X1585531D03*
X1581791D03*
Y1155610D03*
X1589271D03*
X1593011Y1170570D03*
X1585531D03*
X1589271Y1166830D03*
X1581791D03*
X1585531Y1159350D03*
X1593011D03*
X1589271Y1185531D03*
X1585531D03*
X1581791D03*
X1593011D03*
X1581791Y1178051D03*
X1593011D03*
X1589271D03*
X1585531D03*
X1589271Y1174310D03*
X1581791D03*
X1585531Y1193011D03*
X1589271D03*
X1593011D03*
X1581791D03*
X1589271Y1200491D03*
X1585531D03*
X1581791D03*
X1593011D03*
X1593012Y1211712D03*
Y1215452D03*
X1581791D03*
X1589271D03*
X1585531D03*
Y1211712D03*
X1596752Y1114468D03*
X1607972D03*
X1611712Y1118208D03*
X1607972D03*
X1611712Y1114468D03*
X1600492Y1136909D03*
X1596752D03*
X1611712D03*
X1607972D03*
X1611712Y1129429D03*
X1607972D03*
X1600492D03*
X1596752D03*
X1600492Y1144389D03*
X1596752D03*
X1611712Y1151869D03*
X1607972D03*
X1611712Y1144389D03*
X1607972D03*
X1600492Y1151870D03*
X1596752D03*
Y1155610D03*
X1607972D03*
Y1166830D03*
X1611712Y1170570D03*
X1600492D03*
X1596752Y1166830D03*
X1611712Y1159350D03*
X1600492D03*
Y1185531D03*
X1596752D03*
X1600492Y1178051D03*
X1596752D03*
X1611712Y1185531D03*
X1607972D03*
X1611712Y1178051D03*
X1607972D03*
Y1174310D03*
X1596752D03*
X1607972Y1193011D03*
X1611712D03*
X1600492D03*
X1596752D03*
X1600492Y1200491D03*
X1596752D03*
X1611712D03*
X1607972D03*
X1600492Y1211712D03*
Y1215452D03*
X1596752Y1211712D03*
X1611712Y1215452D03*
X1607972D03*
Y1211712D03*
X1609842Y1217322D03*
X1615452Y1118208D03*
X1619193D03*
X1615452Y1114468D03*
X1619193D03*
X1622933D03*
X1626673D03*
Y1118208D03*
X1622933D03*
X1626673Y1136909D03*
X1622933D03*
X1615452D03*
X1619193D03*
X1626673Y1129429D03*
X1622933D03*
X1619193D03*
X1615452D03*
Y1151869D03*
X1619193D03*
X1626673D03*
X1622933D03*
Y1144389D03*
X1615452D03*
X1619193D03*
X1626673D03*
X1622933Y1155610D03*
X1615452D03*
Y1166830D03*
X1619193Y1170570D03*
X1626673Y1159350D03*
X1619193D03*
X1622933Y1166830D03*
X1626673Y1170570D03*
X1619193Y1185531D03*
X1626673D03*
X1622933D03*
Y1178051D03*
X1615452D03*
X1619193D03*
X1626673D03*
X1615452Y1185531D03*
X1622933Y1174310D03*
X1615452D03*
X1622933Y1193011D03*
X1626673D03*
X1615452D03*
X1619193D03*
X1622933Y1200491D03*
X1619193D03*
X1615452D03*
X1626673D03*
X1622933Y1215452D03*
X1619192Y1215451D03*
X1626673Y1215452D03*
X1615452D03*
X1613582Y1217322D03*
X1619192Y1211711D03*
X1622933D03*
X1637893Y1118208D03*
Y1114468D03*
X1634153D03*
X1630413D03*
X1641633D03*
X1634153Y1118208D03*
X1630413D03*
Y1136909D03*
X1637893D03*
X1634153D03*
X1630413Y1129429D03*
X1637893D03*
X1634153D03*
X1630413Y1151869D03*
X1637893D03*
X1634153D03*
Y1144389D03*
X1630413D03*
X1637893D03*
Y1155610D03*
X1630413D03*
X1637893Y1170570D03*
X1641633D03*
X1634153D03*
X1641633Y1166830D03*
X1637893D03*
Y1159350D03*
X1641633D03*
X1634153D03*
X1630413Y1166830D03*
X1641633Y1181791D03*
X1630413Y1185531D03*
X1634153D03*
X1630413Y1178051D03*
X1634153D03*
X1637893Y1185531D03*
Y1178051D03*
Y1174310D03*
X1630413D03*
X1634153Y1193011D03*
X1637893D03*
X1630413D03*
Y1200491D03*
X1637893D03*
X1634153D03*
X1630413Y1215452D03*
X1637893D03*
X1634153D03*
X1656594Y1118208D03*
X1652854D03*
Y1114468D03*
X1645374D03*
X1649114D03*
X1656594D03*
X1645374Y1129429D03*
Y1136909D03*
Y1140649D03*
X1656594Y1133169D03*
Y1140649D03*
Y1136909D03*
X1660334Y1140649D03*
X1649114Y1155610D03*
X1656594D03*
X1645374Y1144389D03*
X1660334Y1148129D03*
X1652854Y1144389D03*
X1656594Y1148129D03*
Y1144389D03*
X1649114Y1159350D03*
Y1170570D03*
Y1166830D03*
X1656594Y1170570D03*
Y1166830D03*
Y1159350D03*
Y1189271D03*
X1649114Y1174310D03*
X1656594D03*
X1652854Y1181791D03*
X1660334Y1189271D03*
X1645374Y1185531D03*
Y1189271D03*
X1660334Y1181791D03*
X1656594Y1178051D03*
X1645374D03*
Y1200491D03*
Y1193011D03*
X1656594Y1196751D03*
Y1204232D03*
X1652854Y1200491D03*
X1649114Y1204232D03*
Y1196751D03*
Y1200491D03*
X1656594D03*
X1645374Y1215452D03*
X1649114D03*
X1652854D03*
X1656594Y1211712D03*
X1645374D03*
X1656594Y1215452D03*
Y1207972D03*
X1649114D03*
X1652854D03*
Y1211712D03*
X1664075Y1140649D03*
X1667815Y1155610D03*
X1664075Y1148129D03*
Y1155610D03*
X1675295Y1144389D03*
Y1151869D03*
Y1166830D03*
Y1159350D03*
X1664075Y1170570D03*
X1667815D03*
X1675295Y1189271D03*
Y1174310D03*
Y1181791D03*
X1686515Y1140649D03*
X1682775D03*
X1679035Y1151869D03*
Y1144389D03*
X1682775Y1148129D03*
X1686515Y1155610D03*
Y1148129D03*
X1682775Y1155610D03*
X1679035Y1166830D03*
X1686515Y1170570D03*
X1682775D03*
X1679035Y1181791D03*
Y1189271D03*
Y1174310D03*
X1686515Y1185531D03*
X1682775Y1178051D03*
X1686515D03*
X1682775Y1185531D03*
X1686515Y1193011D03*
X1682775D03*
Y1222932D03*
X1693996Y1136909D03*
X1697736D03*
X1693996Y1151870D03*
X1697736D03*
X1693996Y1144389D03*
X1697736D03*
Y1159350D03*
X1693996D03*
X1697736Y1174310D03*
X1693996Y1189271D03*
X1697736D03*
Y1181791D03*
X1693996D03*
Y1174310D03*
X1796283Y441086D03*
Y433999D03*
Y437543D03*
X1793483Y441086D03*
Y433999D03*
Y437543D03*
X1796283Y444629D03*
X1793483D03*
G54D53*
X970071Y1365652D03*
Y1409152D03*
G54D32*
X109882Y1458622D03*
Y1463741D03*
Y1473977D03*
Y1479095D03*
Y1489331D03*
Y1494449D03*
Y1560985D03*
Y1566103D03*
Y1576339D03*
Y1581457D03*
Y1591693D03*
Y1596811D03*
Y1622402D03*
X127205Y1458622D03*
Y1463741D03*
X118543Y1452717D03*
Y1462953D03*
X127205Y1473977D03*
Y1479095D03*
X118543Y1468071D03*
Y1478308D03*
X127205Y1489331D03*
Y1494449D03*
X118543Y1483426D03*
Y1493662D03*
Y1498780D03*
X127205Y1560985D03*
Y1566103D03*
Y1576339D03*
X118543Y1565315D03*
Y1570434D03*
X127205Y1581457D03*
Y1591693D03*
X118543Y1580670D03*
Y1585788D03*
Y1596024D03*
X127205Y1596811D03*
X118543Y1601142D03*
X127205Y1622402D03*
X144528Y1458622D03*
Y1463741D03*
X135866Y1452717D03*
Y1462953D03*
X144528Y1473977D03*
Y1479095D03*
X135866Y1468071D03*
Y1478308D03*
X144528Y1489331D03*
Y1494449D03*
X135866Y1483426D03*
Y1493662D03*
Y1498780D03*
X144528Y1560985D03*
Y1566103D03*
Y1576339D03*
X135866Y1565315D03*
Y1570434D03*
X144528Y1581457D03*
Y1591693D03*
X135866Y1580670D03*
Y1585788D03*
Y1596024D03*
X144528Y1596811D03*
X135866Y1601142D03*
X144528Y1622402D03*
X161850Y1458622D03*
Y1463741D03*
X153189Y1452717D03*
Y1462953D03*
X161850Y1473977D03*
Y1479095D03*
X153189Y1468071D03*
Y1478308D03*
X161850Y1489331D03*
Y1494449D03*
X153189Y1483426D03*
Y1493662D03*
Y1498780D03*
X161850Y1560985D03*
Y1566103D03*
Y1576339D03*
X153189Y1565315D03*
Y1570434D03*
X161850Y1581457D03*
Y1591693D03*
X153189Y1580670D03*
Y1585788D03*
Y1596024D03*
X161850Y1596811D03*
X153189Y1601142D03*
X161850Y1622402D03*
X179173Y1458622D03*
Y1463741D03*
X170512Y1452717D03*
Y1462953D03*
X179173Y1473977D03*
Y1479095D03*
X170512Y1468071D03*
Y1478308D03*
X179173Y1489331D03*
Y1494449D03*
X170512Y1483426D03*
Y1493662D03*
Y1498780D03*
X179173Y1504685D03*
Y1509804D03*
Y1560985D03*
Y1566103D03*
Y1576339D03*
X170512Y1565315D03*
Y1570434D03*
X179173Y1581457D03*
Y1591693D03*
X170512Y1580670D03*
Y1585788D03*
Y1596024D03*
X179173Y1596811D03*
Y1607048D03*
Y1612166D03*
X170512Y1601142D03*
X179173Y1622402D03*
X187835Y1452717D03*
Y1462953D03*
Y1468071D03*
Y1478308D03*
Y1483426D03*
Y1493662D03*
Y1498780D03*
Y1509016D03*
Y1514134D03*
Y1565315D03*
Y1570434D03*
Y1580670D03*
Y1585788D03*
Y1596024D03*
Y1601142D03*
Y1611378D03*
Y1616496D03*
X291771Y1452717D03*
X283110Y1473977D03*
X291771Y1478308D03*
X283110Y1479095D03*
X291771Y1483426D03*
X283110Y1489331D03*
X291771Y1493662D03*
X283110Y1494449D03*
X291771Y1498780D03*
X283110Y1504685D03*
X291771Y1509016D03*
X283110Y1509804D03*
X291771Y1514134D03*
X283110Y1560985D03*
X291771Y1565315D03*
X283110Y1566103D03*
X291771Y1570434D03*
X283110Y1591693D03*
X291771Y1596024D03*
X283110Y1596811D03*
X291771Y1601142D03*
X283110Y1607048D03*
X291771Y1611378D03*
X283110Y1612166D03*
X291771Y1616496D03*
X283110Y1622402D03*
X309094Y1452717D03*
X300433Y1473977D03*
X309094Y1478308D03*
X300433Y1479095D03*
X309094Y1483426D03*
X300433Y1489331D03*
X309094Y1493662D03*
X300433Y1494449D03*
X309094Y1498780D03*
X300433Y1504685D03*
X309094Y1509016D03*
X300433Y1509804D03*
X309094Y1514134D03*
X300433Y1560985D03*
X309094Y1565315D03*
X300433Y1566103D03*
X309094Y1570434D03*
X300433Y1591693D03*
X309094Y1596024D03*
X300433Y1596811D03*
X309094Y1601142D03*
X300433Y1607048D03*
X309094Y1611378D03*
X300433Y1612166D03*
X309094Y1616496D03*
X300433Y1622402D03*
X326417Y1452717D03*
X317756Y1473977D03*
X326417Y1478308D03*
X317756Y1479095D03*
X326417Y1483426D03*
X317756Y1489331D03*
X326417Y1493662D03*
X317756Y1494449D03*
X326417Y1498780D03*
X317756Y1504685D03*
X326417Y1509016D03*
X317756Y1509804D03*
X326417Y1514134D03*
X317756Y1560985D03*
X326417Y1565315D03*
X317756Y1566103D03*
X326417Y1570434D03*
X317756Y1591693D03*
X326417Y1596024D03*
X317756Y1596811D03*
X326417Y1601142D03*
X317756Y1607048D03*
X326417Y1611378D03*
X317756Y1612166D03*
X326417Y1616496D03*
X317756Y1622402D03*
X343740Y1452717D03*
X335078Y1473977D03*
X343740Y1478308D03*
X335078Y1479095D03*
X343740Y1483426D03*
X335078Y1489331D03*
X343740Y1493662D03*
X335078Y1494449D03*
X343740Y1498780D03*
X335078Y1504685D03*
X343740Y1509016D03*
X335078Y1509804D03*
X343740Y1514134D03*
X335078Y1560985D03*
X343740Y1565315D03*
X335078Y1566103D03*
X343740Y1570434D03*
X335078Y1591693D03*
X343740Y1596024D03*
X335078Y1596811D03*
X343740Y1601142D03*
X335078Y1607048D03*
X343740Y1611378D03*
X335078Y1612166D03*
X343740Y1616496D03*
X335078Y1622402D03*
X361063Y1452717D03*
X352401Y1458622D03*
Y1463741D03*
X361063Y1462953D03*
Y1468071D03*
X352401Y1473977D03*
Y1479095D03*
X361063Y1478308D03*
Y1483426D03*
X352401Y1489331D03*
Y1494449D03*
X361063Y1493662D03*
Y1498780D03*
X352401Y1504685D03*
Y1509804D03*
X361063Y1509016D03*
Y1514134D03*
X352401Y1560985D03*
Y1566103D03*
X361063Y1565315D03*
Y1570434D03*
X352401Y1576339D03*
Y1581457D03*
X361063Y1580670D03*
Y1585788D03*
X352401Y1591693D03*
X361063Y1596024D03*
X352401Y1596811D03*
X361063Y1601142D03*
X352401Y1607048D03*
Y1612166D03*
X361063Y1611378D03*
Y1616496D03*
X352401Y1622402D03*
X456339Y1458622D03*
Y1463741D03*
Y1489331D03*
Y1494449D03*
Y1504685D03*
Y1509804D03*
Y1576339D03*
Y1581457D03*
Y1591693D03*
Y1596811D03*
Y1607048D03*
Y1612166D03*
Y1622402D03*
X473662Y1458622D03*
Y1463741D03*
X465000Y1452717D03*
Y1462953D03*
Y1468071D03*
X473662Y1489331D03*
Y1494449D03*
X465000Y1493662D03*
Y1498780D03*
X473662Y1504685D03*
Y1509804D03*
X465000Y1509016D03*
Y1514134D03*
X473662Y1576339D03*
Y1581457D03*
Y1591693D03*
X465000Y1580670D03*
Y1585788D03*
Y1596024D03*
X473662Y1596811D03*
Y1607048D03*
Y1612166D03*
X465000Y1601142D03*
Y1611378D03*
X473662Y1622402D03*
X465000Y1616496D03*
X490985Y1458622D03*
Y1463741D03*
X482323Y1452717D03*
Y1462953D03*
Y1468071D03*
X490985Y1489331D03*
Y1494449D03*
X482323Y1493662D03*
Y1498780D03*
X490985Y1504685D03*
Y1509804D03*
X482323Y1509016D03*
Y1514134D03*
X490985Y1576339D03*
Y1581457D03*
Y1591693D03*
X482323Y1580670D03*
Y1585788D03*
Y1596024D03*
X490985Y1596811D03*
Y1607048D03*
Y1612166D03*
X482323Y1601142D03*
Y1611378D03*
X490985Y1622402D03*
X482323Y1616496D03*
X499646Y1452717D03*
Y1462953D03*
Y1468071D03*
Y1493662D03*
Y1498780D03*
Y1509016D03*
Y1514134D03*
Y1580670D03*
Y1585788D03*
Y1596024D03*
Y1601142D03*
Y1611378D03*
Y1616496D03*
X516969Y1452717D03*
X508307Y1458622D03*
X516969Y1462953D03*
X508307Y1463741D03*
X516969Y1468071D03*
X508307Y1489331D03*
X516969Y1493662D03*
X508307Y1494449D03*
X516969Y1498780D03*
X508307Y1504685D03*
X516969Y1509016D03*
X508307Y1509804D03*
X516969Y1514134D03*
X508307Y1576339D03*
X516969Y1580670D03*
X508307Y1581457D03*
X516969Y1585788D03*
X508307Y1591693D03*
X516969Y1596024D03*
X508307Y1596811D03*
X516969Y1601142D03*
X508307Y1607048D03*
X516969Y1611378D03*
X508307Y1612166D03*
X516969Y1616496D03*
X508307Y1622402D03*
X534292Y1452717D03*
X525630Y1458622D03*
Y1463741D03*
X534292Y1462953D03*
Y1468071D03*
X525630Y1473977D03*
Y1479095D03*
X534292Y1478308D03*
Y1483426D03*
X525630Y1489331D03*
Y1494449D03*
X534292Y1493662D03*
Y1498780D03*
X525630Y1504685D03*
Y1509804D03*
X534292Y1509016D03*
Y1514134D03*
X525630Y1560985D03*
Y1566103D03*
X534292Y1565315D03*
Y1570434D03*
X525630Y1576339D03*
Y1581457D03*
X534292Y1580670D03*
Y1585788D03*
X525630Y1591693D03*
X534292Y1596024D03*
X525630Y1596811D03*
X534292Y1601142D03*
X525630Y1607048D03*
Y1612166D03*
X534292Y1611378D03*
Y1616496D03*
X525630Y1622402D03*
X629567Y1458622D03*
Y1463741D03*
Y1473977D03*
Y1479095D03*
Y1504685D03*
Y1509804D03*
Y1560985D03*
Y1566103D03*
Y1576339D03*
Y1581457D03*
Y1607048D03*
Y1612166D03*
Y1622402D03*
X646890Y1458622D03*
Y1463741D03*
X638228Y1452717D03*
Y1462953D03*
X646890Y1473977D03*
Y1479095D03*
X638228Y1468071D03*
Y1478308D03*
Y1483426D03*
X646890Y1504685D03*
Y1509804D03*
X638228Y1509016D03*
Y1514134D03*
X646890Y1560985D03*
Y1566103D03*
Y1576339D03*
X638228Y1565315D03*
Y1570434D03*
X646890Y1581457D03*
X638228Y1580670D03*
Y1585788D03*
X646890Y1607048D03*
Y1612166D03*
X638228Y1611378D03*
X646890Y1622402D03*
X638228Y1616496D03*
X664213Y1458622D03*
Y1463741D03*
X655551Y1452717D03*
Y1462953D03*
X664213Y1473977D03*
Y1479095D03*
X655551Y1468071D03*
Y1478308D03*
Y1483426D03*
X664213Y1504685D03*
Y1509804D03*
X655551Y1509016D03*
Y1514134D03*
X664213Y1560985D03*
Y1566103D03*
Y1576339D03*
X655551Y1565315D03*
Y1570434D03*
X664213Y1581457D03*
X655551Y1580670D03*
Y1585788D03*
X664213Y1607048D03*
Y1612166D03*
X655551Y1611378D03*
X664213Y1622402D03*
X655551Y1616496D03*
X681535Y1458622D03*
Y1463741D03*
X672874Y1452717D03*
Y1462953D03*
X681535Y1473977D03*
Y1479095D03*
X672874Y1468071D03*
Y1478308D03*
Y1483426D03*
X681535Y1504685D03*
Y1509804D03*
X672874Y1509016D03*
Y1514134D03*
X681535Y1560985D03*
Y1566103D03*
Y1576339D03*
X672874Y1565315D03*
Y1570434D03*
X681535Y1581457D03*
X672874Y1580670D03*
Y1585788D03*
X681535Y1607048D03*
Y1612166D03*
X672874Y1611378D03*
X681535Y1622402D03*
X672874Y1616496D03*
X698858Y1458622D03*
Y1463741D03*
X690197Y1452717D03*
Y1462953D03*
X698858Y1473977D03*
Y1479095D03*
X690197Y1468071D03*
Y1478308D03*
X698858Y1489331D03*
Y1494449D03*
X690197Y1483426D03*
X698858Y1504685D03*
Y1509804D03*
X690197Y1509016D03*
Y1514134D03*
X698858Y1560985D03*
Y1566103D03*
Y1576339D03*
X690197Y1565315D03*
Y1570434D03*
X698858Y1581457D03*
Y1591693D03*
X690197Y1580670D03*
Y1585788D03*
X698858Y1596811D03*
Y1607048D03*
Y1612166D03*
X690197Y1611378D03*
X698858Y1622402D03*
X690197Y1616496D03*
X707520Y1452717D03*
Y1462953D03*
Y1468071D03*
Y1478308D03*
Y1483426D03*
Y1493662D03*
Y1498780D03*
Y1509016D03*
Y1514134D03*
Y1565315D03*
Y1570434D03*
Y1580670D03*
Y1585788D03*
Y1596024D03*
Y1601142D03*
Y1611378D03*
Y1616496D03*
X1140511Y1452717D03*
X1131850Y1458622D03*
X1140511Y1462953D03*
X1131850Y1463741D03*
X1140511Y1468071D03*
X1131850Y1473977D03*
X1140511Y1478308D03*
X1131850Y1479095D03*
X1140511Y1483426D03*
X1131850Y1489331D03*
X1140511Y1493662D03*
X1131850Y1494449D03*
X1140511Y1498780D03*
X1131850Y1560985D03*
X1140511Y1565315D03*
X1131850Y1566103D03*
X1140511Y1570434D03*
X1131850Y1576339D03*
X1140511Y1580670D03*
X1131850Y1581457D03*
X1140511Y1585788D03*
X1131850Y1591693D03*
X1140511Y1596024D03*
X1131850Y1596811D03*
X1140511Y1601142D03*
X1131850Y1622402D03*
X1149173Y1458622D03*
Y1463741D03*
Y1473977D03*
Y1479095D03*
Y1489331D03*
Y1494449D03*
Y1560985D03*
Y1566103D03*
Y1576339D03*
Y1581457D03*
Y1591693D03*
Y1596811D03*
Y1622402D03*
X1166496Y1458622D03*
Y1463741D03*
X1157834Y1452717D03*
Y1462953D03*
X1166496Y1473977D03*
Y1479095D03*
X1157834Y1468071D03*
Y1478308D03*
X1166496Y1489331D03*
Y1494449D03*
X1157834Y1483426D03*
Y1493662D03*
Y1498780D03*
X1166496Y1560985D03*
Y1566103D03*
Y1576339D03*
X1157834Y1565315D03*
Y1570434D03*
X1166496Y1581457D03*
Y1591693D03*
X1157834Y1580670D03*
Y1585788D03*
Y1596024D03*
X1166496Y1596811D03*
X1157834Y1601142D03*
X1166496Y1622402D03*
X1183818Y1458622D03*
Y1463741D03*
X1175157Y1452717D03*
Y1462953D03*
X1183818Y1473977D03*
Y1479095D03*
X1175157Y1468071D03*
Y1478308D03*
X1183818Y1489331D03*
Y1494449D03*
X1175157Y1483426D03*
Y1493662D03*
Y1498780D03*
X1183818Y1560985D03*
Y1566103D03*
Y1576339D03*
X1175157Y1565315D03*
Y1570434D03*
X1183818Y1581457D03*
Y1591693D03*
X1175157Y1580670D03*
Y1585788D03*
Y1596024D03*
X1183818Y1596811D03*
X1175157Y1601142D03*
X1183818Y1622402D03*
X1201141Y1458622D03*
Y1463741D03*
X1192480Y1452717D03*
Y1462953D03*
X1201141Y1473977D03*
Y1479095D03*
X1192480Y1468071D03*
Y1478308D03*
X1201141Y1489331D03*
Y1494449D03*
X1192480Y1483426D03*
Y1493662D03*
Y1498780D03*
X1201141Y1504685D03*
Y1509804D03*
Y1560985D03*
Y1566103D03*
Y1576339D03*
X1192480Y1565315D03*
Y1570434D03*
X1201141Y1581457D03*
Y1591693D03*
X1192480Y1580670D03*
Y1585788D03*
Y1596024D03*
X1201141Y1596811D03*
Y1607048D03*
Y1612166D03*
X1192480Y1601142D03*
X1201141Y1622402D03*
X1209803Y1452717D03*
Y1462953D03*
Y1468071D03*
Y1478308D03*
Y1483426D03*
Y1493662D03*
Y1498780D03*
Y1509016D03*
Y1514134D03*
Y1565315D03*
Y1570434D03*
Y1580670D03*
Y1585788D03*
Y1596024D03*
Y1601142D03*
Y1611378D03*
Y1616496D03*
X1313740Y1452717D03*
X1305079Y1473977D03*
X1313740Y1478308D03*
X1305079Y1479095D03*
X1313740Y1483426D03*
X1305079Y1489331D03*
X1313740Y1493662D03*
X1305079Y1494449D03*
X1313740Y1498780D03*
X1305079Y1504685D03*
X1313740Y1509016D03*
X1305079Y1509804D03*
X1313740Y1514134D03*
X1305079Y1560985D03*
X1313740Y1565315D03*
X1305079Y1566103D03*
X1313740Y1570434D03*
X1305079Y1591693D03*
X1313740Y1596024D03*
X1305079Y1596811D03*
X1313740Y1601142D03*
X1305079Y1607048D03*
X1313740Y1611378D03*
X1305079Y1612166D03*
X1313740Y1616496D03*
X1305079Y1622402D03*
X1331063Y1452717D03*
X1322402Y1473977D03*
X1331063Y1478308D03*
X1322402Y1479095D03*
X1331063Y1483426D03*
X1322402Y1489331D03*
X1331063Y1493662D03*
X1322402Y1494449D03*
X1331063Y1498780D03*
X1322402Y1504685D03*
X1331063Y1509016D03*
X1322402Y1509804D03*
X1331063Y1514134D03*
X1322402Y1560985D03*
X1331063Y1565315D03*
X1322402Y1566103D03*
X1331063Y1570434D03*
X1322402Y1591693D03*
X1331063Y1596024D03*
X1322402Y1596811D03*
X1331063Y1601142D03*
X1322402Y1607048D03*
X1331063Y1611378D03*
X1322402Y1612166D03*
X1331063Y1616496D03*
X1322402Y1622402D03*
X1348386Y1452717D03*
X1339725Y1473977D03*
X1348386Y1478308D03*
X1339725Y1479095D03*
X1348386Y1483426D03*
X1339725Y1489331D03*
X1348386Y1493662D03*
X1339725Y1494449D03*
X1348386Y1498780D03*
X1339725Y1504685D03*
X1348386Y1509016D03*
X1339725Y1509804D03*
X1348386Y1514134D03*
X1339725Y1560985D03*
X1348386Y1565315D03*
X1339725Y1566103D03*
X1348386Y1570434D03*
X1339725Y1591693D03*
X1348386Y1596024D03*
X1339725Y1596811D03*
X1348386Y1601142D03*
X1339725Y1607048D03*
X1348386Y1611378D03*
X1339725Y1612166D03*
X1348386Y1616496D03*
X1339725Y1622402D03*
X1365709Y1452717D03*
X1357047Y1473977D03*
X1365709Y1478308D03*
X1357047Y1479095D03*
X1365709Y1483426D03*
X1357047Y1489331D03*
X1365709Y1493662D03*
X1357047Y1494449D03*
X1365709Y1498780D03*
X1357047Y1504685D03*
X1365709Y1509016D03*
X1357047Y1509804D03*
X1365709Y1514134D03*
X1357047Y1560985D03*
X1365709Y1565315D03*
X1357047Y1566103D03*
X1365709Y1570434D03*
X1357047Y1591693D03*
X1365709Y1596024D03*
X1357047Y1596811D03*
X1365709Y1601142D03*
X1357047Y1607048D03*
X1365709Y1611378D03*
X1357047Y1612166D03*
X1365709Y1616496D03*
X1357047Y1622402D03*
X1383032Y1452717D03*
X1374370Y1458622D03*
Y1463741D03*
X1383032Y1462953D03*
Y1468071D03*
X1374370Y1473977D03*
Y1479095D03*
X1383032Y1478308D03*
Y1483426D03*
X1374370Y1489331D03*
Y1494449D03*
X1383032Y1493662D03*
Y1498780D03*
X1374370Y1504685D03*
Y1509804D03*
X1383032Y1509016D03*
Y1514134D03*
X1374370Y1560985D03*
Y1566103D03*
X1383032Y1565315D03*
Y1570434D03*
X1374370Y1576339D03*
Y1581457D03*
X1383032Y1580670D03*
Y1585788D03*
X1374370Y1591693D03*
X1383032Y1596024D03*
X1374370Y1596811D03*
X1383032Y1601142D03*
X1374370Y1607048D03*
Y1612166D03*
X1383032Y1611378D03*
Y1616496D03*
X1374370Y1622402D03*
X1478307Y1458622D03*
Y1463741D03*
Y1489331D03*
Y1494449D03*
Y1504685D03*
Y1509804D03*
Y1576339D03*
Y1581457D03*
Y1591693D03*
Y1596811D03*
Y1607048D03*
Y1612166D03*
Y1622402D03*
X1495630Y1458622D03*
Y1463741D03*
X1486968Y1452717D03*
Y1462953D03*
Y1468071D03*
X1495630Y1489331D03*
Y1494449D03*
X1486968Y1493662D03*
Y1498780D03*
X1495630Y1504685D03*
Y1509804D03*
X1486968Y1509016D03*
Y1514134D03*
X1495630Y1576339D03*
Y1581457D03*
Y1591693D03*
X1486968Y1580670D03*
Y1585788D03*
Y1596024D03*
X1495630Y1596811D03*
Y1607048D03*
Y1612166D03*
X1486968Y1601142D03*
Y1611378D03*
X1495630Y1622402D03*
X1486968Y1616496D03*
X1512953Y1458622D03*
Y1463741D03*
X1504291Y1452717D03*
Y1462953D03*
Y1468071D03*
X1512953Y1489331D03*
Y1494449D03*
X1504291Y1493662D03*
Y1498780D03*
X1512953Y1504685D03*
Y1509804D03*
X1504291Y1509016D03*
Y1514134D03*
X1512953Y1576339D03*
Y1581457D03*
Y1591693D03*
X1504291Y1580670D03*
Y1585788D03*
Y1596024D03*
X1512953Y1596811D03*
Y1607048D03*
Y1612166D03*
X1504291Y1601142D03*
Y1611378D03*
X1512953Y1622402D03*
X1504291Y1616496D03*
X1530275Y1458622D03*
Y1463741D03*
X1521614Y1452717D03*
Y1462953D03*
Y1468071D03*
X1530275Y1489331D03*
Y1494449D03*
X1521614Y1493662D03*
Y1498780D03*
X1530275Y1504685D03*
Y1509804D03*
X1521614Y1509016D03*
Y1514134D03*
X1530275Y1576339D03*
Y1581457D03*
Y1591693D03*
X1521614Y1580670D03*
Y1585788D03*
Y1596024D03*
X1530275Y1596811D03*
Y1607048D03*
Y1612166D03*
X1521614Y1601142D03*
Y1611378D03*
X1530275Y1622402D03*
X1521614Y1616496D03*
X1538937Y1452717D03*
Y1462953D03*
Y1468071D03*
Y1493662D03*
Y1498780D03*
Y1509016D03*
Y1514134D03*
Y1580670D03*
Y1585788D03*
Y1596024D03*
Y1601142D03*
Y1611378D03*
Y1616496D03*
X1556260Y1452717D03*
X1547598Y1458622D03*
Y1463741D03*
X1556260Y1462953D03*
Y1468071D03*
X1547598Y1473977D03*
Y1479095D03*
X1556260Y1478308D03*
Y1483426D03*
X1547598Y1489331D03*
Y1494449D03*
X1556260Y1493662D03*
Y1498780D03*
X1547598Y1504685D03*
Y1509804D03*
X1556260Y1509016D03*
Y1514134D03*
X1547598Y1560985D03*
Y1566103D03*
X1556260Y1565315D03*
Y1570434D03*
X1547598Y1576339D03*
Y1581457D03*
X1556260Y1580670D03*
Y1585788D03*
X1547598Y1591693D03*
X1556260Y1596024D03*
X1547598Y1596811D03*
X1556260Y1601142D03*
X1547598Y1607048D03*
Y1612166D03*
X1556260Y1611378D03*
Y1616496D03*
X1547598Y1622402D03*
X1660196Y1452717D03*
X1651535Y1458622D03*
X1660196Y1462953D03*
X1651535Y1463741D03*
X1660196Y1468071D03*
X1651535Y1473977D03*
X1660196Y1478308D03*
X1651535Y1479095D03*
X1660196Y1483426D03*
X1651535Y1504685D03*
X1660196Y1509016D03*
X1651535Y1509804D03*
X1660196Y1514134D03*
X1651535Y1560985D03*
X1660196Y1565315D03*
X1651535Y1566103D03*
X1660196Y1570434D03*
X1651535Y1576339D03*
X1660196Y1580670D03*
X1651535Y1581457D03*
X1660196Y1585788D03*
X1651535Y1607048D03*
X1660196Y1611378D03*
X1651535Y1612166D03*
X1660196Y1616496D03*
X1651535Y1622402D03*
X1668858Y1458622D03*
Y1463741D03*
Y1473977D03*
Y1479095D03*
Y1504685D03*
Y1509804D03*
Y1560985D03*
Y1566103D03*
Y1576339D03*
Y1581457D03*
Y1607048D03*
Y1612166D03*
Y1622402D03*
X1686181Y1458622D03*
Y1463741D03*
X1677519Y1452717D03*
Y1462953D03*
X1686181Y1473977D03*
Y1479095D03*
X1677519Y1468071D03*
Y1478308D03*
Y1483426D03*
X1686181Y1504685D03*
Y1509804D03*
X1677519Y1509016D03*
Y1514134D03*
X1686181Y1560985D03*
Y1566103D03*
Y1576339D03*
X1677519Y1565315D03*
Y1570434D03*
X1686181Y1581457D03*
X1677519Y1580670D03*
Y1585788D03*
X1686181Y1607048D03*
Y1612166D03*
X1677519Y1611378D03*
X1686181Y1622402D03*
X1677519Y1616496D03*
X1703503Y1458622D03*
Y1463741D03*
X1694842Y1452717D03*
Y1462953D03*
X1703503Y1473977D03*
Y1479095D03*
X1694842Y1468071D03*
Y1478308D03*
Y1483426D03*
X1703503Y1504685D03*
Y1509804D03*
X1694842Y1509016D03*
Y1514134D03*
X1703503Y1560985D03*
Y1566103D03*
Y1576339D03*
X1694842Y1565315D03*
Y1570434D03*
X1703503Y1581457D03*
X1694842Y1580670D03*
Y1585788D03*
X1703503Y1607048D03*
Y1612166D03*
X1694842Y1611378D03*
X1703503Y1622402D03*
X1694842Y1616496D03*
X1720826Y1458622D03*
Y1463741D03*
X1712165Y1452717D03*
Y1462953D03*
X1720826Y1473977D03*
Y1479095D03*
X1712165Y1468071D03*
Y1478308D03*
X1720826Y1489331D03*
Y1494449D03*
X1712165Y1483426D03*
X1720826Y1504685D03*
Y1509804D03*
X1712165Y1509016D03*
Y1514134D03*
X1720826Y1560985D03*
Y1566103D03*
Y1576339D03*
X1712165Y1565315D03*
Y1570434D03*
X1720826Y1581457D03*
Y1591693D03*
X1712165Y1580670D03*
Y1585788D03*
X1720826Y1596811D03*
Y1607048D03*
Y1612166D03*
X1712165Y1611378D03*
X1720826Y1622402D03*
X1712165Y1616496D03*
X1729488Y1452717D03*
Y1462953D03*
Y1468071D03*
Y1478308D03*
Y1483426D03*
Y1493662D03*
Y1498780D03*
Y1509016D03*
Y1514134D03*
Y1565315D03*
Y1570434D03*
Y1580670D03*
Y1585788D03*
Y1596024D03*
Y1601142D03*
Y1611378D03*
Y1616496D03*
G54D54*
X1030635Y754546D03*
Y774546D03*
Y784546D03*
Y794546D03*
Y804546D03*
Y814546D03*
Y824546D03*
G54D27*
X76112Y1348187D03*
X79512D03*
X76112Y1360099D03*
X79512D03*
Y1372385D03*
X76112D03*
Y1384297D03*
X79512D03*
X88352Y1348187D03*
X91752D03*
X100592D03*
X91752Y1360099D03*
X88352D03*
X100592D03*
Y1384297D03*
Y1372385D03*
X91752D03*
X88352D03*
Y1384297D03*
X91752D03*
Y1396583D03*
X88352D03*
X100592D03*
X91752Y1408495D03*
X88352D03*
X100592D03*
X116232Y1348187D03*
X112832D03*
X103992D03*
X112832Y1360099D03*
X116232D03*
X103992D03*
Y1372385D03*
Y1384297D03*
X112832D03*
X116232Y1372385D03*
Y1384297D03*
X112832Y1372385D03*
X116232Y1396583D03*
X112832D03*
X103992D03*
X112832Y1408495D03*
X116232D03*
X103992D03*
X125072Y1348187D03*
X128472D03*
Y1360099D03*
X125072D03*
Y1384297D03*
X128472D03*
X125072Y1372385D03*
X128472D03*
X125072Y1396583D03*
X128472D03*
X125072Y1408495D03*
X128472D03*
X140712Y1348187D03*
X137312D03*
X149552D03*
X137312Y1360099D03*
X140712D03*
X149552D03*
Y1384297D03*
Y1372385D03*
X140712D03*
Y1384297D03*
X137312D03*
Y1372385D03*
X140712Y1396583D03*
X137312D03*
X149552D03*
X140712Y1408495D03*
X137312D03*
X149552D03*
X165192Y1348187D03*
X161792D03*
X152952D03*
X165192Y1360099D03*
X161792D03*
X152952D03*
Y1384297D03*
Y1372385D03*
X161792Y1384297D03*
X165192Y1372385D03*
Y1384297D03*
X161792Y1372385D03*
X165192Y1396583D03*
X161792D03*
X152952D03*
X165192Y1408495D03*
X161792D03*
X152952D03*
X177432Y1348187D03*
X174032D03*
Y1360099D03*
X177432D03*
Y1384297D03*
X174032D03*
Y1372385D03*
X177432D03*
Y1396583D03*
X174032D03*
X177432Y1408495D03*
X174032D03*
X189672Y1348187D03*
X186272D03*
X198512D03*
X189672Y1360099D03*
X186272D03*
X198512D03*
Y1384297D03*
Y1372385D03*
X186272Y1384297D03*
X189672D03*
Y1372385D03*
X186272D03*
Y1396583D03*
X189672D03*
X198512D03*
X189672Y1408495D03*
X186272D03*
X198512D03*
X201912Y1348187D03*
Y1360099D03*
Y1384297D03*
Y1372385D03*
Y1396583D03*
Y1408495D03*
X241623Y1348187D03*
X245023D03*
Y1360099D03*
X241623D03*
X245023Y1372385D03*
X241623D03*
Y1384297D03*
X245023D03*
X253863Y1348187D03*
X257263D03*
X253863Y1360099D03*
X257263D03*
X253863Y1372385D03*
X257263D03*
X253863Y1384297D03*
X257263D03*
X253863Y1396583D03*
X257263D03*
Y1408495D03*
X253863D03*
X281594Y1211712D03*
X270374Y1215452D03*
X269503Y1348187D03*
X278343D03*
X266103D03*
X278343Y1360099D03*
X266103D03*
X269503D03*
Y1372385D03*
X266103D03*
X278343D03*
X266103Y1384297D03*
X269503D03*
X278343D03*
Y1396583D03*
X269503D03*
X266103D03*
X278343Y1408495D03*
X269503D03*
X266103D03*
X281743Y1348187D03*
X293983D03*
X290583D03*
X281743Y1360099D03*
X293983D03*
X290583D03*
X293983Y1372385D03*
X281743D03*
X290583Y1384297D03*
X293983D03*
X290583Y1372385D03*
X281743Y1384297D03*
X293983Y1396583D03*
X290583D03*
X281743D03*
Y1408495D03*
X293983D03*
X290583D03*
X302823Y1348187D03*
X306223D03*
Y1360099D03*
X302823D03*
X306223Y1372385D03*
X302823D03*
X306223Y1384297D03*
X302823D03*
Y1396583D03*
X306223D03*
X302823Y1408495D03*
X306223D03*
X327303Y1348187D03*
X315063D03*
X318463D03*
X327303Y1360099D03*
X315063D03*
X318463D03*
X315063Y1372385D03*
X318463Y1384297D03*
X315063D03*
X327303Y1372385D03*
X318463D03*
X327303Y1384297D03*
Y1396583D03*
X315063D03*
X318463D03*
X327303Y1408495D03*
X318463D03*
X315063D03*
X339543Y1348187D03*
X342943D03*
X330703D03*
Y1360099D03*
X342943D03*
X339543D03*
Y1372385D03*
X342943D03*
X330703D03*
X342943Y1384297D03*
X339543D03*
X330703D03*
Y1396583D03*
X339543D03*
X342943D03*
X330703Y1408495D03*
X342943D03*
X339543D03*
X351783Y1348187D03*
X355183D03*
Y1360099D03*
X351783D03*
Y1372385D03*
X355183D03*
Y1384297D03*
X351783D03*
Y1396583D03*
X355183D03*
X351783Y1408495D03*
X355183D03*
X364023Y1348187D03*
X367423D03*
Y1360099D03*
X364023D03*
Y1372385D03*
X367423Y1384297D03*
X364023D03*
X367423Y1372385D03*
X364023Y1396583D03*
X367423D03*
X364023Y1408495D03*
X367423D03*
X393094Y1423600D03*
X395894D03*
X440402Y1348187D03*
Y1360099D03*
Y1372385D03*
Y1384297D03*
X452642Y1348187D03*
X456042D03*
X443802D03*
X456042Y1360099D03*
X452642D03*
X443802D03*
Y1372385D03*
X452642D03*
X456042D03*
X452642Y1384297D03*
X456042D03*
X443802D03*
X452642Y1396583D03*
X456042D03*
X452642Y1408495D03*
X456042D03*
X468282Y1348187D03*
X464882D03*
X468282Y1360099D03*
X464882D03*
Y1372385D03*
X468282D03*
X464882Y1384297D03*
X468282D03*
Y1396583D03*
X464882D03*
Y1408495D03*
X468282D03*
X489362Y1348187D03*
X480522D03*
X477122D03*
X480522Y1360099D03*
X477122D03*
X489362D03*
X477122Y1372385D03*
X480522D03*
X489362D03*
Y1384297D03*
X480522D03*
X477122D03*
X480522Y1396583D03*
X477122D03*
X489362D03*
X477122Y1408495D03*
X480522D03*
X489362D03*
X492762Y1348187D03*
X501602D03*
X505002D03*
X501602Y1360099D03*
X505002D03*
X492762D03*
X505002Y1372385D03*
X492762D03*
X501602D03*
X492762Y1384297D03*
X505002D03*
X501602D03*
X505002Y1396583D03*
X492762D03*
X501602D03*
X505002Y1408495D03*
X501602D03*
X492762D03*
X517242Y1348187D03*
X513842D03*
Y1360099D03*
X517242D03*
Y1372385D03*
X513842D03*
X517242Y1384297D03*
X513842D03*
X517242Y1396583D03*
X513842D03*
X517242Y1408495D03*
X513842D03*
X529482Y1348187D03*
X526082D03*
X538322D03*
Y1360099D03*
X529482D03*
X526082D03*
X529482Y1372385D03*
X538322Y1384297D03*
X529482D03*
X538322Y1372385D03*
X526082D03*
Y1384297D03*
Y1396583D03*
X538322D03*
X529482D03*
Y1408495D03*
X526082D03*
X538322D03*
X553962Y1348187D03*
X541722D03*
X550562D03*
X553962Y1360099D03*
X550562D03*
X541722D03*
Y1372385D03*
X550562D03*
X541722Y1384297D03*
X553962D03*
X550562D03*
X553962Y1372385D03*
Y1396583D03*
X541722D03*
X550562D03*
X553962Y1408495D03*
X550562D03*
X541722D03*
X562802Y1348187D03*
X566202D03*
Y1360099D03*
X562802D03*
X566202Y1372385D03*
Y1384297D03*
X562802D03*
Y1372385D03*
X566202Y1396583D03*
X562802D03*
X566202Y1408495D03*
X562802D03*
X629688Y1396583D03*
X626288D03*
Y1408495D03*
X629688D03*
X650768Y1348187D03*
Y1360099D03*
Y1384297D03*
Y1372385D03*
X638528D03*
X641928D03*
X638528Y1384297D03*
X641928D03*
Y1396583D03*
X638528D03*
X650768D03*
X638528Y1408495D03*
X641928D03*
X650768D03*
X666408Y1348187D03*
X663008D03*
X654168D03*
X666408Y1360099D03*
X663008D03*
X654168D03*
Y1384297D03*
Y1372385D03*
X663008D03*
X666408D03*
X663008Y1384297D03*
X666408D03*
Y1396583D03*
X663008D03*
X654168D03*
X666408Y1408495D03*
X663008D03*
X654168D03*
X678648Y1348187D03*
X675248D03*
X678648Y1360099D03*
X675248D03*
Y1384297D03*
X678648D03*
Y1372385D03*
X675248D03*
Y1396583D03*
X678648D03*
Y1408495D03*
X675248D03*
X690888Y1348187D03*
X687488D03*
X699728D03*
X687488Y1360099D03*
X690888D03*
X699728D03*
Y1372385D03*
Y1384297D03*
X690888Y1372385D03*
X687488D03*
Y1384297D03*
X690888D03*
Y1396583D03*
X687488D03*
X699728D03*
X687488Y1408495D03*
X690888D03*
X699728D03*
X715368Y1348187D03*
X711968D03*
X703128D03*
X715368Y1360099D03*
X711968D03*
X703128D03*
Y1372385D03*
Y1384297D03*
X715368Y1372385D03*
X711968D03*
X715368Y1384297D03*
X711968D03*
X715368Y1396583D03*
X711968D03*
X703128D03*
X715368Y1408495D03*
X711968D03*
X703128D03*
X727608Y1348187D03*
X724208D03*
Y1360099D03*
X727608D03*
X724208Y1372385D03*
Y1384297D03*
X727608D03*
Y1372385D03*
X724208Y1396489D03*
X727608D03*
X724208Y1408401D03*
X727608D03*
X739848Y1348187D03*
X736448D03*
X748688D03*
X736448Y1360099D03*
X739848D03*
X748688D03*
Y1372385D03*
Y1384297D03*
X739848Y1372385D03*
X736448D03*
X739848Y1384297D03*
X736448D03*
X739848Y1396489D03*
X736448D03*
X739848Y1408401D03*
X736448D03*
X760928Y1348187D03*
X764328D03*
X752088D03*
X764328Y1360099D03*
X760928D03*
X752088D03*
Y1372385D03*
Y1384297D03*
X764328Y1372385D03*
X760928D03*
X764328Y1384297D03*
X760928D03*
X776568Y1348187D03*
X773168D03*
Y1360099D03*
X776568D03*
X878220Y848442D03*
Y845293D03*
Y835844D03*
Y851592D03*
X877800Y876500D03*
X897118Y848442D03*
X881370Y835844D03*
X893968Y845293D03*
X884519Y848442D03*
X897118Y842143D03*
X893968D03*
X887669Y848442D03*
X886093Y835318D03*
X897118Y845293D03*
X893968Y838994D03*
X890818Y842143D03*
X893968Y835846D03*
X887669Y845293D03*
X890818D03*
X893968Y848442D03*
X884519Y845293D03*
X881370D03*
X884519Y842143D03*
X887669D03*
X881370Y848442D03*
X890818D03*
X887669Y851592D03*
X890818Y854742D03*
X887669D03*
X897118Y851592D03*
X890818Y864189D03*
Y857891D03*
X887669Y864189D03*
X884519Y854742D03*
Y851592D03*
Y857891D03*
X887669D03*
X890818Y851592D03*
X893967Y851591D03*
X881370Y851592D03*
X887669Y867338D03*
X890818Y870488D03*
X887669D03*
X897118Y876787D03*
X890818Y867338D03*
X881370D03*
X897118Y879937D03*
X884519Y873638D03*
X887669D03*
X884519Y876787D03*
X890818Y879937D03*
X881370Y876787D03*
X887669Y879937D03*
X884519Y867338D03*
X890818Y873638D03*
X893968Y876787D03*
Y879937D03*
X890818Y876787D03*
X884519Y879937D03*
Y870488D03*
X881370D03*
Y883086D03*
X884585Y886354D03*
X885126Y889742D03*
X881370Y886236D03*
X906565Y848442D03*
X900267D03*
X906565Y838994D03*
X900267Y838992D03*
X909714Y848442D03*
X906565Y842143D03*
X900267Y845293D03*
Y842143D03*
X906565Y845293D03*
X900266Y835844D03*
X900267Y851592D03*
X906565D03*
X909714D03*
Y876787D03*
X900267Y879937D03*
Y876787D03*
X906565D03*
X912864Y873638D03*
Y879937D03*
X909714D03*
X906565D03*
X912864Y876787D03*
X922313Y845293D03*
X916014Y848442D03*
Y842143D03*
X919163Y845293D03*
X922313Y842143D03*
X916014Y845293D03*
X919163Y835844D03*
Y838994D03*
Y842143D03*
X925462Y845293D03*
X919163Y854742D03*
Y857891D03*
X922313Y854742D03*
X916014Y857891D03*
Y854742D03*
Y851592D03*
Y864189D03*
X925462Y851592D03*
X922313Y864189D03*
Y857891D03*
X925462D03*
X928612Y864189D03*
X919163D03*
X925462D03*
X916014Y870488D03*
X925462Y873638D03*
X922313Y876787D03*
X928612Y870488D03*
X925462D03*
X916014Y873638D03*
X922313D03*
X916014Y876787D03*
X928612Y873638D03*
X925462Y876787D03*
X928612D03*
Y879937D03*
X916014D03*
X922313D03*
X919163D03*
X925462D03*
X916014Y867338D03*
X919163Y873638D03*
Y870488D03*
X922313D03*
X919163Y876787D03*
X922313Y867338D03*
X919163D03*
X925462D03*
X922313Y883086D03*
Y886236D03*
X925462D03*
X919163Y883086D03*
X928612Y886236D03*
X925462Y883086D03*
X928612D03*
X1058113Y1348187D03*
X1054713D03*
X1058113Y1360099D03*
X1054713D03*
X1058113Y1372385D03*
X1054713D03*
Y1384297D03*
X1058113D03*
X1066953Y1348187D03*
X1070353D03*
X1066953Y1360099D03*
X1070353D03*
X1066953Y1384297D03*
Y1372385D03*
X1070353D03*
Y1384297D03*
Y1396583D03*
X1066953D03*
Y1408495D03*
X1070353D03*
X1091433Y1348187D03*
X1082593D03*
X1079193D03*
X1091433Y1360099D03*
X1082593D03*
X1079193D03*
Y1372385D03*
X1082593D03*
Y1384297D03*
X1079193D03*
X1091433D03*
Y1372385D03*
Y1396583D03*
X1082593D03*
X1079193D03*
X1091433Y1408495D03*
X1082593D03*
X1079193D03*
X1094833Y1348187D03*
X1107073D03*
X1103673D03*
X1094833Y1360099D03*
X1103673D03*
X1107073D03*
Y1372385D03*
X1103673D03*
X1107073Y1384297D03*
X1103673D03*
X1094833D03*
Y1372385D03*
Y1396583D03*
X1107073D03*
X1103673D03*
X1094833Y1408495D03*
X1107073D03*
X1103673D03*
X1115913Y1348187D03*
X1119313D03*
X1115913Y1360099D03*
X1119313D03*
Y1384297D03*
X1115913Y1372385D03*
X1119313D03*
X1115913Y1384297D03*
Y1396583D03*
X1119313D03*
X1115913Y1408495D03*
X1119313D03*
X1140393Y1348187D03*
X1131553D03*
X1128153D03*
X1140393Y1360099D03*
X1131553D03*
X1128153D03*
Y1384297D03*
X1131553D03*
X1128153Y1372385D03*
X1131553D03*
X1140393Y1384297D03*
Y1372385D03*
Y1396583D03*
X1131553D03*
X1128153D03*
X1140393Y1408495D03*
X1128153D03*
X1131553D03*
X1143793Y1348187D03*
X1156033D03*
X1152633D03*
X1143793Y1360099D03*
X1152633D03*
X1156033D03*
Y1384297D03*
X1152633D03*
X1156033Y1372385D03*
X1152633D03*
X1143793D03*
Y1384297D03*
Y1396583D03*
X1156033D03*
X1152633D03*
X1143793Y1408495D03*
X1152633D03*
X1156033D03*
X1168273Y1348187D03*
X1164873D03*
Y1360099D03*
X1168273D03*
Y1384297D03*
X1164873D03*
X1168273Y1372385D03*
X1164873D03*
Y1396583D03*
X1168273D03*
Y1408495D03*
X1164873D03*
X1184547Y1215452D03*
X1177113Y1348187D03*
X1180513D03*
X1177113Y1360099D03*
X1180513D03*
X1177113Y1384297D03*
X1180513D03*
X1177113Y1372385D03*
X1180513D03*
Y1396583D03*
X1177113D03*
Y1408495D03*
X1180513D03*
X1230326Y1348187D03*
X1233726D03*
X1230326Y1360099D03*
X1233726D03*
X1230326Y1372385D03*
X1233726D03*
X1230326Y1384297D03*
X1233726D03*
X1245966Y1348187D03*
X1242566D03*
X1254806D03*
Y1360099D03*
X1242566D03*
X1245966D03*
X1254806Y1372385D03*
X1242566D03*
X1245966D03*
X1242566Y1384297D03*
X1245966D03*
X1254806D03*
X1245966Y1396583D03*
X1254806D03*
X1242566D03*
X1254806Y1408495D03*
X1242566D03*
X1245966D03*
X1267046Y1348187D03*
X1270446D03*
X1258206D03*
Y1360099D03*
X1270446D03*
X1267046D03*
X1258206Y1372385D03*
X1270446D03*
X1267046D03*
X1270446Y1384297D03*
X1267046D03*
X1258206D03*
X1267046Y1396583D03*
X1270446D03*
X1258206D03*
Y1408495D03*
X1270446D03*
X1267046D03*
X1282686Y1348187D03*
X1279286D03*
Y1360099D03*
X1282686D03*
X1279286Y1372385D03*
X1282686D03*
Y1384297D03*
X1279286D03*
Y1396583D03*
X1282686D03*
X1279286Y1408495D03*
X1282686D03*
X1291526Y1348187D03*
X1294926D03*
X1291526Y1360099D03*
X1294926D03*
X1291526Y1372385D03*
X1294926D03*
X1291526Y1384297D03*
X1294926D03*
Y1396583D03*
X1291526D03*
Y1408495D03*
X1294926D03*
X1316906Y829871D03*
Y833021D03*
Y848769D03*
X1313756Y833021D03*
Y836170D03*
X1316906Y839320D03*
X1310555Y848675D03*
X1313756Y848769D03*
X1316906Y836170D03*
X1313756Y842470D03*
Y858218D03*
X1316906Y855068D03*
X1313756Y855066D03*
X1316906Y858218D03*
X1319406Y1348187D03*
X1316006D03*
X1307166D03*
X1303766D03*
X1319406Y1360099D03*
X1316006D03*
X1307166D03*
X1303766D03*
X1316006Y1372385D03*
X1307166D03*
X1303766D03*
Y1384297D03*
X1307166D03*
X1319406Y1372385D03*
X1316006Y1384297D03*
X1319406D03*
Y1396583D03*
X1316006D03*
X1303766D03*
X1307166D03*
X1316006Y1408495D03*
X1319406D03*
X1307166D03*
X1303766D03*
X1335803Y829871D03*
X1323205D03*
X1326355Y839320D03*
X1335803D03*
X1329504Y833021D03*
X1332654Y842470D03*
X1329504Y845619D03*
X1332654D03*
X1326355Y836170D03*
X1335803Y842470D03*
X1329504Y836170D03*
X1335803Y845619D03*
Y848769D03*
X1329504Y839320D03*
X1323205Y836170D03*
X1335803D03*
X1329504Y842470D03*
X1335803Y833021D03*
X1323205D03*
X1320055Y845619D03*
X1326355D03*
X1320055Y836170D03*
X1326355Y842470D03*
X1320055Y848769D03*
X1323205Y845619D03*
X1332654Y848769D03*
X1320055Y839320D03*
X1326355Y848769D03*
X1323205D03*
X1329504D03*
X1323204Y839319D03*
X1332654Y839320D03*
X1320055Y842470D03*
X1323205D03*
X1329504Y855068D03*
Y858218D03*
X1320055Y851918D03*
X1332654Y855068D03*
X1326355D03*
Y858218D03*
X1329504Y861367D03*
X1323205Y858218D03*
X1320055D03*
X1332654Y861367D03*
X1329504Y851918D03*
X1323205D03*
X1326355Y861367D03*
X1320055Y855068D03*
X1332654Y858218D03*
X1335803Y855068D03*
Y858218D03*
Y861367D03*
X1320055D03*
X1323204Y855067D03*
X1326355Y851918D03*
X1332654D03*
X1326355Y880263D03*
X1329504Y877114D03*
X1335803Y880263D03*
X1326355Y867665D03*
Y870814D03*
X1323205D03*
X1320055D03*
X1329504Y867665D03*
X1326355Y873964D03*
X1332654Y880263D03*
X1329504D03*
X1332654Y877114D03*
X1326355D03*
X1329504Y870814D03*
X1320055Y873964D03*
X1332654Y870814D03*
X1323204Y873965D03*
X1332654Y867665D03*
X1320055Y880263D03*
Y867665D03*
X1323205Y880263D03*
Y877114D03*
X1320055D03*
X1335803Y867665D03*
Y873964D03*
Y870814D03*
X1332654Y873964D03*
X1329504D03*
X1323205Y867665D03*
Y886562D03*
X1326355Y889712D03*
X1335803Y883413D03*
X1329504Y892862D03*
X1332654Y889712D03*
X1335803Y892862D03*
Y889712D03*
X1326355Y892862D03*
X1329504Y889712D03*
X1320055Y892862D03*
X1323205D03*
X1329504Y886562D03*
X1332654Y883413D03*
X1320055Y886562D03*
X1326355Y883413D03*
X1323205D03*
X1332654Y892862D03*
X1320055Y883413D03*
X1332654Y886562D03*
X1335803D03*
X1320055Y889712D03*
X1323204Y889713D03*
X1329504Y883413D03*
X1328246Y1348187D03*
X1331646D03*
X1328246Y1360099D03*
X1331646D03*
Y1384297D03*
Y1372385D03*
X1328246D03*
Y1384297D03*
X1331646Y1396583D03*
X1328246D03*
X1331646Y1408495D03*
X1328246D03*
X1342103Y845619D03*
X1345252Y836170D03*
X1338953Y845619D03*
X1345252Y833021D03*
X1342103Y836170D03*
X1351550D03*
X1342103Y842470D03*
X1345252Y845619D03*
X1342103Y839320D03*
X1338953Y848769D03*
X1338952Y839319D03*
X1345252Y842470D03*
X1342103Y848769D03*
X1338953Y842470D03*
X1345252Y848769D03*
X1338953Y836170D03*
X1351550Y842470D03*
Y848769D03*
Y845619D03*
X1345252Y839320D03*
X1351550Y858218D03*
X1345252D03*
Y861367D03*
X1342103Y858218D03*
X1351550Y861367D03*
X1338953Y851918D03*
X1342103D03*
X1345252D03*
X1351550D03*
X1338953Y880263D03*
X1351550D03*
X1345252D03*
X1342103Y870814D03*
X1345252D03*
Y867665D03*
X1351550Y870814D03*
Y867665D03*
X1338953Y877114D03*
X1345252D03*
X1351550D03*
X1342103Y880263D03*
X1338953Y883413D03*
X1345252Y889712D03*
Y886562D03*
X1342103Y883413D03*
X1345252D03*
X1338952Y889713D03*
X1338953Y892862D03*
X1342103Y886562D03*
Y892862D03*
Y889712D03*
X1338953Y886562D03*
X1351550Y883413D03*
Y889712D03*
Y886562D03*
Y892862D03*
X1343886Y1348187D03*
X1340486D03*
X1343886Y1360099D03*
X1340486D03*
X1343886Y1372385D03*
X1340486D03*
Y1384297D03*
X1343886D03*
X1340486Y1396583D03*
X1343886D03*
Y1408495D03*
X1340486D03*
X1364148Y829871D03*
X1367298D03*
X1359425Y829000D03*
X1354699Y842470D03*
Y848769D03*
X1357849D03*
X1364148Y845619D03*
X1354699Y836170D03*
X1357849Y833021D03*
X1367298Y845619D03*
X1364148Y842470D03*
X1357850Y839319D03*
X1357849Y836170D03*
X1360999Y842470D03*
X1354699Y845619D03*
X1357849D03*
X1360999Y839320D03*
X1367298Y842470D03*
X1360999Y848769D03*
Y845619D03*
X1367298Y833021D03*
X1354699Y839320D03*
X1360999Y836170D03*
X1367298Y848769D03*
X1364148Y839320D03*
X1357849Y842470D03*
X1364148Y833021D03*
X1367298Y836170D03*
Y839320D03*
X1364148Y848769D03*
Y851918D03*
X1367298Y861367D03*
X1364148Y858218D03*
Y855068D03*
Y861367D03*
X1367298Y858218D03*
Y851918D03*
X1354699Y858218D03*
X1367298Y855068D03*
X1360999D03*
Y858218D03*
Y861367D03*
X1354699Y851918D03*
X1357849D03*
X1364148Y867665D03*
X1367298Y877114D03*
X1364148Y870814D03*
X1367298Y873964D03*
X1364148D03*
Y877114D03*
X1367298Y870814D03*
X1364148Y880263D03*
X1367298D03*
X1357849D03*
X1360999D03*
X1367298Y867665D03*
X1354699Y870814D03*
X1357849Y877114D03*
X1354699Y880263D03*
X1360999Y867665D03*
Y870814D03*
Y873964D03*
X1367298Y883413D03*
X1354699Y892862D03*
X1360999D03*
X1367298D03*
X1360999Y883413D03*
X1357850Y889713D03*
X1364148Y889712D03*
X1357849Y883413D03*
X1367298Y889712D03*
X1354699D03*
X1357849Y886562D03*
X1364148D03*
X1357849Y892862D03*
X1360999Y889712D03*
X1354699Y883413D03*
X1360999Y886562D03*
X1364148Y892862D03*
Y883413D03*
X1367298Y886562D03*
X1354699D03*
X1356126Y1348187D03*
X1352726D03*
X1356126Y1360099D03*
X1352726D03*
Y1384297D03*
X1356126Y1372385D03*
Y1384297D03*
X1352726Y1372385D03*
X1356126Y1396583D03*
X1352726D03*
Y1408495D03*
X1356126D03*
X1370447Y829871D03*
Y839320D03*
X1383046Y845619D03*
X1379896D03*
X1373597D03*
Y842470D03*
X1370447Y848769D03*
X1379896D03*
Y839320D03*
X1373597Y848769D03*
X1376747D03*
X1373597Y833021D03*
X1370447D03*
X1373597Y836170D03*
X1370447D03*
X1373598Y839319D03*
X1370447Y842470D03*
Y845619D03*
X1383046Y842470D03*
X1376747Y836170D03*
Y842470D03*
X1379896Y833021D03*
X1383046Y839320D03*
X1376747Y845619D03*
Y839320D03*
X1379896Y855068D03*
Y861367D03*
X1376747Y858218D03*
Y851918D03*
X1373597Y861367D03*
X1376747Y855068D03*
X1373597Y858218D03*
X1376747Y861367D03*
X1383046Y851918D03*
X1373597D03*
X1373598Y855067D03*
X1379896Y851918D03*
X1370447D03*
Y858218D03*
X1383046D03*
Y861367D03*
X1370447Y855068D03*
Y861367D03*
X1383046Y873964D03*
X1376747Y880263D03*
X1370447Y877114D03*
X1373598Y873965D03*
X1370447Y873964D03*
X1379896Y877114D03*
X1373597Y880263D03*
X1383046Y877114D03*
X1370447Y880263D03*
X1376747Y873964D03*
X1383046Y880263D03*
X1370447Y870814D03*
X1376747D03*
X1373597D03*
X1376747Y867665D03*
Y877114D03*
X1373597Y867665D03*
X1379896D03*
X1383046Y870814D03*
X1379896Y880263D03*
X1373597Y877114D03*
X1379896Y873964D03*
X1383046Y892862D03*
X1379896Y886562D03*
X1370447Y883413D03*
X1373598Y889713D03*
X1376747Y886562D03*
X1383046Y883413D03*
X1376747Y889712D03*
X1383046D03*
X1379896D03*
X1373597Y883413D03*
Y886562D03*
X1370447Y892862D03*
X1376747D03*
X1370447Y889712D03*
X1373597Y892862D03*
X1383046Y886562D03*
X1379896Y892862D03*
X1376747Y883413D03*
X1464770Y1348187D03*
X1461370D03*
X1464770Y1360099D03*
X1461370D03*
X1464770Y1372385D03*
X1461370D03*
X1464770Y1384297D03*
X1461370D03*
X1477010Y1348187D03*
X1473610D03*
Y1360099D03*
X1477010D03*
X1473610Y1372385D03*
X1477010D03*
X1473610Y1384297D03*
X1477010D03*
Y1396583D03*
X1473610D03*
Y1408495D03*
X1477010D03*
X1489250Y1348187D03*
X1485850D03*
X1498090D03*
Y1360099D03*
X1485850D03*
X1489250D03*
Y1372385D03*
X1485850D03*
X1498090D03*
X1485850Y1384297D03*
X1498090D03*
X1489250D03*
X1498090Y1396583D03*
X1485850D03*
X1489250D03*
X1498090Y1408495D03*
X1489250D03*
X1485850D03*
X1513730Y1348187D03*
X1510330D03*
X1501490D03*
X1510330Y1360099D03*
X1501490D03*
X1513730D03*
X1510330Y1372385D03*
X1513730D03*
X1501490D03*
Y1384297D03*
X1513730D03*
X1510330D03*
Y1396583D03*
X1513730D03*
X1501490D03*
X1510330Y1408495D03*
X1513730D03*
X1501490D03*
X1525970Y1348187D03*
X1522570D03*
Y1360099D03*
X1525970D03*
Y1372385D03*
X1522570D03*
X1525970Y1384297D03*
X1522570D03*
Y1396583D03*
X1525970D03*
Y1408495D03*
X1522570D03*
X1538210Y1348187D03*
X1547050D03*
X1534810D03*
X1538210Y1360099D03*
X1534810D03*
X1547050D03*
X1538210Y1372385D03*
X1534810D03*
X1547050D03*
Y1384297D03*
X1534810D03*
X1538210D03*
Y1396583D03*
X1534810D03*
X1547050D03*
X1538210Y1408495D03*
X1534810D03*
X1547050D03*
X1550450Y1348187D03*
X1559290D03*
X1562690D03*
X1559290Y1360099D03*
X1562690D03*
X1550450D03*
X1562690Y1372385D03*
X1559290D03*
X1550450D03*
X1562690Y1384297D03*
X1559290D03*
X1550450D03*
Y1396583D03*
X1562690D03*
X1559290D03*
Y1408495D03*
X1562690D03*
X1550450D03*
X1574930Y1348187D03*
X1571530D03*
X1574930Y1360099D03*
X1571530D03*
X1574930Y1372385D03*
X1571530D03*
Y1384297D03*
X1574930D03*
X1571530Y1396583D03*
X1574930D03*
X1571530Y1408495D03*
X1574930D03*
X1587170Y1348187D03*
X1583770D03*
X1587170Y1360099D03*
X1583770D03*
X1587170Y1372385D03*
X1583770D03*
Y1384297D03*
X1587170D03*
X1583770Y1396583D03*
X1587170D03*
X1583770Y1408495D03*
X1587170D03*
X1611398Y1348187D03*
Y1360099D03*
Y1384297D03*
Y1372385D03*
X1614798Y1348187D03*
X1623638D03*
X1627038D03*
X1614798Y1360099D03*
X1623638D03*
X1627038D03*
Y1372385D03*
X1623638D03*
X1627038Y1384297D03*
X1623638D03*
X1614798Y1372385D03*
Y1384297D03*
X1627038Y1396583D03*
X1623638D03*
X1627038Y1408495D03*
X1623638D03*
X1641634Y1215452D03*
X1639278Y1348187D03*
X1635878D03*
X1639278Y1360099D03*
X1635878D03*
Y1384297D03*
X1639278D03*
Y1372385D03*
X1635878D03*
X1639278Y1396583D03*
X1635878D03*
Y1408495D03*
X1639278D03*
X1660358Y1348187D03*
X1651518D03*
X1648118D03*
X1660358Y1360099D03*
X1651518D03*
X1648118D03*
Y1372385D03*
X1651518D03*
X1648118Y1384297D03*
X1651518D03*
X1660358D03*
Y1372385D03*
Y1396583D03*
X1651518D03*
X1648118D03*
X1660358Y1408495D03*
X1648118D03*
X1651518D03*
X1663758Y1348187D03*
X1672598D03*
X1675998D03*
X1663758Y1360099D03*
X1675998D03*
X1672598D03*
X1675998Y1372385D03*
X1672598D03*
Y1384297D03*
X1675998D03*
X1663758D03*
Y1372385D03*
Y1396583D03*
X1675998D03*
X1672598D03*
X1663758Y1408495D03*
X1675998D03*
X1672598D03*
X1688238Y1348187D03*
X1684838D03*
X1688238Y1360099D03*
X1684838D03*
Y1384297D03*
X1688238D03*
X1684838Y1372385D03*
X1688238D03*
X1684838Y1396583D03*
X1688238D03*
Y1408495D03*
X1684838D03*
X1709318Y1348187D03*
X1700478D03*
X1697078D03*
X1709318Y1360099D03*
X1697078D03*
X1700478D03*
X1697078Y1372385D03*
X1700478D03*
X1697078Y1384297D03*
X1700478D03*
X1709318D03*
Y1372385D03*
Y1396583D03*
X1700478D03*
X1697078D03*
X1709318Y1408495D03*
X1697078D03*
X1700478D03*
X1712718Y1348187D03*
X1721558D03*
X1724958D03*
X1712718Y1360099D03*
X1724958D03*
X1721558D03*
Y1372385D03*
X1724958D03*
Y1384297D03*
X1721558D03*
X1712718Y1372385D03*
Y1384297D03*
Y1396583D03*
X1721558D03*
X1724958D03*
X1712718Y1408495D03*
X1721558D03*
X1724958D03*
X1733798Y1348187D03*
X1737198D03*
X1733798Y1360099D03*
X1737198D03*
Y1384297D03*
X1733798D03*
Y1372385D03*
X1737198D03*
Y1396583D03*
X1733798D03*
X1737198Y1408495D03*
X1733798D03*
G54D28*
X116731Y1052235D03*
X106619Y1056423D03*
X102431Y1066535D03*
X106619Y1076647D03*
X116731Y1080835D03*
Y1249086D03*
X106619Y1253274D03*
X102431Y1263386D03*
X106619Y1273498D03*
X116731Y1277686D03*
X126843Y1056423D03*
Y1076647D03*
X131031Y1066535D03*
X126843Y1253274D03*
X131031Y1263386D03*
X126843Y1273498D03*
X342840Y1056423D03*
X338652Y1066535D03*
X342840Y1076647D03*
Y1253274D03*
X338652Y1263386D03*
X342840Y1273498D03*
X352952Y1052235D03*
Y1080835D03*
Y1249086D03*
Y1277686D03*
X363064Y1056423D03*
Y1076647D03*
X367252Y1066535D03*
X363064Y1253274D03*
X367252Y1263386D03*
X363064Y1273498D03*
X563706Y1056423D03*
X559518Y1066535D03*
X563706Y1076647D03*
Y1253274D03*
X559518Y1263386D03*
X563706Y1273498D03*
X583930Y1056423D03*
X573818Y1052235D03*
X583930Y1076647D03*
X588118Y1066535D03*
X573818Y1080835D03*
X583930Y1253274D03*
X573818Y1249086D03*
X588118Y1263386D03*
X573818Y1277686D03*
X583930Y1273498D03*
X760433Y1480906D03*
X756274Y1490945D03*
X760433Y1500984D03*
X780511Y1480906D03*
X770472Y1476747D03*
Y1505143D03*
X780511Y1500984D03*
X799926Y1056423D03*
X795738Y1066535D03*
X799926Y1076647D03*
Y1253274D03*
X795738Y1263386D03*
X799926Y1273498D03*
X784670Y1490945D03*
X810040Y378544D03*
X805881Y388583D03*
X810040Y398622D03*
X810038Y1052235D03*
Y1080835D03*
Y1249086D03*
Y1277686D03*
X820079Y374385D03*
X830118Y378544D03*
X820079Y402781D03*
X830118Y398622D03*
X820150Y1056423D03*
Y1076647D03*
X824338Y1066535D03*
X820150Y1253274D03*
X824338Y1263386D03*
X820150Y1273498D03*
X834277Y388583D03*
X1010827Y378544D03*
X1006668Y388583D03*
X1010827Y398622D03*
X1020866Y374385D03*
Y402781D03*
X1020793Y1056423D03*
X1016605Y1066535D03*
X1020793Y1076647D03*
Y1253274D03*
X1016605Y1263386D03*
X1020793Y1273498D03*
X1030905Y378544D03*
X1035064Y388583D03*
X1030905Y398622D03*
X1041017Y1056423D03*
X1030905Y1052235D03*
X1041017Y1076647D03*
X1030905Y1080835D03*
X1041017Y1253274D03*
X1030905Y1249086D03*
Y1277686D03*
X1041017Y1273498D03*
X1045205Y1066535D03*
Y1263386D03*
X1060433Y1480906D03*
X1056274Y1490945D03*
X1060433Y1500984D03*
X1070472Y1476747D03*
Y1505143D03*
X1080511Y1480906D03*
X1084670Y1490945D03*
X1080511Y1500984D03*
X1252825Y1066535D03*
Y1263386D03*
X1267125Y1052235D03*
X1257013Y1056423D03*
Y1076647D03*
X1267125Y1080835D03*
Y1249086D03*
X1257013Y1253274D03*
Y1273498D03*
X1267125Y1277686D03*
X1277237Y1056423D03*
Y1076647D03*
X1281425Y1066535D03*
X1277237Y1253274D03*
X1281425Y1263386D03*
X1277237Y1273498D03*
X1477879Y1056423D03*
X1473691Y1066535D03*
X1477879Y1076647D03*
Y1253274D03*
X1473691Y1263386D03*
X1477879Y1273498D03*
X1498103Y1056423D03*
X1487991Y1052235D03*
X1498103Y1076647D03*
X1487991Y1080835D03*
X1498103Y1253274D03*
X1487991Y1249086D03*
Y1277686D03*
X1498103Y1273498D03*
X1502291Y1066535D03*
Y1263386D03*
X1709912Y1066535D03*
Y1263386D03*
X1724212Y1052235D03*
X1714100Y1056423D03*
Y1076647D03*
X1724212Y1080835D03*
Y1249086D03*
X1714100Y1253274D03*
Y1273498D03*
X1724212Y1277686D03*
X1734324Y1056423D03*
Y1076647D03*
X1738512Y1066535D03*
X1734324Y1253274D03*
X1738512Y1263386D03*
X1734324Y1273498D03*
G54D45*
X710406Y-26826D03*
Y-36826D03*
D03*
Y-26826D03*
X735406D03*
Y-36826D03*
D03*
Y-26826D03*
X830406Y-76006D03*
D03*
Y-66006D03*
D03*
X855406Y-76006D03*
D03*
Y-66006D03*
D03*
X939542Y-36798D03*
Y-26798D03*
D03*
Y-36798D03*
X964386Y-75978D03*
D03*
Y-65978D03*
D03*
X964542Y-36798D03*
Y-26798D03*
D03*
Y-36798D03*
X989386Y-75978D03*
D03*
Y-65978D03*
D03*
X993906Y-46826D03*
Y-36826D03*
D03*
Y-26826D03*
X1018906Y-46826D03*
Y-36826D03*
D03*
Y-26826D03*
X1063906Y-76006D03*
Y-86006D03*
Y-76006D03*
Y-66006D03*
X1088906Y-76006D03*
Y-86006D03*
Y-76006D03*
Y-66006D03*
X1217686Y-85978D03*
Y-75978D03*
D03*
Y-65978D03*
X1223042Y-46928D03*
Y-36928D03*
Y-26928D03*
Y-36928D03*
X1242686Y-85978D03*
Y-75978D03*
D03*
Y-65978D03*
X1248042Y-46928D03*
Y-36928D03*
Y-26928D03*
Y-36928D03*
X1280406Y-46956D03*
Y-36956D03*
D03*
Y-26956D03*
X1305406Y-46956D03*
Y-36956D03*
D03*
Y-26956D03*
X1320406Y-76006D03*
Y-86006D03*
Y-76006D03*
Y-66006D03*
X1345406Y-76006D03*
Y-86006D03*
Y-76006D03*
Y-66006D03*
X1474186Y-85978D03*
Y-75978D03*
D03*
Y-65978D03*
X1499186Y-85978D03*
Y-75978D03*
D03*
Y-65978D03*
X1509542Y-47058D03*
Y-37058D03*
Y-27058D03*
Y-37058D03*
X1534542Y-47058D03*
Y-37058D03*
Y-27058D03*
Y-37058D03*
X1564906Y-47086D03*
Y-37086D03*
D03*
Y-27086D03*
X1574906Y-76006D03*
Y-86006D03*
Y-76006D03*
Y-66006D03*
X1589906Y-47086D03*
Y-37086D03*
D03*
Y-27086D03*
X1599906Y-76006D03*
Y-86006D03*
Y-76006D03*
Y-66006D03*
X1728686Y-85978D03*
Y-75978D03*
D03*
Y-65978D03*
X1753686Y-85978D03*
Y-75978D03*
D03*
Y-65978D03*
X1794042Y-47188D03*
Y-37188D03*
Y-27188D03*
Y-37188D03*
X1819042Y-47188D03*
Y-37188D03*
Y-27188D03*
Y-37188D03*
G54D10*
X3704Y5374D03*
X3017Y24773D03*
Y44773D03*
Y64773D03*
Y84773D03*
Y104773D03*
Y124773D03*
Y144773D03*
Y164773D03*
Y184773D03*
Y204773D03*
Y224773D03*
Y244773D03*
Y264773D03*
Y284773D03*
Y304773D03*
X3221Y324773D03*
X3035Y978036D03*
Y998036D03*
Y1018036D03*
Y1038036D03*
Y1058036D03*
Y1078036D03*
Y1098036D03*
Y1118036D03*
Y1138036D03*
Y1158036D03*
Y1178036D03*
Y1198036D03*
Y1238036D03*
Y1258036D03*
Y1278036D03*
Y1298036D03*
Y1318036D03*
Y1338036D03*
Y1358036D03*
Y1378036D03*
Y1398036D03*
Y1418036D03*
Y1438036D03*
Y1458036D03*
Y1478036D03*
Y1498036D03*
Y1538036D03*
Y1558036D03*
X15972Y3000D03*
X10971Y333342D03*
X17964Y349298D03*
Y369298D03*
Y389298D03*
Y409298D03*
Y429298D03*
Y449298D03*
Y469298D03*
Y489298D03*
Y509298D03*
Y529298D03*
Y549298D03*
Y569298D03*
Y589298D03*
Y609298D03*
Y629298D03*
Y649298D03*
Y669298D03*
Y689298D03*
Y709298D03*
Y729298D03*
Y749298D03*
Y769298D03*
Y789298D03*
Y809298D03*
Y829298D03*
Y849298D03*
Y869298D03*
Y889298D03*
Y909298D03*
Y929298D03*
X9554Y961954D03*
X17964Y949298D03*
X6161Y1075991D03*
X6108Y1070611D03*
Y1065318D03*
X6059Y1091964D03*
X6055Y1086546D03*
X6053Y1081305D03*
X8042Y1522199D03*
X7922Y1532494D03*
X26956Y4469D03*
X28317Y24773D03*
Y44773D03*
X35638Y53597D03*
X36692Y641817D03*
X27934Y1204311D03*
X30934D03*
X27934Y1215511D03*
X30934D03*
X27934Y1212711D03*
Y1209911D03*
Y1207111D03*
X30934Y1212711D03*
Y1209911D03*
Y1207111D03*
X21544Y1479662D03*
X33536Y1467485D03*
X21544Y1489648D03*
X42192Y641817D03*
X51449Y822718D03*
X47949D03*
X44960Y1190619D03*
X49638Y1203884D03*
X40996Y1467703D03*
X40195Y1511279D03*
X55638Y53597D03*
X66371Y482134D03*
Y484634D03*
X60233Y521804D03*
X68202Y522129D03*
X60233Y524304D03*
X56540Y531378D03*
Y528878D03*
X68202Y527129D03*
Y524629D03*
Y529629D03*
X62789Y608311D03*
X66510Y628242D03*
X60849Y826818D03*
X64649D03*
X58949Y821018D03*
X64849Y840418D03*
X60249D03*
X74432Y5374D03*
X73745Y24773D03*
Y44773D03*
X73509Y110445D03*
Y115401D03*
X83911Y117557D03*
X80660Y103783D03*
X73509Y129574D03*
Y124618D03*
X83911Y122513D03*
Y131731D03*
Y136687D03*
X69816Y475946D03*
Y478446D03*
X78033Y478586D03*
Y481086D03*
Y476086D03*
Y483586D03*
X72549Y838818D03*
X93334Y3000D03*
X95943Y377953D03*
X113334Y3000D03*
X129318Y4469D03*
X130679Y24773D03*
Y44773D03*
X138000Y53597D03*
X146196Y390223D03*
X138194Y397335D03*
X146196Y395179D03*
Y404396D03*
Y409352D03*
X138194Y402291D03*
X135794Y416465D03*
Y411509D03*
X146196Y418569D03*
Y423525D03*
X135794Y425682D03*
Y430638D03*
X146196Y432743D03*
Y437699D03*
X135794Y439855D03*
Y444811D03*
Y468609D03*
Y473565D03*
X146196Y489895D03*
X135794Y487738D03*
X146196Y480677D03*
Y475721D03*
X135794Y482782D03*
X146196Y494851D03*
X135794Y512743D03*
Y517699D03*
X146196Y519855D03*
X135794Y526916D03*
Y531872D03*
X146196Y524811D03*
Y538984D03*
Y534028D03*
X158000Y53597D03*
X176794Y5374D03*
X176107Y24773D03*
Y44773D03*
X195697Y3000D03*
X183022Y103783D03*
X215697Y3000D03*
X231681Y4469D03*
X229745Y1446675D03*
X224753D03*
Y1462631D03*
X229745Y1457675D03*
X224753D03*
X229745Y1451631D03*
Y1462631D03*
X224753Y1451631D03*
X233042Y24773D03*
Y44773D03*
X240363Y53597D03*
X260363D03*
X279156Y5374D03*
X278469Y24773D03*
Y44773D03*
X265945Y440098D03*
Y437598D03*
Y435098D03*
Y432598D03*
Y430098D03*
X294959Y11097D03*
X285384Y103783D03*
X298059Y3000D03*
X301943Y332017D03*
X318059Y3000D03*
X318497Y466528D03*
Y471484D03*
X328899Y473640D03*
Y487813D03*
Y478596D03*
X318497Y480701D03*
Y485657D03*
X328899Y492769D03*
Y517774D03*
X318497Y510661D03*
Y515617D03*
X328899Y522730D03*
X318497Y524835D03*
X328899Y536903D03*
Y531947D03*
X318497Y529791D03*
X328899Y572769D03*
X318497Y565657D03*
Y560701D03*
X328899Y567813D03*
X318497Y579830D03*
Y574874D03*
X328899Y581987D03*
X318497Y589047D03*
X328899Y586943D03*
X318497Y594003D03*
X328899Y596160D03*
X318497Y603221D03*
X328899Y601116D03*
Y610333D03*
X318497Y608177D03*
X328899Y615289D03*
X334043Y4469D03*
X335404Y24773D03*
Y44773D03*
X342725Y53597D03*
X348737Y375386D03*
X354486Y377173D03*
X357173Y392183D03*
X357218Y396866D03*
X361234Y402867D03*
X358042Y442518D03*
Y439718D03*
X362725Y53597D03*
X361767Y392228D03*
X376992Y395248D03*
X368587Y409016D03*
X364551Y409032D03*
X361811Y396866D03*
X375919Y449118D03*
Y446318D03*
X367919Y449118D03*
Y446318D03*
X376099Y458309D03*
Y454309D03*
Y462309D03*
X369282Y468088D03*
Y465288D03*
X367816Y1310586D03*
Y1315542D03*
X388059Y3000D03*
X381518Y5374D03*
X388487Y24069D03*
X380831Y24773D03*
X383612Y30618D03*
X380831Y44773D03*
X387746Y103783D03*
X389237Y371070D03*
X385237Y370976D03*
X396373Y407104D03*
X385584Y450041D03*
Y452841D03*
Y455641D03*
X387587Y1296675D03*
X387644Y1302089D03*
X389458Y1365466D03*
X389188Y1369033D03*
X388600Y1395500D03*
X389985Y1405762D03*
X408059Y3000D03*
X396373Y409904D03*
X395577Y455641D03*
Y450041D03*
Y452841D03*
X397315Y479560D03*
X400914Y762675D03*
X408300Y755487D03*
X407965Y770196D03*
X408400Y795200D03*
Y792200D03*
X406600Y789000D03*
X402376Y842677D03*
X399876D03*
X402376Y850677D03*
X399876D03*
X395959Y1352153D03*
X403029Y1379716D03*
X403111Y1384920D03*
X408212Y1379695D03*
X394657Y1377875D03*
X403111Y1390103D03*
X408212Y1390083D03*
X410152Y1410928D03*
X398112Y1403741D03*
X415453Y455039D03*
X419040Y533690D03*
Y528390D03*
Y530990D03*
Y536290D03*
Y538890D03*
X423266Y631438D03*
X420266D03*
X417666D03*
X420266Y637038D03*
Y634238D03*
X417666Y637038D03*
Y634238D03*
X423266Y637038D03*
Y634238D03*
Y642638D03*
X420266D03*
X417666D03*
X423266Y639838D03*
X420266D03*
X417666D03*
X415696Y762466D03*
X424649Y842644D03*
X422149D03*
Y850644D03*
X424649D03*
X422149Y858644D03*
X424649D03*
X414280Y1362561D03*
X413437Y1379736D03*
Y1384899D03*
X413395Y1390062D03*
X428059Y3000D03*
X433724Y433975D03*
X432310Y436164D03*
X428740Y533690D03*
X442704Y533790D03*
X428740Y528390D03*
Y530990D03*
X442704Y528490D03*
Y531090D03*
X428740Y536290D03*
Y538890D03*
X442704Y536390D03*
Y538990D03*
X436369Y622883D03*
X441612Y631011D03*
X435881Y1394934D03*
Y1398800D03*
X448059Y3000D03*
X452404Y533690D03*
Y528390D03*
Y530990D03*
Y536290D03*
Y538890D03*
X468059Y3000D03*
X468850Y537507D03*
X461849Y668016D03*
X459349D03*
X466849D03*
X469349D03*
X464349D03*
X469349Y678016D03*
X466849D03*
X459349D03*
X461849D03*
X464349D03*
X484043Y4469D03*
X485404Y24773D03*
Y44773D03*
X482193Y472784D03*
Y468784D03*
Y476784D03*
X484341Y700528D03*
Y705484D03*
X492725Y53597D03*
X499278Y641817D03*
X493778D03*
X512725Y53597D03*
X523457Y482134D03*
Y484634D03*
X517319Y521804D03*
X513626Y528578D03*
Y531378D03*
X517319Y524304D03*
X519875Y608311D03*
X523596Y628242D03*
X531518Y5374D03*
X530831Y24773D03*
Y44773D03*
X537747Y103783D03*
X535119Y483886D03*
Y481086D03*
Y478586D03*
X526902Y478446D03*
Y475946D03*
X535119Y476086D03*
X525288Y522129D03*
Y524629D03*
Y527129D03*
Y529929D03*
X542275Y760782D03*
X532449Y782389D03*
X534672Y785037D03*
X536641Y838649D03*
X550421Y3000D03*
X542599Y782389D03*
X542546Y784911D03*
X554357Y784889D03*
X551524D03*
X570421Y3000D03*
X562231Y784911D03*
X558294D03*
X560263Y829989D03*
X568503Y936807D03*
X565003D03*
X586405Y4469D03*
X587766Y24773D03*
Y44773D03*
X583501Y800831D03*
X577903Y940907D03*
X581703D03*
X576003Y935107D03*
X581903Y954507D03*
X577303D03*
X595087Y53597D03*
X603282Y390223D03*
Y395179D03*
Y404396D03*
Y409352D03*
X595280Y402291D03*
Y397335D03*
X592880Y416465D03*
Y411509D03*
X603282Y418569D03*
Y423525D03*
X592880Y425682D03*
X603282Y432743D03*
Y437699D03*
X592880Y439855D03*
Y430638D03*
Y444811D03*
Y468609D03*
Y473565D03*
X603282Y489895D03*
X592880Y487738D03*
X603282Y480677D03*
Y475721D03*
X592880Y482782D03*
X603282Y494851D03*
X592880Y517699D03*
X603282Y519855D03*
X592880Y526916D03*
Y531872D03*
X603282Y524811D03*
Y538984D03*
Y534028D03*
X589603Y952907D03*
X615087Y53597D03*
X633248Y44884D03*
X640109Y103783D03*
X690073Y44662D03*
X697387Y53619D03*
X717387D03*
X723031Y440098D03*
Y437598D03*
Y435098D03*
Y432598D03*
Y430098D03*
X736242Y5374D03*
X735555Y24773D03*
Y44773D03*
X742471Y103783D03*
X755145Y3000D03*
X759029Y332017D03*
X775145Y3000D03*
X775584Y466528D03*
X775583Y471484D03*
Y480701D03*
Y485657D03*
Y515617D03*
Y510661D03*
Y524835D03*
Y529791D03*
Y560701D03*
Y565657D03*
Y579830D03*
Y574874D03*
Y589047D03*
Y594003D03*
Y603221D03*
Y608177D03*
X791129Y4469D03*
X792490Y24773D03*
Y44773D03*
X799811Y53597D03*
X785985Y473640D03*
Y487813D03*
Y478596D03*
Y492769D03*
Y517774D03*
Y522730D03*
Y531947D03*
Y536903D03*
Y572769D03*
Y567813D03*
Y581987D03*
Y586943D03*
Y601116D03*
Y596160D03*
Y615289D03*
Y610333D03*
X806318Y1401661D03*
X806874Y1447457D03*
X812474D03*
X806874Y1452587D03*
Y1457717D03*
X812474D03*
X815096Y1464387D03*
X812009Y1473432D03*
Y1470432D03*
X815096Y1467387D03*
X812096Y1479587D03*
Y1476587D03*
X815096Y1473387D03*
Y1479587D03*
Y1476587D03*
Y1470387D03*
X819811Y53597D03*
X829791Y839020D03*
X825721Y836666D03*
X823234Y867680D03*
X825774Y895553D03*
X816648Y1377608D03*
X817974Y1447457D03*
Y1452587D03*
Y1457717D03*
X818096Y1464387D03*
X821096D03*
X818096Y1473387D03*
X821096D03*
X824096D03*
X818096Y1479587D03*
X821096D03*
X824096D03*
X818096Y1476587D03*
X821096D03*
X824096D03*
X818096Y1467387D03*
Y1470387D03*
X821096D03*
Y1467387D03*
X824096D03*
Y1470387D03*
X838606Y5374D03*
X837919Y24773D03*
Y44773D03*
X844833Y103783D03*
X833185Y456309D03*
Y452309D03*
Y448309D03*
X850145Y3000D03*
X857973Y404867D03*
X862522Y400229D03*
X862566Y404867D03*
X857928Y400184D03*
X862020Y410899D03*
X862882Y468791D03*
Y465991D03*
X854882D03*
Y468791D03*
X861468Y491303D03*
X859071Y1447459D03*
X864671D03*
X859071Y1452589D03*
Y1457719D03*
X864671D03*
X864644Y1464759D03*
X861644D03*
X855644D03*
X858644D03*
Y1467759D03*
X855644Y1470759D03*
X858644D03*
X864644Y1467759D03*
Y1470759D03*
X861644Y1467759D03*
Y1470759D03*
X855644Y1467759D03*
Y1473759D03*
X858644D03*
X864644D03*
X861644D03*
X855644Y1476759D03*
X858644D03*
X864644D03*
X861644D03*
X872736Y383125D03*
X872318Y408589D03*
X866128Y417532D03*
X869342Y417399D03*
X880910Y471982D03*
Y469182D03*
Y466382D03*
X870882Y465991D03*
Y468791D03*
X878610Y747171D03*
X871294Y771809D03*
X871624Y1213314D03*
X874624D03*
X871624Y1221714D03*
Y1218914D03*
Y1216114D03*
X874624Y1221714D03*
Y1218914D03*
Y1216114D03*
X871624Y1224514D03*
X874624D03*
X870171Y1447459D03*
Y1452589D03*
Y1457719D03*
X867644Y1464759D03*
X870644D03*
X867644Y1467759D03*
X870644D03*
X867644Y1470759D03*
X870644D03*
X867644Y1473759D03*
X870644D03*
X867644Y1476759D03*
X870644D03*
X884736Y383125D03*
X893736D03*
X888736D03*
X891699Y420445D03*
Y423245D03*
X890903Y469182D03*
Y471982D03*
Y466382D03*
X896431Y534093D03*
X897118Y857891D03*
Y864189D03*
Y854742D03*
X893968Y864189D03*
Y857891D03*
Y854742D03*
X897118Y873638D03*
Y870488D03*
Y867338D03*
X893968Y870488D03*
Y873638D03*
Y867338D03*
X887669Y876787D03*
X888650Y1199622D03*
X893328Y1212887D03*
X912278Y343881D03*
X910779Y471380D03*
X903431Y534093D03*
X912462Y695770D03*
X912864Y848442D03*
Y845293D03*
Y842143D03*
X909714Y845293D03*
Y842143D03*
X900267Y864189D03*
X909714Y854742D03*
X906565Y857891D03*
X909714D03*
X906565Y864189D03*
X909714D03*
X906565Y854742D03*
X900267Y857891D03*
Y854742D03*
X912864Y851592D03*
Y857891D03*
Y854742D03*
X909714Y873638D03*
Y870488D03*
X906565Y873638D03*
Y870488D03*
Y867338D03*
X900267Y873638D03*
Y870488D03*
Y867338D03*
X909714D03*
X912171Y1447459D03*
X906671D03*
X901071D03*
X912171Y1457719D03*
Y1452589D03*
X906671Y1457719D03*
X901071D03*
Y1452589D03*
X908370Y1464583D03*
X905370D03*
X899370D03*
X902370D03*
X911370D03*
X905370Y1476583D03*
X908370D03*
X902370D03*
X899370D03*
X905370Y1473583D03*
X908370D03*
X902370D03*
X899370D03*
X902370Y1467583D03*
X899370Y1470583D03*
X902370D03*
X908370Y1467583D03*
Y1470583D03*
X905370Y1467583D03*
Y1470583D03*
X899370Y1467583D03*
X911370Y1476583D03*
Y1473583D03*
Y1467583D03*
Y1470583D03*
X930145Y3000D03*
X921847Y346622D03*
X927636Y452505D03*
X929050Y450316D03*
X928612Y835844D03*
X922313Y851592D03*
X929611Y858669D03*
X914370Y1464583D03*
Y1476583D03*
Y1473583D03*
Y1467583D03*
Y1470583D03*
X941129Y4469D03*
X942490Y24773D03*
Y44773D03*
X931620Y584417D03*
X931594Y599420D03*
X931647Y593271D03*
X931578Y590669D03*
X933810Y972433D03*
X935601Y1221714D03*
Y1218914D03*
Y1216114D03*
Y1213314D03*
X938601Y1221714D03*
Y1218914D03*
Y1216114D03*
Y1213314D03*
X935601Y1224514D03*
X938601D03*
X949811Y53597D03*
X956365Y641817D03*
X950865D03*
X950567Y927654D03*
X952627Y1199622D03*
X957305Y1212887D03*
X969811Y53597D03*
X976763Y307303D03*
X969623Y405614D03*
X963577Y426391D03*
X974406Y521804D03*
Y524304D03*
X970713Y531378D03*
Y528878D03*
X976962Y608311D03*
X980683Y628242D03*
X972278Y934429D03*
X988606Y5374D03*
X987919Y24773D03*
Y44773D03*
X994833Y103783D03*
X993132Y310942D03*
X993243Y321325D03*
X987055Y320273D03*
X993920Y335454D03*
X993420Y337954D03*
X992206Y478586D03*
Y481086D03*
Y483886D03*
X980544Y482134D03*
Y484634D03*
X992206Y476086D03*
X983989Y475946D03*
Y478446D03*
X982375Y522129D03*
Y527129D03*
Y524629D03*
Y529929D03*
X1007508Y3000D03*
X1004635Y300276D03*
X1008635D03*
X998667Y322239D03*
X1000420Y348954D03*
X1010119Y933822D03*
X1006619D03*
X1013683Y-44304D03*
Y-39348D03*
Y-29348D03*
Y-34304D03*
X1027508Y3000D03*
X1021895Y771974D03*
X1019519Y937922D03*
X1023319D03*
X1017619Y932122D03*
X1023519Y951522D03*
X1018919D03*
X1043492Y4469D03*
X1041496Y300276D03*
X1031354Y322905D03*
X1031219Y949922D03*
X1044853Y24773D03*
Y44773D03*
X1052174Y53597D03*
X1046674Y340031D03*
X1045966Y346808D03*
X1052367Y402291D03*
Y397335D03*
X1049967Y416465D03*
Y411509D03*
Y425682D03*
Y439855D03*
Y430638D03*
Y444811D03*
Y468609D03*
Y473565D03*
Y487738D03*
Y482782D03*
Y512743D03*
Y517699D03*
Y526916D03*
Y531872D03*
X1072174Y53597D03*
X1060369Y390223D03*
Y395179D03*
Y404396D03*
Y409352D03*
Y418569D03*
Y423525D03*
Y432743D03*
Y437699D03*
Y489895D03*
Y480677D03*
Y475721D03*
Y494851D03*
Y519855D03*
Y524811D03*
Y538984D03*
Y534028D03*
X1083683Y-78528D03*
Y-83484D03*
Y-73484D03*
Y-68528D03*
X1090280Y44773D03*
X1083483Y1523433D03*
X1097195Y103783D03*
X1147214Y44773D03*
X1154535Y53597D03*
X1174535D03*
X1176858Y306534D03*
X1180118Y430098D03*
Y440098D03*
Y437598D03*
Y435098D03*
Y432598D03*
X1193330Y5374D03*
X1192643Y24773D03*
Y44773D03*
X1199557Y103783D03*
X1192500Y322400D03*
X1199615Y950670D03*
X1201794Y985289D03*
X1212232Y3000D03*
X1221337Y332017D03*
X1232232Y3000D03*
X1232670Y466528D03*
Y471484D03*
Y480701D03*
Y485657D03*
Y515617D03*
Y510661D03*
Y524835D03*
Y529791D03*
Y565657D03*
Y560701D03*
Y579830D03*
Y589047D03*
Y574874D03*
Y603221D03*
Y594003D03*
Y608177D03*
X1248216Y4469D03*
X1249577Y24773D03*
Y44773D03*
X1243072Y473640D03*
Y487813D03*
Y478596D03*
Y492769D03*
Y522730D03*
Y517774D03*
Y536903D03*
Y531947D03*
Y567813D03*
Y572769D03*
Y586943D03*
Y581987D03*
Y601116D03*
Y596160D03*
Y610333D03*
Y615289D03*
X1256898Y53597D03*
X1266219Y374300D03*
X1268659Y377173D03*
X1276898Y53597D03*
X1275940Y392228D03*
X1271346Y392183D03*
X1275407Y402867D03*
X1271391Y396866D03*
X1275984D03*
X1282760Y409016D03*
X1278724Y409032D03*
X1272215Y442518D03*
Y439718D03*
X1282092Y449118D03*
Y446318D03*
X1283455Y468088D03*
Y465288D03*
X1300183Y-44434D03*
Y-29478D03*
Y-34434D03*
Y-39478D03*
X1302232Y3000D03*
X1295692Y5374D03*
X1303229Y23274D03*
X1295005Y24773D03*
X1297785Y30618D03*
X1295005Y44773D03*
X1301919Y103783D03*
X1303158Y371043D03*
X1299410Y370976D03*
X1291165Y395248D03*
X1290092Y449118D03*
Y446318D03*
X1299757Y450041D03*
Y452841D03*
Y455641D03*
X1290272Y458309D03*
Y454309D03*
Y462309D03*
X1310546Y409904D03*
Y407104D03*
X1309750Y455641D03*
Y450041D03*
Y452841D03*
X1311488Y479560D03*
X1309856Y899161D03*
X1305761D03*
X1313756D03*
X1322232Y3000D03*
X1320903Y370995D03*
X1333331Y370905D03*
X1329064Y370951D03*
X1329626Y455039D03*
X1340183Y-83484D03*
Y-78528D03*
Y-68528D03*
Y-73484D03*
X1342232Y3000D03*
X1338287Y370905D03*
X1347897Y433975D03*
X1346483Y436164D03*
X1362232Y3000D03*
X1382232D03*
X1373748Y397758D03*
X1375375Y428995D03*
X1398216Y4469D03*
X1399577Y24773D03*
Y44773D03*
X1397550Y390484D03*
X1387814Y397136D03*
X1389295Y408443D03*
X1386809Y414173D03*
X1388788Y428348D03*
X1406898Y53597D03*
X1416830Y407134D03*
X1411400Y398032D03*
X1413889Y415642D03*
X1413452Y641817D03*
X1407952D03*
X1426898Y53597D03*
X1431493Y521804D03*
X1427800Y528578D03*
X1431493Y524304D03*
X1427800Y531378D03*
X1422176Y1491198D03*
X1423806Y1524252D03*
X1445692Y5374D03*
X1445005Y24773D03*
Y44773D03*
X1440568Y369566D03*
X1449619Y363290D03*
X1438588Y380589D03*
X1437631Y482134D03*
Y484634D03*
X1449293Y476086D03*
X1441076Y475946D03*
Y478446D03*
X1449293Y478586D03*
Y481086D03*
Y483886D03*
X1439462Y522129D03*
Y529929D03*
Y527129D03*
Y524629D03*
X1434049Y608311D03*
X1437770Y628242D03*
X1464594Y3000D03*
X1462675Y14334D03*
X1451920Y103783D03*
X1455979Y391756D03*
X1458212Y403374D03*
X1473364Y410724D03*
X1472403Y417338D03*
X1469293Y428815D03*
X1484594Y3000D03*
X1498446Y912370D03*
X1497208Y909740D03*
X1500578Y4469D03*
X1501939Y24773D03*
Y44773D03*
X1509260Y53597D03*
X1509454Y402291D03*
Y397335D03*
X1507054Y416465D03*
Y411509D03*
Y425682D03*
Y439855D03*
Y430638D03*
Y444811D03*
Y468609D03*
Y473565D03*
Y487738D03*
Y482782D03*
Y517699D03*
Y512743D03*
Y526916D03*
Y531872D03*
X1507034Y888133D03*
X1507358Y909740D03*
X1507305Y912262D03*
X1501400Y966000D03*
X1529260Y53597D03*
X1517456Y390223D03*
Y395179D03*
Y404396D03*
Y409352D03*
Y418569D03*
Y423525D03*
Y432743D03*
Y437699D03*
Y489895D03*
Y480677D03*
Y475721D03*
Y494851D03*
Y519855D03*
Y538984D03*
Y524811D03*
Y534028D03*
X1516283Y912240D03*
X1519116D03*
X1523053Y912262D03*
X1525022Y957340D03*
X1547367Y44773D03*
X1554282Y103783D03*
X1594683Y-83484D03*
Y-78528D03*
Y-68528D03*
Y-73484D03*
X1584683Y-44564D03*
Y-29608D03*
Y-34564D03*
Y-39608D03*
X1604301Y44773D03*
X1611622Y53597D03*
X1631622D03*
X1637205Y440098D03*
Y437598D03*
Y435098D03*
Y432598D03*
Y430098D03*
X1650417Y5374D03*
X1649730Y24773D03*
Y44773D03*
X1656644Y103783D03*
X1669319Y3001D03*
X1673203Y332017D03*
X1689319Y3001D03*
X1689757Y466528D03*
Y471484D03*
Y480701D03*
Y485657D03*
Y515617D03*
Y510661D03*
Y524835D03*
Y529791D03*
Y565657D03*
Y560701D03*
Y589047D03*
Y574874D03*
Y579830D03*
Y603221D03*
Y594003D03*
Y608177D03*
X1705303Y4470D03*
X1706664Y24774D03*
Y44774D03*
X1700159Y473640D03*
Y487813D03*
Y478596D03*
Y492769D03*
Y517774D03*
Y522730D03*
Y536903D03*
Y531947D03*
Y572769D03*
Y567813D03*
Y586943D03*
Y581987D03*
Y601116D03*
Y596160D03*
Y610333D03*
Y615289D03*
X1713985Y53598D03*
X1725746Y377173D03*
X1723964Y370935D03*
X1733985Y53598D03*
X1733027Y392228D03*
X1728433Y392183D03*
X1739847Y409016D03*
X1735811Y409032D03*
X1732494Y402867D03*
X1728478Y396866D03*
X1733071D03*
X1729302Y439718D03*
Y442518D03*
X1739179Y449118D03*
Y446318D03*
X1740542Y468088D03*
Y465288D03*
X1752778Y5374D03*
X1752091Y24773D03*
Y44773D03*
X1756497Y370976D03*
X1748252Y395248D03*
X1756844Y450041D03*
Y452841D03*
Y455641D03*
X1747179Y449118D03*
Y446318D03*
X1747359Y454309D03*
Y458309D03*
Y462309D03*
X1765559Y3001D03*
X1759006Y103783D03*
X1760497Y371070D03*
X1767633Y409904D03*
Y407104D03*
X1766837Y450041D03*
Y452841D03*
Y455641D03*
X1768575Y479560D03*
X1773600Y888100D03*
X1773614Y895275D03*
X1773600Y902800D03*
X1786713Y455039D03*
X1788400Y888100D03*
X1781000Y888087D03*
X1788396Y895066D03*
X1788300Y902800D03*
X1780665Y902796D03*
X1781263Y964660D03*
X1784763D03*
X1779581Y1222200D03*
Y1219400D03*
Y1216600D03*
Y1213800D03*
X1782581Y1222200D03*
Y1219400D03*
Y1216600D03*
Y1213800D03*
X1779581Y1225000D03*
X1782581D03*
X1804984Y433975D03*
X1803570Y436164D03*
X1794163Y968760D03*
X1797963D03*
X1792263Y962960D03*
X1798163Y982360D03*
X1793563D03*
X1805863Y980760D03*
X1796607Y1200108D03*
X1801285Y1213373D03*
X1822983Y346053D03*
Y366053D03*
Y386053D03*
Y406053D03*
Y426053D03*
Y446053D03*
Y466053D03*
Y486053D03*
Y506053D03*
Y526053D03*
Y546053D03*
Y566053D03*
Y586053D03*
Y606053D03*
Y626053D03*
Y646053D03*
Y666053D03*
Y686053D03*
Y706053D03*
Y726053D03*
Y746053D03*
Y766053D03*
Y786053D03*
Y806053D03*
Y826053D03*
Y846053D03*
Y866053D03*
Y886053D03*
Y906053D03*
Y926053D03*
Y946053D03*
X1825559Y3001D03*
X1836543Y4470D03*
X1837904Y24774D03*
Y44774D03*
Y64774D03*
Y84774D03*
Y104774D03*
Y124774D03*
Y144774D03*
Y164774D03*
Y184774D03*
Y204774D03*
Y224774D03*
Y244774D03*
Y264774D03*
Y284774D03*
Y304774D03*
X1837728Y324733D03*
X1830094Y333210D03*
X1830472Y960970D03*
X1837937Y973244D03*
Y993244D03*
Y1013244D03*
Y1033244D03*
Y1053244D03*
Y1073244D03*
X1824733Y1102830D03*
X1837937Y1093244D03*
X1825832Y1097589D03*
X1837937Y1113244D03*
Y1133244D03*
Y1153244D03*
Y1173244D03*
Y1193244D03*
Y1213244D03*
Y1253244D03*
Y1273244D03*
Y1293244D03*
Y1313244D03*
Y1333244D03*
Y1353244D03*
Y1373244D03*
Y1393244D03*
Y1433244D03*
Y1453244D03*
Y1473244D03*
Y1493244D03*
Y1513244D03*
Y1533244D03*
Y1553244D03*
Y1573244D03*
G54D14*
X20408Y51296D03*
Y55296D03*
X9057Y138939D03*
X19184Y144728D03*
X15184D03*
X15520Y195176D03*
X18320D03*
X13020D03*
X10520D03*
X12880Y203393D03*
X10380D03*
X19068Y206838D03*
X16568D03*
X13606Y1476707D03*
X19365Y1494298D03*
X24316Y67527D03*
Y63527D03*
Y59527D03*
X23184Y144728D03*
X35650Y487982D03*
Y478982D03*
Y483982D03*
Y499982D03*
X25819Y531726D03*
Y536726D03*
Y552726D03*
Y540726D03*
X30410Y1218497D03*
Y1220997D03*
Y1234797D03*
Y1232297D03*
Y1227897D03*
Y1225397D03*
Y1241697D03*
Y1239197D03*
X25674Y1486291D03*
X32195Y1511279D03*
X32079Y1521641D03*
X31237Y1532096D03*
X46240Y109410D03*
X45988Y102323D03*
X46240Y116496D03*
X46931Y130670D03*
X49236Y121658D03*
X46932Y137756D03*
X49839Y546830D03*
X44195Y1511279D03*
X39237Y1532096D03*
X64098Y102323D03*
Y109410D03*
Y116496D03*
Y123583D03*
Y130670D03*
Y137756D03*
X69139Y236611D03*
X68841Y248891D03*
X66224Y473045D03*
X58224D03*
X53643Y472905D03*
X59670Y500086D03*
X64495Y527449D03*
X61695D03*
X60554Y1612002D03*
X66291Y1633801D03*
X74139Y236611D03*
X71639D03*
X71341Y248891D03*
X73841D03*
X74326Y480705D03*
X71995Y532749D03*
X74795D03*
X74291Y1633801D03*
X86291D03*
X119582Y102249D03*
X111582D03*
X115582D03*
X115382Y195176D03*
X112882D03*
X117882D03*
X115242Y203393D03*
X112742D03*
X120682Y195176D03*
X118930Y206838D03*
X121430D03*
X148602Y109410D03*
Y116496D03*
X148350Y102323D03*
X148774Y124576D03*
X149827Y130670D03*
X149822Y137756D03*
X166460Y116496D03*
Y109410D03*
Y102323D03*
Y123583D03*
Y130670D03*
Y137756D03*
X174001Y236611D03*
X176501D03*
X171501D03*
X176203Y248891D03*
X173703D03*
X171203D03*
X185169Y389154D03*
Y396240D03*
X186448Y404911D03*
X186589Y426299D03*
X185402Y412571D03*
X186900Y445847D03*
X185169Y467539D03*
Y474626D03*
X185430Y480828D03*
X187380Y498834D03*
X185169Y518760D03*
Y511673D03*
Y525847D03*
X191125Y602400D03*
Y598400D03*
Y594400D03*
Y606400D03*
Y614400D03*
X203591Y91951D03*
X213944Y102249D03*
X215244Y195176D03*
X215104Y203393D03*
X203280Y389154D03*
Y396240D03*
Y403327D03*
Y410413D03*
Y417500D03*
Y424586D03*
Y431673D03*
Y438760D03*
Y445847D03*
Y467539D03*
Y474626D03*
Y488799D03*
Y481713D03*
Y495886D03*
Y511673D03*
Y518760D03*
Y525847D03*
Y532933D03*
Y540020D03*
Y547106D03*
Y554193D03*
Y602205D03*
Y595118D03*
X221944Y102249D03*
X217944D03*
X220244Y195176D03*
X217744D03*
X223044D03*
X223792Y206838D03*
X221292D03*
X217604Y203393D03*
X228267Y392718D03*
Y408718D03*
Y400718D03*
Y404718D03*
Y412718D03*
X250964Y109410D03*
X250712Y102323D03*
X250964Y116496D03*
X251136Y124576D03*
X252189Y130670D03*
X252184Y137756D03*
X268822Y116496D03*
Y109410D03*
Y102323D03*
Y130670D03*
Y123583D03*
Y137756D03*
X276363Y236611D03*
X278863D03*
X273863D03*
X276065Y248891D03*
X273565D03*
X278565D03*
X274205Y466027D03*
X274347Y475262D03*
Y489435D03*
Y482666D03*
X274163Y495088D03*
X274205Y509626D03*
X274820Y522134D03*
X274898Y514608D03*
X275463Y529136D03*
X275302Y535677D03*
X274586Y565574D03*
X274205Y559665D03*
X274233Y574338D03*
X274332Y616358D03*
X292500Y410394D03*
Y403307D03*
X284295Y430760D03*
X284316Y433570D03*
X284132Y437072D03*
X284173Y439963D03*
X284417Y443180D03*
X284437Y454744D03*
X284379Y452018D03*
X292316Y458406D03*
Y465492D03*
Y472579D03*
Y479665D03*
Y486752D03*
Y493839D03*
Y523799D03*
Y516713D03*
Y509626D03*
Y537973D03*
Y530886D03*
Y559665D03*
Y566752D03*
Y573839D03*
Y588012D03*
Y580925D03*
Y595099D03*
Y602185D03*
Y616358D03*
Y609272D03*
X324306Y102249D03*
X320306D03*
X316306D03*
X322606Y195176D03*
X325406D03*
X320106D03*
X317606D03*
X323654Y206838D03*
X319966Y203393D03*
X317466D03*
X326154Y206838D03*
X319857Y321649D03*
X324291Y556775D03*
X353074Y102323D03*
X353326Y109410D03*
Y116496D03*
X353498Y124576D03*
X354551Y130670D03*
X354546Y137756D03*
X371184Y116496D03*
Y109410D03*
Y102323D03*
Y130670D03*
Y123583D03*
Y137756D03*
X376225Y236611D03*
X375927Y248891D03*
X373101Y779608D03*
X376300Y779800D03*
X370214Y959812D03*
Y967812D03*
X381225Y236611D03*
X378725D03*
X378427Y248891D03*
X380927D03*
X379800Y778000D03*
X387692Y790056D03*
X393547D03*
X386614Y868286D03*
X385512Y955356D03*
X390150Y955312D03*
Y959905D03*
X385467Y959950D03*
X409268Y408240D03*
X409386Y420393D03*
X400900Y755400D03*
Y770100D03*
X407193Y883566D03*
X396182Y955858D03*
X402682Y948536D03*
X402815Y951750D03*
X404004Y1198321D03*
Y1200821D03*
X407469Y1495035D03*
X407854Y1492118D03*
X406377Y1499142D03*
X411768Y408240D03*
X414268D03*
X411847Y424240D03*
X414386Y420393D03*
X411886D03*
X411847Y426740D03*
X415700Y755400D03*
Y770200D03*
X422430Y834800D03*
X422379Y867229D03*
X420661Y1119422D03*
X423141Y1113822D03*
Y1119422D03*
X418181Y1113822D03*
Y1119422D03*
X420661Y1113822D03*
X417469Y1200821D03*
Y1198321D03*
X439804Y536682D03*
Y539182D03*
X430934Y1200821D03*
Y1198321D03*
X430657Y1563562D03*
X446179Y447101D03*
X448726Y653288D03*
Y646480D03*
Y648980D03*
Y655788D03*
X450244Y1090268D03*
Y1093068D03*
X455269Y1119422D03*
X450309Y1113822D03*
Y1119422D03*
X452789Y1113822D03*
Y1119422D03*
X455269Y1113822D03*
X474307Y102249D03*
X470307D03*
X466307D03*
X470107Y195176D03*
X467607D03*
X472607D03*
X475407D03*
X473655Y206838D03*
X467467Y203393D03*
X469967D03*
X463104Y536582D03*
Y539082D03*
X476155Y206838D03*
X492736Y478982D03*
X482905Y531726D03*
X482737Y537215D03*
X482905Y552726D03*
Y540726D03*
X488728Y1119422D03*
X483768Y1113822D03*
X486248D03*
Y1119422D03*
X483768D03*
X488728Y1113822D03*
X477206Y1198321D03*
X490671D03*
Y1200821D03*
X477206D03*
X503075Y102323D03*
X503327Y109410D03*
Y116496D03*
X506653Y121652D03*
X504552Y130670D03*
X504547Y137756D03*
X493485Y439903D03*
X492736Y487982D03*
Y483982D03*
Y499982D03*
X506925Y546830D03*
X504136Y1198321D03*
Y1200821D03*
X521185Y116496D03*
Y109410D03*
Y102323D03*
Y130670D03*
Y123583D03*
Y137756D03*
X508729Y469905D03*
X521310Y470045D03*
X513310D03*
X516756Y500086D03*
X518781Y527449D03*
X521581D03*
X518812Y665867D03*
X515831Y1090568D03*
Y1093068D03*
X518376Y1113822D03*
Y1119422D03*
X520856Y1113822D03*
Y1119422D03*
X515896Y1113822D03*
Y1119422D03*
X526226Y236611D03*
X531226D03*
X528726D03*
X528428Y248891D03*
X530928D03*
X525928D03*
X531412Y480705D03*
X528612D03*
X529481Y532849D03*
X532281D03*
X533486Y664052D03*
X538442D03*
X524941Y661387D03*
X530796D03*
X572669Y102249D03*
X568669D03*
X572469Y195176D03*
X572329Y203393D03*
X567559Y812850D03*
X576669Y102249D03*
X574969Y195176D03*
X577769D03*
X578517Y206838D03*
X576017D03*
X605437Y102323D03*
X605689Y109410D03*
Y116496D03*
X605861Y124576D03*
X606914Y130670D03*
X606909Y137756D03*
X623547Y109410D03*
Y116496D03*
Y102323D03*
Y123583D03*
Y130670D03*
Y137756D03*
X633588Y236611D03*
X631088D03*
X628588D03*
X630790Y248891D03*
X633290D03*
X628290D03*
X642255Y389154D03*
Y396240D03*
X643534Y404911D03*
X642488Y412571D03*
X643675Y426299D03*
X643986Y445847D03*
X642255Y467539D03*
Y474626D03*
X642516Y480828D03*
X644466Y498834D03*
X642255Y518760D03*
Y511673D03*
Y525847D03*
X648211Y602400D03*
Y598400D03*
Y594400D03*
Y606400D03*
Y614400D03*
X660366Y389154D03*
Y403327D03*
Y410413D03*
Y396240D03*
Y417500D03*
Y424586D03*
Y431673D03*
Y438760D03*
Y445847D03*
Y467539D03*
Y474626D03*
Y488799D03*
Y481713D03*
Y495886D03*
Y511673D03*
Y518760D03*
Y525847D03*
Y532933D03*
Y540020D03*
Y554193D03*
Y547106D03*
Y602205D03*
Y595118D03*
X679031Y102249D03*
X672331Y195176D03*
X674831D03*
X680131D03*
X672191Y203393D03*
X674691D03*
X678379Y206838D03*
X680879D03*
X685353Y392718D03*
Y408718D03*
Y400718D03*
Y404718D03*
Y412718D03*
X707799Y102323D03*
X708051Y109410D03*
Y116496D03*
X708223Y124576D03*
X709276Y130670D03*
X709271Y137756D03*
X725909Y102323D03*
Y116496D03*
Y109410D03*
Y130670D03*
Y123583D03*
Y137756D03*
X733450Y236611D03*
X730950D03*
X733152Y248891D03*
X730652D03*
X731291Y466027D03*
X731433Y475262D03*
Y489435D03*
Y482666D03*
X731249Y495088D03*
X731984Y514608D03*
X731906Y522134D03*
X731291Y509626D03*
X732549Y529136D03*
X732388Y535677D03*
X731291Y559665D03*
X731672Y565574D03*
X731319Y574338D03*
X731418Y616358D03*
X735950Y236611D03*
X735652Y248891D03*
X749586Y410394D03*
Y403307D03*
X741259Y439963D03*
X741381Y430760D03*
X741402Y433570D03*
X741218Y437072D03*
X741503Y443180D03*
X741523Y454744D03*
X741465Y452018D03*
X749402Y458406D03*
Y465492D03*
Y472579D03*
Y479665D03*
Y486752D03*
Y493839D03*
Y523799D03*
Y516713D03*
Y509626D03*
Y537973D03*
Y530886D03*
Y559665D03*
Y566752D03*
Y573839D03*
Y588012D03*
Y580925D03*
Y602185D03*
Y595099D03*
Y609272D03*
Y616358D03*
X751140Y1581335D03*
X740640Y1586885D03*
X748924Y1617709D03*
X735878Y1617010D03*
X763040Y91951D03*
X781393Y102249D03*
X777393D03*
X773393D03*
X779693Y195176D03*
X777193D03*
X782493D03*
X774693D03*
X780741Y206838D03*
X783241D03*
X777053Y203393D03*
X774553D03*
X776943Y321649D03*
X778985Y442498D03*
X778881Y446510D03*
X779029Y450510D03*
X777033Y1595215D03*
X781545Y1602835D03*
X774658Y1601012D03*
X792564Y406410D03*
X784586Y421000D03*
Y418500D03*
Y413500D03*
Y416000D03*
X784665Y564843D03*
X787447Y1593586D03*
X791610Y1593708D03*
X810161Y102323D03*
X810413Y109410D03*
Y116496D03*
X810585Y124576D03*
X811638Y130670D03*
X811633Y137756D03*
X828271Y116496D03*
Y109410D03*
Y102323D03*
Y130670D03*
Y123583D03*
Y137756D03*
X835812Y236611D03*
X838312D03*
X833312D03*
X833014Y248891D03*
X838014D03*
X835514D03*
X867093Y570703D03*
Y582828D03*
Y558703D03*
Y562703D03*
Y566703D03*
Y578703D03*
X872440Y1230083D03*
Y1227583D03*
Y1234483D03*
Y1236983D03*
Y1243883D03*
Y1241383D03*
Y1248283D03*
Y1250783D03*
X889436Y715970D03*
X905094Y424581D03*
X902594D03*
X907594D03*
X905212Y436734D03*
X902712D03*
X907712D03*
X907173Y440581D03*
Y443081D03*
X909024Y578394D03*
Y574394D03*
X909714Y838994D03*
X931393Y102249D03*
X923393D03*
X927393D03*
X925359Y180347D03*
X927859D03*
X925219Y188564D03*
X927719D03*
X919606Y231000D03*
X919577Y245669D03*
Y233858D03*
X919682Y236921D03*
X919577Y259843D03*
Y255118D03*
X919729Y274580D03*
X930359Y180347D03*
X933159D03*
X931407Y192009D03*
X933907D03*
X941505Y463442D03*
X939827Y531104D03*
X939992Y536726D03*
Y540726D03*
Y552726D03*
X936417Y1234483D03*
Y1236983D03*
Y1230083D03*
Y1227583D03*
Y1243883D03*
Y1241383D03*
Y1248283D03*
Y1250783D03*
X956460Y-35982D03*
X953207Y-35996D03*
X956445Y-38497D03*
X953192Y-38511D03*
X950167Y-37191D03*
X960161Y102323D03*
X960413Y109410D03*
Y116496D03*
X961638Y130670D03*
X961633Y137756D03*
X950315Y464851D03*
X949823Y487982D03*
X949876Y478486D03*
X949823Y483982D03*
Y499982D03*
X978036Y-77691D03*
X978051Y-75176D03*
X975011Y-76371D03*
X978271Y109410D03*
Y102323D03*
Y116496D03*
Y130670D03*
Y123583D03*
X963360Y121459D03*
X978271Y137756D03*
X977150Y328472D03*
Y335472D03*
X967816Y472905D03*
X972397Y472954D03*
X973843Y500086D03*
X978668Y527449D03*
X975868D03*
X964012Y546830D03*
X978857Y1360945D03*
X981289Y-77677D03*
X981304Y-75162D03*
X985812Y236611D03*
X988312D03*
X983312D03*
X983014Y248891D03*
X988014D03*
X985514D03*
X980397Y473045D03*
X985699Y480705D03*
X988499D03*
X989068Y532949D03*
X986268D03*
X981857Y1360945D03*
X978944Y1413859D03*
X981944D03*
X1007611Y1561247D03*
Y1558247D03*
Y1555247D03*
Y1552247D03*
X1004611Y1561247D03*
Y1558247D03*
Y1555247D03*
Y1552247D03*
X1015402Y91951D03*
X1025755Y102249D03*
X1027055Y195176D03*
X1033755Y102249D03*
X1029755D03*
X1032055Y195176D03*
X1029555D03*
X1034855D03*
X1033103Y206838D03*
X1035603D03*
X1029415Y203393D03*
X1062523Y102323D03*
X1062775Y109410D03*
Y116496D03*
X1062947Y124576D03*
X1064000Y130670D03*
X1063995Y137756D03*
X1080633Y102323D03*
Y116496D03*
Y109410D03*
Y130670D03*
Y123583D03*
Y137756D03*
X1085674Y236611D03*
X1088174D03*
X1090674D03*
X1090376Y248891D03*
X1087876D03*
X1085376D03*
X1077855Y327478D03*
X1077252Y323521D03*
Y318565D03*
X1077855Y332434D03*
X1099342Y389154D03*
Y396240D03*
X1100621Y404911D03*
X1099575Y412571D03*
X1100762Y426299D03*
X1101073Y445847D03*
X1099342Y467539D03*
Y474626D03*
X1099603Y480828D03*
X1101553Y498834D03*
X1099342Y518760D03*
Y511673D03*
Y525847D03*
X1105298Y598400D03*
Y602400D03*
Y594400D03*
Y614400D03*
Y606400D03*
X1117764Y91951D03*
X1117453Y389154D03*
Y396240D03*
Y403327D03*
Y410413D03*
Y417500D03*
Y424586D03*
Y431673D03*
Y438760D03*
Y445847D03*
Y467539D03*
Y474626D03*
Y488799D03*
Y481713D03*
Y495886D03*
Y511673D03*
Y518760D03*
Y525847D03*
Y532933D03*
Y540020D03*
Y554193D03*
Y547106D03*
Y602205D03*
Y595118D03*
X1136117Y102249D03*
X1132117D03*
X1128117D03*
X1134417Y195176D03*
X1131917D03*
X1137217D03*
X1129417D03*
X1137965Y206838D03*
X1131777Y203393D03*
X1135465Y206838D03*
X1142440Y404718D03*
Y412718D03*
X1125287Y592897D03*
X1142440Y392718D03*
Y400718D03*
Y408718D03*
X1164885Y102323D03*
X1165137Y109410D03*
Y116496D03*
X1165309Y124576D03*
X1166362Y130670D03*
X1166357Y137756D03*
X1182995Y116496D03*
Y109410D03*
Y102323D03*
Y130670D03*
Y123583D03*
Y137756D03*
X1188036Y236611D03*
X1187738Y248891D03*
X1188378Y466027D03*
X1188520Y475262D03*
Y489435D03*
Y482666D03*
X1188336Y495088D03*
X1189071Y514608D03*
X1188993Y522134D03*
X1188378Y509626D03*
X1189475Y535677D03*
X1189636Y529136D03*
X1188378Y559665D03*
X1188759Y565574D03*
X1188406Y574338D03*
X1188505Y616358D03*
X1190536Y236611D03*
X1193036D03*
X1192738Y248891D03*
X1190238D03*
X1198468Y430760D03*
X1198489Y433570D03*
X1198305Y437072D03*
X1198346Y439963D03*
X1198552Y452018D03*
X1198590Y443180D03*
X1198610Y454744D03*
X1220126Y91951D03*
X1206673Y410394D03*
Y403307D03*
X1206489Y458406D03*
Y465492D03*
Y472579D03*
Y479665D03*
Y486752D03*
Y493839D03*
Y523799D03*
Y516713D03*
Y509626D03*
Y537973D03*
Y530886D03*
Y566752D03*
Y559665D03*
Y580925D03*
Y588012D03*
Y573839D03*
Y602185D03*
Y595099D03*
Y616358D03*
Y609272D03*
X1231336Y-87691D03*
X1234589Y-87777D03*
X1231351Y-85176D03*
X1234604Y-85262D03*
X1228311Y-86371D03*
X1236692Y-48727D03*
X1236707Y-46212D03*
X1233667Y-47421D03*
X1238479Y102249D03*
X1230479D03*
X1234479D03*
X1236779Y195176D03*
X1234279D03*
X1239579D03*
X1231779D03*
X1234139Y203393D03*
X1231639D03*
X1237827Y206838D03*
X1234100Y322924D03*
X1239945Y-48727D03*
X1239960Y-46212D03*
X1240327Y206838D03*
X1241752Y564843D03*
X1267499Y116496D03*
X1267247Y102323D03*
X1267499Y109410D03*
X1267671Y124576D03*
X1268724Y130670D03*
X1268719Y137756D03*
X1259500Y330000D03*
X1285357Y116496D03*
Y109410D03*
Y102323D03*
Y123583D03*
Y130670D03*
Y137756D03*
X1281834Y374839D03*
X1290398Y236611D03*
X1295398D03*
X1292898D03*
X1290100Y248891D03*
X1292600D03*
X1295100D03*
X1301500Y329000D03*
X1292731Y331820D03*
X1300400Y339619D03*
Y344575D03*
X1290066Y804246D03*
X1319000Y566500D03*
Y582500D03*
Y613000D03*
Y629000D03*
Y657500D03*
Y673500D03*
Y704500D03*
Y720500D03*
X1305412Y799061D03*
X1318178Y1198321D03*
Y1200821D03*
X1325941Y408240D03*
X1328441D03*
X1323441D03*
X1326059Y420393D03*
X1326020Y424240D03*
X1323559Y420393D03*
X1328559D03*
X1326020Y426740D03*
X1335802Y896011D03*
X1332355Y1113822D03*
Y1119422D03*
X1334835Y1113822D03*
Y1119422D03*
X1331643Y1200821D03*
Y1198321D03*
X1344768Y769675D03*
X1337315Y1113822D03*
Y1119422D03*
X1345108Y1200821D03*
Y1198321D03*
X1361039Y327099D03*
Y332055D03*
X1364039Y334973D03*
Y339929D03*
X1361039Y342847D03*
X1364039Y350721D03*
X1361039Y347803D03*
X1364039Y355677D03*
X1360352Y447101D03*
X1364148Y896011D03*
X1364418Y1090568D03*
Y1093068D03*
X1366963Y1119422D03*
Y1113822D03*
X1364483Y1119422D03*
Y1113822D03*
X1380480Y102249D03*
X1384480D03*
X1384280Y195176D03*
X1381780D03*
X1384140Y203393D03*
X1381640D03*
X1384253Y346826D03*
X1384447Y356871D03*
X1384174Y362641D03*
X1379896Y870814D03*
Y883413D03*
X1383046Y899161D03*
X1369443Y1119422D03*
Y1113822D03*
X1388480Y102249D03*
X1389580Y195176D03*
X1386780D03*
X1390328Y206838D03*
X1387828D03*
X1385943Y323222D03*
X1385971Y327688D03*
X1386143Y331982D03*
X1386057Y341200D03*
X1385971Y336791D03*
X1386286Y350218D03*
X1397079Y531726D03*
Y536726D03*
Y552726D03*
Y540726D03*
X1397942Y1119422D03*
X1400422D03*
Y1113822D03*
X1397942D03*
X1391380Y1200821D03*
Y1198321D03*
X1417248Y102323D03*
X1416347Y384373D03*
X1406910Y487982D03*
Y478982D03*
Y483982D03*
Y499982D03*
X1410000Y689000D03*
Y705000D03*
Y733000D03*
Y749000D03*
X1402902Y1119422D03*
Y1113822D03*
X1404845Y1198321D03*
Y1200821D03*
X1404239Y1547755D03*
X1403747Y1570433D03*
X1417500Y109410D03*
Y116496D03*
X1421700Y122900D03*
X1418725Y130670D03*
X1418720Y137756D03*
X1427484Y470045D03*
X1422903Y469905D03*
X1430930Y500086D03*
X1432955Y527449D03*
X1421099Y546830D03*
X1427000Y774500D03*
Y790500D03*
Y818500D03*
Y834500D03*
X1430005Y1090568D03*
Y1093068D03*
X1432550Y1119422D03*
Y1113822D03*
X1430070Y1119422D03*
Y1113822D03*
X1418310Y1198321D03*
Y1200821D03*
X1435358Y116496D03*
Y109410D03*
Y102323D03*
Y130670D03*
Y123583D03*
Y137756D03*
X1440399Y236611D03*
X1442899D03*
X1445399D03*
X1440101Y248891D03*
X1442601D03*
X1445101D03*
X1435484Y470045D03*
X1442786Y480705D03*
X1445586D03*
X1435755Y527449D03*
X1443555Y532949D03*
X1446355D03*
X1435030Y1119422D03*
Y1113822D03*
X1437293Y1546125D03*
X1436801Y1568803D03*
X1451215Y323193D03*
X1451330Y327588D03*
X1451272Y340971D03*
X1451344Y336620D03*
X1451300Y332225D03*
X1451387Y345609D03*
X1451186Y350447D03*
X1472489Y91951D03*
X1479500Y706500D03*
Y750500D03*
X1487836Y-87777D03*
X1491089D03*
X1487851Y-85262D03*
X1491104D03*
X1484811Y-86371D03*
X1490842Y102249D03*
X1486842D03*
X1482842D03*
X1486642Y195176D03*
X1489142D03*
X1484142D03*
X1491942D03*
X1492690Y206838D03*
X1490190D03*
X1484002Y203393D03*
X1486502D03*
X1484796Y320359D03*
X1484968Y325025D03*
X1484876Y329377D03*
X1488255Y342921D03*
X1484682Y338394D03*
X1497760Y336543D03*
X1487926Y347387D03*
X1496500Y792000D03*
Y836000D03*
X1500480Y295727D03*
X1523192Y-48857D03*
X1526445D03*
X1523207Y-46342D03*
X1526460D03*
X1520167Y-47451D03*
X1519610Y102323D03*
X1519862Y109410D03*
Y116496D03*
X1520034Y124576D03*
X1521087Y130670D03*
X1521082Y137756D03*
X1527876Y939439D03*
X1537720Y116496D03*
Y109410D03*
Y102323D03*
Y130670D03*
Y123583D03*
Y137756D03*
X1542761Y236611D03*
X1545261D03*
X1542463Y248891D03*
X1544963D03*
X1541534Y322850D03*
X1547761Y236611D03*
X1547463Y248891D03*
X1547972Y304906D03*
X1556151Y318596D03*
X1556294Y327814D03*
X1556437Y332022D03*
X1556380Y336917D03*
X1556498Y340958D03*
X1556353Y345636D03*
X1556429Y389154D03*
Y396240D03*
X1557708Y404911D03*
X1556662Y412571D03*
X1557849Y426299D03*
X1558160Y445847D03*
X1556429Y467539D03*
Y474626D03*
X1556690Y480828D03*
X1558640Y498834D03*
X1556429Y518760D03*
Y511673D03*
Y525847D03*
X1562385Y598400D03*
Y602400D03*
Y594400D03*
Y614400D03*
Y606400D03*
X1574851Y91951D03*
X1574845Y338843D03*
X1574540Y389154D03*
Y396240D03*
Y403327D03*
Y410413D03*
Y417500D03*
Y424586D03*
Y438760D03*
Y431673D03*
Y445847D03*
Y467539D03*
Y474626D03*
Y488799D03*
Y481713D03*
Y495886D03*
Y511673D03*
Y518760D03*
Y540020D03*
Y525847D03*
Y532933D03*
Y547106D03*
Y554193D03*
Y602205D03*
Y595118D03*
X1593204Y102249D03*
X1585204D03*
X1589204D03*
X1586504Y195176D03*
X1594304D03*
X1589004D03*
X1591504D03*
X1586364Y203393D03*
X1588864D03*
X1595052Y206838D03*
X1592552D03*
X1593290Y339876D03*
X1597006Y290417D03*
X1599527Y392718D03*
Y408718D03*
Y400718D03*
Y404718D03*
Y412718D03*
X1621972Y102323D03*
X1622224Y109410D03*
Y116496D03*
X1622396Y124576D03*
X1623449Y130670D03*
X1623444Y137756D03*
X1640082Y116496D03*
Y109410D03*
Y102323D03*
Y130670D03*
Y123583D03*
Y137756D03*
X1644825Y248891D03*
X1632230Y330400D03*
X1645123Y236611D03*
X1650123D03*
X1647623D03*
X1647325Y248891D03*
X1649825D03*
X1655555Y430760D03*
X1655576Y433570D03*
X1655392Y437072D03*
X1655433Y439963D03*
X1655677Y443180D03*
X1655697Y454744D03*
X1655639Y452018D03*
X1645465Y466027D03*
X1645607Y475262D03*
Y489435D03*
Y482666D03*
X1645423Y495088D03*
X1646158Y514608D03*
X1646080Y522134D03*
X1645465Y509626D03*
X1646562Y535677D03*
X1646723Y529136D03*
X1645465Y559665D03*
X1645846Y565574D03*
X1645493Y574338D03*
X1645592Y616358D03*
X1677213Y91951D03*
X1663760Y410394D03*
Y403307D03*
X1663576Y458406D03*
Y465492D03*
Y472579D03*
Y479665D03*
Y486752D03*
Y493839D03*
Y523799D03*
Y516713D03*
Y509626D03*
Y537973D03*
Y530886D03*
Y559665D03*
Y566752D03*
Y580925D03*
Y588012D03*
Y573839D03*
Y602185D03*
Y595099D03*
Y616358D03*
Y609272D03*
X1695566Y102249D03*
X1687566D03*
X1691566D03*
X1691366Y195176D03*
X1688866D03*
X1691226Y203393D03*
X1688726D03*
X1691117Y321649D03*
X1696666Y195176D03*
X1693866D03*
X1697414Y206838D03*
X1694914D03*
X1698839Y564843D03*
X1724334Y102323D03*
X1724586Y109410D03*
Y116496D03*
X1724758Y124576D03*
X1725811Y130670D03*
X1725806Y137756D03*
X1715705Y328692D03*
X1712734Y340534D03*
X1742336Y-87777D03*
X1739311Y-86371D03*
X1734826Y376499D03*
X1745589Y-87777D03*
X1742351Y-85262D03*
X1745604D03*
X1742444Y102323D03*
Y116496D03*
Y109410D03*
Y130670D03*
Y123583D03*
Y137756D03*
X1752485Y236611D03*
X1749985D03*
X1747485D03*
X1747187Y248891D03*
X1749687D03*
X1752187D03*
X1747561Y385161D03*
X1758583Y1581027D03*
X1750685Y1618504D03*
X1756422Y1640303D03*
X1770680Y926322D03*
X1763818Y926241D03*
X1765294Y1575434D03*
X1759092Y1588137D03*
X1767142Y1588219D03*
X1764422Y1640303D03*
X1779575Y91951D03*
X1790533Y303750D03*
X1783028Y408240D03*
X1785528D03*
X1780528D03*
X1783107Y424240D03*
X1780646Y420393D03*
X1785646D03*
X1783146D03*
X1783107Y426740D03*
X1780397Y1237469D03*
Y1230569D03*
Y1228069D03*
Y1234969D03*
Y1241869D03*
Y1244369D03*
Y1248769D03*
Y1251269D03*
X1776422Y1640303D03*
X1804667Y-47581D03*
X1804993Y297591D03*
X1807692Y-49001D03*
X1810945Y-48987D03*
X1807707Y-46486D03*
X1810960Y-46472D03*
X1817439Y447101D03*
G54D30*
X106586Y1204932D03*
X563673D03*
X1020434Y1205579D03*
X1477846Y1204932D03*
G54D38*
X190325Y368760D03*
Y455492D03*
Y503760D03*
Y583957D03*
Y636752D03*
X647411Y368760D03*
Y455492D03*
Y503760D03*
Y583957D03*
Y636752D03*
X1104498Y368760D03*
Y455492D03*
Y503760D03*
Y583957D03*
Y636752D03*
X1561585Y368760D03*
Y455492D03*
Y503760D03*
Y583957D03*
Y636752D03*
G54D43*
X515573Y692515D03*
X518299Y692384D03*
X520799D03*
X529493Y692443D03*
Y697443D03*
Y699943D03*
X529501Y702622D03*
X526993Y692443D03*
X529493Y694943D03*
X524493Y692443D03*
X1809078Y2165771D03*
X1806706Y2180760D03*
X1812366Y2063809D03*
X1822066Y2054109D03*
X1812366D03*
X1813087Y2087512D03*
X1825427Y2104853D03*
X1817378Y2165771D03*
X1815006Y2180760D03*
X1841295Y2065122D03*
X1832995D03*
X1833649Y2057507D03*
X1830872Y2083503D03*
X1840875Y2083215D03*
X1837649Y2072324D03*
X1829349D03*
X1833727Y2104853D03*
X1835862Y2121040D03*
X1833506Y2185252D03*
X1852032Y2052576D03*
X1854559Y2077931D03*
X1851762Y2121040D03*
X1854796Y2170548D03*
X1846496D03*
X1855978Y2185118D03*
X1847678D03*
X1859032Y2052576D03*
X1870505Y2064156D03*
X1860338Y2071384D03*
X1874505Y2078973D03*
X1860234Y2157701D03*
X1867072Y2174962D03*
X1864547Y2185020D03*
X1890039Y2066092D03*
X1878805Y2064156D03*
X1886128Y2075919D03*
X1882805Y2078973D03*
X1876497Y2070684D03*
X1884535Y2155415D03*
X1882972Y2174962D03*
X1882111Y2179074D03*
X1874932Y2180585D03*
X1881852Y2196600D03*
X1886699Y2183170D03*
X1876697D03*
X1905939Y2066092D03*
X1893118Y2054585D03*
X1905944Y2055424D03*
X1898342Y2062143D03*
X1901295Y2072745D03*
X1892835Y2155415D03*
X1902872Y2178531D03*
X1894572D03*
X1893087Y2168011D03*
X1896403Y2185019D03*
X1917195Y2072745D03*
X1917550Y2158451D03*
X1909250D03*
X1922010Y2151829D03*
X1913710D03*
X1921855Y2172152D03*
X1936295Y2074343D03*
X1935195Y2155918D03*
X1936377Y2163810D03*
X1924735Y2178131D03*
X1936212Y2173508D03*
X1930155Y2172152D03*
X1931738Y2182647D03*
X1923438D03*
X1941040Y2070124D03*
X1951095Y2155918D03*
X1946077Y2163810D03*
X1969128Y2161283D03*
X1959428D03*
X1969128Y2151583D03*
X1959428D03*
G54D51*
X909360Y230906D03*
Y274606D03*
G54D21*
X51043Y144095D03*
X57933Y66811D03*
X160295D03*
X153405Y144095D03*
X183435Y630650D03*
X190325Y374862D03*
X262657Y66811D03*
X255767Y144095D03*
X279360Y630650D03*
X286250Y374862D03*
X358129Y144095D03*
X365019Y66811D03*
X508130Y144095D03*
X515020Y66811D03*
X617382D03*
X610492Y144095D03*
X647411Y374862D03*
X640521Y630650D03*
X719744Y66811D03*
X712854Y144095D03*
X736446Y630650D03*
X743336Y374862D03*
X815216Y144095D03*
X822106Y66811D03*
X972106D03*
X965216Y144095D03*
X1074468Y66811D03*
X1067578Y144095D03*
X1104498Y374862D03*
X1097608Y630650D03*
X1169940Y144095D03*
X1176830Y66811D03*
X1200423Y374862D03*
X1193533Y630650D03*
X1272302Y144095D03*
X1279192Y66811D03*
X1429193D03*
X1422303Y144095D03*
X1531555Y66811D03*
X1524665Y144095D03*
X1561585Y374862D03*
X1554695Y630650D03*
X1627027Y144095D03*
X1633917Y66811D03*
X1657510Y374862D03*
X1650620Y630650D03*
X1736279Y66811D03*
X1729389Y144095D03*
G54D24*
X46248Y1760941D03*
Y1750941D03*
Y1806941D03*
Y1796941D03*
X143208Y1084547D03*
Y1092027D03*
X146948Y1077066D03*
Y1084547D03*
Y1092027D03*
X143208Y1095767D03*
X146948D03*
X143208Y1110728D03*
Y1118208D03*
X146948Y1110728D03*
Y1118208D03*
X146949Y1166830D03*
X154429Y1073326D03*
X161909D03*
X154429Y1092027D03*
X161909Y1077066D03*
X165649Y1080807D03*
Y1088287D03*
X161909D03*
Y1092027D03*
X154429Y1077066D03*
X158169Y1080807D03*
X150689D03*
X158169Y1084547D03*
X150689D03*
X158169Y1088287D03*
X154429D03*
X150689D03*
X165649Y1084547D03*
X158169Y1099507D03*
X150689D03*
X158169Y1103247D03*
X150689D03*
X161909Y1095767D03*
X165649Y1099507D03*
Y1103247D03*
X154429Y1106988D03*
X150689D03*
X154429Y1095767D03*
X158169Y1110728D03*
Y1114468D03*
X154429D03*
X150689D03*
X158169Y1129429D03*
X165649Y1166830D03*
Y1170570D03*
Y1178050D03*
Y1174310D03*
X163779Y1213582D03*
X160039D03*
X214271Y1114468D03*
X238582Y1078936D03*
X242322Y1082677D03*
X238582Y1097637D03*
X246062Y1254724D03*
X238582D03*
Y1250984D03*
X234842Y1247243D03*
X242322Y1243503D03*
Y1247243D03*
X246062Y1250984D03*
X249803Y1082677D03*
X257283D03*
X249803Y1101377D03*
X253543Y1250984D03*
Y1254724D03*
X249803Y1247243D03*
X253543Y1239763D03*
X249803D03*
X257283Y1247243D03*
X261023Y1250984D03*
Y1239763D03*
Y1254724D03*
X279724Y1082677D03*
Y1086417D03*
X275984Y1078936D03*
X264763Y1082677D03*
X275984Y1097637D03*
X274114Y1121948D03*
X277854Y1133169D03*
Y1125688D03*
X274114Y1204232D03*
X279724Y1247243D03*
X272244Y1243503D03*
Y1247243D03*
X264763D03*
X268503Y1250984D03*
X264763Y1243503D03*
X272244Y1239763D03*
X275984Y1250984D03*
X279724Y1243503D03*
X268503Y1254724D03*
X275984D03*
X294684Y1082677D03*
Y1090157D03*
X294685Y1086417D03*
X290944Y1078936D03*
X287204Y1082677D03*
X283464Y1093897D03*
X290944Y1097637D03*
X294685Y1247243D03*
Y1243503D03*
X283464Y1250984D03*
X287204Y1247243D03*
Y1243503D03*
Y1239763D03*
X290944Y1250984D03*
X283464Y1254724D03*
X290944D03*
X302164Y1082677D03*
X302165Y1086417D03*
X309644Y1082677D03*
X309645Y1086417D03*
X298425Y1097637D03*
X305905D03*
X300295Y1155610D03*
X309645Y1247243D03*
Y1243503D03*
X298425Y1250984D03*
X302165Y1247243D03*
Y1243503D03*
Y1239763D03*
X305905Y1250984D03*
X298425Y1254724D03*
X305905D03*
X320866Y1086417D03*
X317126D03*
X317125Y1082677D03*
X324606Y1086417D03*
X320866Y1093897D03*
X324606D03*
Y1105117D03*
Y1097637D03*
X320866Y1105117D03*
Y1097637D03*
X313385D03*
X324606Y1112598D03*
Y1120078D03*
X320866Y1112598D03*
Y1120078D03*
X317125Y1108858D03*
X320866Y1127558D03*
Y1135039D03*
X322736Y1140649D03*
X324606Y1127558D03*
Y1135039D03*
X326476Y1140649D03*
X322736Y1155610D03*
X326476Y1148129D03*
Y1155610D03*
X322736Y1148129D03*
X326476Y1170570D03*
Y1178051D03*
Y1185531D03*
X320866Y1250984D03*
X313385D03*
X317125Y1247243D03*
Y1243503D03*
X313385Y1254724D03*
X317125Y1239763D03*
X320866Y1254724D03*
X333286Y1728583D03*
Y1738583D03*
X333212Y1774624D03*
Y1784624D03*
X438162Y1348187D03*
Y1360099D03*
Y1384297D03*
Y1372385D03*
X450402Y1348187D03*
Y1360099D03*
Y1384297D03*
Y1372385D03*
Y1396583D03*
Y1408495D03*
X462642Y1348187D03*
X474882D03*
X462642Y1360099D03*
X474882D03*
X462642Y1384297D03*
X474882D03*
X462642Y1372385D03*
X474882D03*
Y1396583D03*
X462642D03*
X474882Y1408495D03*
X462642D03*
X487122Y1348187D03*
Y1360099D03*
Y1372385D03*
Y1384297D03*
Y1396583D03*
Y1408495D03*
X499362Y1348187D03*
Y1360099D03*
Y1372385D03*
Y1384297D03*
Y1396583D03*
Y1408495D03*
X511602Y1348187D03*
Y1360099D03*
Y1372385D03*
Y1384297D03*
Y1396583D03*
Y1408495D03*
X536082Y1348187D03*
X523842D03*
X536082Y1360099D03*
X523842D03*
Y1384297D03*
Y1372385D03*
X536082Y1384297D03*
Y1372385D03*
Y1396583D03*
X523842D03*
X536082Y1408495D03*
X523842D03*
X548322Y1348187D03*
Y1360099D03*
Y1384297D03*
Y1372385D03*
Y1396583D03*
Y1408495D03*
X560562Y1348187D03*
Y1360099D03*
Y1384297D03*
Y1372385D03*
Y1396583D03*
Y1408495D03*
X600295Y1084547D03*
Y1092027D03*
X604035Y1077066D03*
Y1084547D03*
Y1092027D03*
X600295Y1095767D03*
X604035D03*
X600295Y1110728D03*
Y1118208D03*
X604035Y1110728D03*
Y1118208D03*
X604036Y1166830D03*
X611516Y1073326D03*
X618996D03*
Y1088287D03*
Y1092027D03*
X611516Y1077066D03*
X615256Y1080807D03*
X607776D03*
X615256Y1084547D03*
X607776D03*
X615256Y1088287D03*
X611516D03*
X607776D03*
X611516Y1092027D03*
X618996Y1077066D03*
X611516Y1106988D03*
X607776D03*
X611516Y1095767D03*
X615256Y1099507D03*
X607776D03*
X615256Y1103247D03*
X607776D03*
X618996Y1095767D03*
X615256Y1110728D03*
Y1114468D03*
X611516D03*
X607776D03*
X615256Y1129429D03*
X617126Y1213582D03*
X620866D03*
X620083Y1728286D03*
Y1738286D03*
X619711Y1775438D03*
Y1785438D03*
X626476Y1088287D03*
X622736Y1080807D03*
Y1084547D03*
Y1088287D03*
Y1099507D03*
Y1103247D03*
Y1166830D03*
Y1170570D03*
Y1174310D03*
Y1178050D03*
X636288Y1372385D03*
Y1384297D03*
Y1396583D03*
X624048D03*
X636288Y1408495D03*
X624048D03*
X648528Y1348187D03*
Y1360099D03*
Y1372385D03*
Y1384297D03*
Y1396583D03*
Y1408495D03*
X660768Y1348187D03*
Y1360099D03*
Y1372385D03*
Y1384297D03*
Y1396583D03*
Y1408495D03*
X671358Y1114468D03*
X673008Y1348187D03*
X685248D03*
X673008Y1360099D03*
X685248D03*
Y1372385D03*
Y1384297D03*
X673008Y1372385D03*
Y1384297D03*
X685248Y1396583D03*
X673008D03*
X685248Y1408495D03*
X673008D03*
X695669Y1078936D03*
X699409Y1082677D03*
X695669Y1097637D03*
X699409Y1247243D03*
Y1243503D03*
X691929Y1247243D03*
X695669Y1250984D03*
Y1254724D03*
X697488Y1348187D03*
Y1360099D03*
Y1384297D03*
Y1372385D03*
Y1396583D03*
Y1408495D03*
X706890Y1082677D03*
X714370D03*
X706890Y1101377D03*
X703149Y1254724D03*
Y1250984D03*
X718110D03*
Y1239763D03*
X714370Y1247243D03*
X710630Y1254724D03*
Y1250984D03*
Y1239763D03*
X706890Y1247243D03*
Y1239763D03*
X718110Y1254724D03*
X709728Y1348187D03*
Y1360099D03*
Y1384297D03*
Y1372385D03*
Y1396583D03*
Y1408495D03*
X721850Y1082677D03*
X733071Y1078936D03*
Y1097637D03*
X731201Y1121948D03*
X734941Y1125688D03*
Y1133169D03*
X731201Y1204232D03*
X729331Y1243503D03*
X721850D03*
X729331Y1239763D03*
Y1247243D03*
X733071Y1250984D03*
Y1254724D03*
X725590D03*
Y1250984D03*
X721850Y1247243D03*
X734208Y1348187D03*
X721968D03*
X734208Y1360099D03*
X721968D03*
Y1384297D03*
Y1372385D03*
X734208D03*
Y1384297D03*
X721968Y1396489D03*
X734208D03*
X721968Y1408401D03*
X734208D03*
X744291Y1082677D03*
X748031Y1078936D03*
X736811Y1086417D03*
Y1082677D03*
X748031Y1097637D03*
X740551Y1093897D03*
X736811Y1243503D03*
Y1247243D03*
X744291Y1243503D03*
Y1239763D03*
X748031Y1254724D03*
Y1250984D03*
X744291Y1247243D03*
X740551Y1254724D03*
Y1250984D03*
X746448Y1348187D03*
Y1360099D03*
Y1372385D03*
Y1384297D03*
X759251Y1082677D03*
X751772Y1086417D03*
X751771Y1090157D03*
Y1082677D03*
X759252Y1086417D03*
X766732D03*
X766731Y1082677D03*
X762992Y1097637D03*
X755512D03*
X757382Y1155610D03*
X755512Y1250984D03*
Y1254724D03*
X759252Y1247243D03*
Y1243503D03*
X762992Y1250984D03*
Y1254724D03*
X766732Y1247243D03*
Y1243503D03*
X759252Y1239763D03*
X751772Y1247243D03*
Y1243503D03*
X758688Y1348187D03*
Y1360099D03*
Y1372385D03*
Y1384297D03*
X774213Y1086417D03*
X774212Y1082677D03*
X781693Y1086417D03*
X777953D03*
X770472Y1097637D03*
X777953Y1093897D03*
Y1105117D03*
X781693Y1093897D03*
Y1097637D03*
X777953D03*
X781693Y1105117D03*
Y1112598D03*
X777953Y1120078D03*
X781693D03*
X774212Y1108858D03*
X777953Y1112598D03*
X783563Y1140649D03*
X779823D03*
X781693Y1127558D03*
X777953D03*
Y1135039D03*
X781693D03*
X783563Y1155610D03*
Y1148129D03*
X779823Y1155610D03*
Y1148129D03*
X783563Y1170570D03*
Y1185531D03*
Y1178051D03*
X770472Y1250984D03*
Y1254724D03*
X777953Y1250984D03*
X774212Y1247243D03*
Y1243503D03*
Y1239763D03*
X777953Y1254724D03*
X770928Y1348187D03*
Y1360099D03*
X907279Y1738990D03*
Y1728990D03*
X907073Y1776014D03*
Y1786014D03*
X1057381Y1092027D03*
Y1084547D03*
Y1095767D03*
Y1118208D03*
Y1110728D03*
X1068602Y1073326D03*
X1072342Y1088287D03*
Y1084547D03*
Y1080807D03*
X1061121Y1092027D03*
X1068602D03*
X1064862Y1088287D03*
X1068602D03*
X1061121Y1084547D03*
X1064862D03*
Y1080807D03*
X1061121Y1077066D03*
X1068602D03*
X1072342Y1099507D03*
Y1103247D03*
X1061121Y1095767D03*
X1068602D03*
X1064862Y1106988D03*
X1068602D03*
X1064862Y1103247D03*
Y1099507D03*
X1072342Y1114468D03*
Y1110728D03*
X1061121Y1118208D03*
X1064862Y1114468D03*
X1068602D03*
X1061121Y1110728D03*
X1072342Y1129429D03*
X1061122Y1166830D03*
X1074212Y1213582D03*
X1076082Y1073326D03*
X1083562Y1088287D03*
X1079822D03*
Y1084547D03*
Y1080807D03*
X1076082Y1092027D03*
Y1088287D03*
Y1077066D03*
X1079822Y1103247D03*
Y1099507D03*
X1076082Y1095767D03*
X1079822Y1170570D03*
Y1166830D03*
Y1174310D03*
Y1178050D03*
X1077952Y1213582D03*
X1128444Y1114468D03*
X1152755Y1078936D03*
X1156495Y1082677D03*
X1152755Y1097637D03*
Y1254724D03*
Y1250984D03*
X1149015Y1247243D03*
X1156495Y1243503D03*
Y1247243D03*
X1163976Y1082677D03*
X1171456D03*
X1163976Y1101377D03*
Y1239763D03*
Y1247243D03*
X1167716Y1239763D03*
Y1250984D03*
Y1254724D03*
X1171456Y1247243D03*
X1160235Y1250984D03*
Y1254724D03*
X1178936Y1082677D03*
X1188287Y1121948D03*
Y1204232D03*
X1175196Y1254724D03*
Y1239763D03*
Y1250984D03*
X1178936Y1247243D03*
X1182676Y1250984D03*
Y1254724D03*
X1186417Y1247243D03*
Y1239763D03*
X1178936Y1243503D03*
X1186417D03*
X1190157Y1078936D03*
X1201377Y1082677D03*
X1205117Y1078936D03*
X1193897Y1082677D03*
Y1086417D03*
X1190157Y1097637D03*
X1197637Y1093897D03*
X1205117Y1097637D03*
X1192027Y1133169D03*
Y1125688D03*
X1190157Y1254724D03*
Y1250984D03*
X1197637D03*
Y1254724D03*
X1201377Y1247243D03*
X1205117Y1250984D03*
Y1254724D03*
X1201377Y1239763D03*
Y1243503D03*
X1193897Y1247243D03*
Y1243503D03*
X1216337Y1082677D03*
X1216338Y1086417D03*
X1208857Y1082677D03*
X1208858Y1086417D03*
X1208857Y1090157D03*
X1212598Y1097637D03*
X1220078D03*
X1214468Y1155610D03*
X1212598Y1250984D03*
Y1254724D03*
X1216338Y1247243D03*
Y1243503D03*
X1220078Y1250984D03*
Y1254724D03*
X1216338Y1239763D03*
X1208858Y1247243D03*
Y1243503D03*
X1223817Y1082677D03*
X1223818Y1086417D03*
X1231298Y1082677D03*
X1235039Y1086417D03*
X1231299D03*
X1227558Y1097637D03*
X1235039Y1093897D03*
Y1097637D03*
Y1105117D03*
X1231298Y1108858D03*
X1235039Y1112598D03*
Y1120078D03*
X1236909Y1140649D03*
X1235039Y1127558D03*
Y1135039D03*
X1236909Y1148129D03*
Y1155610D03*
X1223818Y1247243D03*
Y1243503D03*
X1227558Y1250984D03*
Y1254724D03*
X1235039Y1250984D03*
X1231298Y1247243D03*
Y1243503D03*
Y1239763D03*
X1235039Y1254724D03*
X1238779Y1086417D03*
Y1093897D03*
Y1097637D03*
Y1105117D03*
Y1112598D03*
Y1120078D03*
X1240649Y1140649D03*
X1238779Y1127558D03*
Y1135039D03*
X1240649Y1148129D03*
Y1155610D03*
Y1170570D03*
Y1178051D03*
Y1185531D03*
X1514468Y1084547D03*
Y1092027D03*
Y1095767D03*
Y1110728D03*
Y1118208D03*
X1525689Y1073326D03*
Y1077066D03*
X1518208D03*
X1529429Y1080807D03*
X1521949D03*
X1529429Y1084547D03*
X1521949D03*
X1518208D03*
X1529429Y1088287D03*
X1525689D03*
X1521949D03*
X1525689Y1092027D03*
X1518208D03*
X1521949Y1103247D03*
X1525689Y1106988D03*
X1521949D03*
X1525689Y1095767D03*
X1518208D03*
X1529429Y1099507D03*
X1521949D03*
X1529429Y1103247D03*
Y1110728D03*
X1518208D03*
X1529429Y1114468D03*
X1525689D03*
X1521949D03*
X1518208Y1118208D03*
X1529429Y1129429D03*
X1518209Y1166830D03*
X1533169Y1073326D03*
X1540649Y1088287D03*
X1533169Y1077066D03*
X1536909Y1080807D03*
Y1084547D03*
Y1088287D03*
X1533169D03*
Y1092027D03*
Y1095767D03*
X1536909Y1099507D03*
Y1103247D03*
Y1166830D03*
Y1170570D03*
Y1174310D03*
X1535039Y1176180D03*
Y1213582D03*
X1531299D03*
X1585531Y1114468D03*
X1609842Y1078936D03*
Y1097637D03*
Y1254724D03*
Y1250984D03*
X1606102Y1247243D03*
X1613582Y1082677D03*
X1621063D03*
Y1101377D03*
X1613582Y1243503D03*
Y1247243D03*
X1621063Y1239763D03*
Y1247243D03*
X1624803Y1239763D03*
Y1250984D03*
Y1254724D03*
X1617322Y1250984D03*
Y1254724D03*
X1636023Y1082677D03*
X1628543D03*
X1632283Y1254724D03*
X1628543Y1247243D03*
X1632283Y1239763D03*
Y1250984D03*
X1636023Y1247243D03*
X1639763Y1250984D03*
Y1254724D03*
X1643504Y1247243D03*
Y1239763D03*
X1636023Y1243503D03*
X1643504D03*
X1658464Y1082677D03*
X1650984D03*
Y1086417D03*
X1647244Y1078936D03*
Y1097637D03*
X1654724Y1093897D03*
X1645374Y1121948D03*
X1649114Y1133169D03*
Y1125688D03*
X1645374Y1204232D03*
X1647244Y1254724D03*
Y1250984D03*
X1654724D03*
Y1254724D03*
X1658464Y1247243D03*
Y1239763D03*
Y1243503D03*
X1650984Y1247243D03*
Y1243503D03*
X1662204Y1078936D03*
X1673424Y1082677D03*
X1673425Y1086417D03*
X1665944Y1082677D03*
X1665945Y1086417D03*
X1665944Y1090157D03*
X1662204Y1097637D03*
X1669685D03*
X1671555Y1155610D03*
X1665945Y1247243D03*
Y1243503D03*
X1662204Y1250984D03*
Y1254724D03*
X1669685Y1250984D03*
Y1254724D03*
X1673425Y1247243D03*
Y1243503D03*
Y1239763D03*
X1680904Y1082677D03*
X1680905Y1086417D03*
X1688385Y1082677D03*
X1692126Y1086417D03*
X1688386D03*
X1677165Y1097637D03*
X1684645D03*
X1692126Y1093897D03*
Y1097637D03*
Y1105117D03*
X1688385Y1108858D03*
X1692126Y1112598D03*
Y1120078D03*
Y1127558D03*
Y1135039D03*
X1684645Y1250984D03*
Y1254724D03*
X1692126Y1250984D03*
X1688385Y1247243D03*
Y1243503D03*
Y1239763D03*
X1692126Y1254724D03*
X1677165Y1250984D03*
Y1254724D03*
X1680905Y1247243D03*
Y1243503D03*
X1695866Y1086417D03*
Y1093897D03*
Y1097637D03*
Y1105117D03*
Y1112598D03*
Y1120078D03*
X1697736Y1140649D03*
X1693996D03*
X1695866Y1127558D03*
Y1135039D03*
X1697736Y1148129D03*
X1693996D03*
X1697736Y1155610D03*
X1693996D03*
X1697736Y1170570D03*
Y1178051D03*
Y1185531D03*
G54D36*
X145078Y1228543D03*
X148818D03*
X145078Y1250984D03*
X148818Y1243503D03*
Y1250984D03*
X145078Y1243503D03*
X161909Y1125688D03*
X158169Y1151869D03*
X154429D03*
Y1166830D03*
X160039Y1194881D03*
Y1202362D03*
Y1209842D03*
Y1217322D03*
Y1236023D03*
Y1232283D03*
X152559Y1236023D03*
Y1232283D03*
X156299Y1250984D03*
X160039Y1247243D03*
X152559D03*
X156299Y1239763D03*
X163779Y1250984D03*
X156299Y1254724D03*
X163779D03*
X178740Y1075196D03*
X171259D03*
X174999D03*
X182480D03*
X178740Y1078936D03*
X174999Y1086417D03*
Y1082677D03*
X171259Y1078936D03*
X182480Y1086417D03*
Y1082677D03*
X174999Y1078936D03*
X182480D03*
X178740Y1082677D03*
Y1086417D03*
X174999Y1093897D03*
X182480D03*
X171259Y1097637D03*
X182480D03*
X174999D03*
X178740Y1101376D03*
Y1105117D03*
X173129Y1129428D03*
X169389D03*
X180610Y1170570D03*
X174999Y1209842D03*
X167519Y1221062D03*
X182480Y1236023D03*
Y1232283D03*
X174999D03*
Y1236023D03*
X167519Y1232283D03*
Y1236023D03*
X182480Y1239763D03*
Y1247243D03*
X178740Y1250984D03*
Y1239763D03*
X174999Y1243503D03*
X178740Y1254724D03*
X171259D03*
X167519Y1247243D03*
X186220Y1075196D03*
X193700D03*
X189960D03*
X197440D03*
X189960Y1086417D03*
Y1082677D03*
X193700Y1078936D03*
X186220D03*
X197440Y1086417D03*
Y1082677D03*
X186220D03*
Y1086417D03*
X189960Y1078936D03*
X193700Y1086417D03*
Y1082677D03*
X197440Y1078936D03*
X193700Y1105117D03*
X197440Y1093897D03*
X189960Y1097637D03*
X186220Y1105117D03*
X197440Y1097637D03*
X193700Y1101376D03*
X186220D03*
X188090Y1178051D03*
Y1193011D03*
X197440Y1236023D03*
Y1232283D03*
X189960Y1236023D03*
Y1232283D03*
X197440Y1247243D03*
X193700Y1254724D03*
X186220D03*
X189960Y1239763D03*
X186220Y1250984D03*
X189960Y1247243D03*
X193700Y1250984D03*
X201181Y1075196D03*
X208661D03*
X204921D03*
X212401D03*
X208661Y1078936D03*
X212401Y1086417D03*
Y1082677D03*
X204921Y1086417D03*
Y1082677D03*
X201181Y1078936D03*
X212401D03*
X208661Y1082677D03*
X201181D03*
Y1086417D03*
X208661D03*
X204921Y1078936D03*
Y1097637D03*
X208661Y1101376D03*
X212401Y1097637D03*
X208661Y1105117D03*
X212401Y1093897D03*
X201181Y1101376D03*
X204921Y1093897D03*
X201181Y1105117D03*
X204921Y1232283D03*
X212401D03*
Y1236023D03*
X204921D03*
X208661Y1250984D03*
X201181Y1239763D03*
X212401D03*
Y1247243D03*
X201181Y1254724D03*
X204921Y1239763D03*
X201181Y1250984D03*
X204921Y1247243D03*
X208661Y1254724D03*
X213969Y1445013D03*
Y1456013D03*
X223622Y1075196D03*
X231102D03*
X216141D03*
X227362D03*
X219881D03*
X227362Y1086417D03*
Y1082677D03*
X219881Y1086417D03*
Y1082677D03*
X223622Y1078936D03*
X231102D03*
X216141D03*
X219881D03*
X216141Y1086417D03*
X231102Y1082677D03*
Y1086417D03*
X223622Y1082677D03*
X227362Y1078936D03*
X216141Y1082677D03*
X223622Y1086417D03*
X216141Y1101376D03*
X231102D03*
X227362Y1093897D03*
X219881Y1097637D03*
X223621Y1101376D03*
Y1105117D03*
X216141D03*
X219881Y1093897D03*
X227362Y1097637D03*
X231102Y1105117D03*
Y1228543D03*
X219881Y1232283D03*
Y1236023D03*
X227362Y1232283D03*
Y1236023D03*
X223622Y1254724D03*
X231102D03*
X227362Y1247243D03*
X219881Y1239763D03*
X223622Y1250984D03*
X219881Y1247243D03*
X231102Y1250984D03*
X227362Y1239763D03*
X216141Y1250984D03*
Y1254724D03*
X227249Y1445013D03*
Y1456013D03*
X234841Y1093897D03*
X246062Y1105117D03*
X242321Y1097637D03*
X234841D03*
X238582Y1101376D03*
X246062D03*
X238582Y1105117D03*
X242321Y1093897D03*
X246062Y1221062D03*
X238582Y1224803D03*
Y1228543D03*
X242322Y1236023D03*
Y1232283D03*
X246062Y1228543D03*
X234842Y1232283D03*
X246062Y1224803D03*
X234842Y1236023D03*
Y1239763D03*
Y1243503D03*
X242322Y1239763D03*
X257283Y1101377D03*
X253543Y1105117D03*
Y1101376D03*
X261023Y1105117D03*
Y1101376D03*
X249803Y1221062D03*
X253543D03*
X261023D03*
X257283D03*
X261023Y1224803D03*
X253543Y1228543D03*
X249803Y1232283D03*
X257283D03*
Y1236023D03*
X261023Y1228543D03*
X253543Y1224803D03*
X249803Y1236023D03*
Y1243503D03*
X257283D03*
X272244Y1101377D03*
X279724D03*
X264763D03*
X264762Y1097637D03*
X268503Y1105117D03*
X272243Y1097637D03*
X275984Y1105117D03*
X279723Y1093897D03*
X272243D03*
X279723Y1097637D03*
X268503Y1101376D03*
X275984D03*
X264762Y1093897D03*
X277854Y1121948D03*
Y1129429D03*
X264763Y1221062D03*
Y1232283D03*
X268503Y1224803D03*
X275984D03*
X272244Y1236023D03*
X279724Y1232283D03*
Y1236023D03*
X275984Y1228543D03*
X272244Y1232283D03*
X268503Y1228543D03*
X264763Y1236023D03*
X279724Y1239763D03*
X275984D03*
X264763D03*
X287204Y1086417D03*
X283464Y1097637D03*
X294684Y1101377D03*
X283464Y1101376D03*
X294684Y1093897D03*
X287203D03*
X294684Y1097637D03*
X283464Y1105117D03*
X290944Y1101376D03*
Y1105117D03*
X287203Y1097637D03*
X294684Y1123818D03*
Y1116338D03*
Y1131299D03*
X289074Y1144389D03*
X294685Y1198621D03*
Y1213582D03*
Y1206102D03*
X287204Y1232283D03*
X283464Y1224803D03*
Y1228543D03*
X287204Y1236023D03*
X294685D03*
X290944Y1224803D03*
X294685Y1232283D03*
X290944Y1228543D03*
X294685Y1239763D03*
X302164Y1090157D03*
X305904D03*
X309644D03*
X302165Y1101377D03*
X309645D03*
X298425Y1105117D03*
Y1101376D03*
X309644Y1097637D03*
X302164D03*
X305905Y1105117D03*
X309644Y1093897D03*
X305905Y1101376D03*
X302164Y1093897D03*
X309645Y1123818D03*
X309644Y1108858D03*
X309645Y1116338D03*
X302165Y1120078D03*
X305905Y1112598D03*
X298425Y1116338D03*
X305905Y1120078D03*
X302165Y1112598D03*
X298425Y1123818D03*
X309645Y1131299D03*
X307775Y1140649D03*
X298425Y1135039D03*
Y1127558D03*
X305905Y1127559D03*
Y1135039D03*
X302165D03*
Y1127559D03*
X298425Y1131299D03*
X300295Y1151869D03*
Y1144389D03*
X307775Y1148129D03*
Y1155610D03*
Y1159350D03*
X298425Y1198621D03*
X305905Y1202362D03*
X302165D03*
X298425Y1213582D03*
X305905Y1209842D03*
Y1217322D03*
X302165Y1209842D03*
X298425Y1206102D03*
X302165Y1217322D03*
Y1232283D03*
X309645D03*
X298425Y1224803D03*
Y1228543D03*
X309645Y1236023D03*
X305905Y1228543D03*
Y1224803D03*
X302165Y1236023D03*
X305905Y1239763D03*
X317125Y1090157D03*
X320866D03*
X324606D03*
X317126Y1105117D03*
X317125Y1101377D03*
X313385D03*
X317125Y1093897D03*
X320866Y1101377D03*
X324606D03*
X317125Y1097637D03*
X318996Y1136909D03*
X317125Y1131299D03*
X318996Y1144389D03*
Y1151869D03*
X322736Y1166830D03*
X318996Y1159350D03*
Y1166830D03*
X326476D03*
X318996Y1189271D03*
Y1181791D03*
Y1174310D03*
X317125Y1198621D03*
X320866D03*
X313385Y1202362D03*
X324606Y1198621D03*
X317125Y1202362D03*
Y1206102D03*
Y1213582D03*
Y1217322D03*
Y1209842D03*
X324606Y1213582D03*
X313385Y1209842D03*
X320866Y1213582D03*
X324606Y1206102D03*
X313385Y1217322D03*
X317125Y1236023D03*
X313385Y1224803D03*
X324606Y1228543D03*
X317125Y1232283D03*
X313385Y1228543D03*
X320866D03*
Y1243503D03*
X313385Y1239763D03*
X320866Y1247243D03*
X324606D03*
X602165Y1228543D03*
Y1243503D03*
Y1250984D03*
X618996Y1125688D03*
Y1133169D03*
X615256Y1151869D03*
X611516D03*
Y1166830D03*
X617126Y1202362D03*
Y1194881D03*
Y1209842D03*
Y1217322D03*
X605905Y1228543D03*
X609646Y1232283D03*
X617126Y1236023D03*
Y1232283D03*
X609646Y1236023D03*
X613386Y1239763D03*
X620866Y1254724D03*
Y1250984D03*
X617126Y1247243D03*
X609646D03*
X613386Y1254724D03*
Y1250984D03*
X605905Y1243503D03*
Y1254724D03*
Y1250984D03*
X626476Y1073326D03*
X635827Y1075196D03*
X628346D03*
X632086D03*
X626476Y1077066D03*
X628346Y1078936D03*
X635827D03*
X632086Y1082677D03*
Y1086417D03*
Y1078936D03*
X635827Y1086417D03*
Y1082677D03*
X632086Y1097637D03*
X626476Y1099507D03*
X628346Y1097637D03*
X635827Y1105117D03*
X632086Y1093897D03*
X635827Y1101376D03*
X630216Y1129428D03*
X626476D03*
X630216Y1136909D03*
X626476D03*
X632086Y1209842D03*
X624606Y1221062D03*
X632086Y1232283D03*
Y1236023D03*
X624606Y1232283D03*
Y1236023D03*
X632086Y1243503D03*
X635827Y1239763D03*
Y1254724D03*
Y1250984D03*
X628346Y1254724D03*
X624606Y1247243D03*
X643307Y1075196D03*
X650787D03*
X639567D03*
X647047D03*
X650787Y1078936D03*
X647047Y1082677D03*
Y1086417D03*
X643307Y1078936D03*
X639567Y1086417D03*
Y1082677D03*
X643307Y1086417D03*
Y1082677D03*
X647047Y1078936D03*
X639567D03*
X650787Y1082677D03*
Y1086417D03*
Y1105117D03*
X639567Y1097637D03*
X643307Y1105117D03*
X647047Y1097637D03*
X639567Y1093897D03*
X643307Y1101376D03*
X650787D03*
X637697Y1170570D03*
X645177Y1178051D03*
Y1193011D03*
X639567Y1236023D03*
X647047D03*
X639567Y1232283D03*
X647047D03*
X639567Y1239763D03*
Y1247243D03*
X647047Y1239763D03*
X650787Y1254724D03*
Y1250984D03*
X647047Y1247243D03*
X643307Y1254724D03*
Y1250984D03*
X658268Y1075196D03*
X665748D03*
X662008D03*
X654527D03*
X669488D03*
Y1086417D03*
X665748Y1078936D03*
X669488Y1082677D03*
X654527D03*
Y1086417D03*
X662008Y1082677D03*
Y1086417D03*
X658268Y1078936D03*
X662008D03*
X665748Y1082677D03*
X658268D03*
X654527Y1078936D03*
X665748Y1086417D03*
X658268D03*
X669488Y1078936D03*
X662008Y1097637D03*
X654527Y1093897D03*
X669488D03*
X665748Y1105117D03*
X654527Y1097637D03*
X662008Y1093897D03*
X669488Y1097637D03*
X665748Y1101376D03*
X658268Y1105117D03*
Y1101376D03*
X669488Y1232283D03*
X654527Y1236023D03*
X662008Y1232283D03*
Y1236023D03*
X669488D03*
X654527Y1232283D03*
Y1247243D03*
X662008Y1239763D03*
X658268D03*
X669488D03*
X665748Y1250984D03*
Y1254724D03*
X669488Y1247243D03*
X662008D03*
X658268Y1254724D03*
Y1250984D03*
X680709Y1075196D03*
X673228D03*
X676968D03*
X684449D03*
Y1082677D03*
Y1086417D03*
X673228Y1078936D03*
X680709D03*
X676968Y1082677D03*
Y1086417D03*
Y1078936D03*
X680709Y1086417D03*
X684449Y1078936D03*
X673228Y1086417D03*
Y1082677D03*
X680709D03*
X673228Y1105117D03*
X684449Y1093897D03*
X676968D03*
X684449Y1097637D03*
X676968D03*
X680708Y1105117D03*
X673228Y1101376D03*
X680708D03*
X676968Y1236023D03*
X684449Y1232283D03*
Y1236023D03*
X676968Y1232283D03*
Y1239763D03*
X680709Y1254724D03*
Y1250984D03*
X676968Y1247243D03*
X673228Y1254724D03*
Y1250984D03*
X684449Y1247243D03*
Y1239763D03*
X688189Y1075196D03*
Y1078936D03*
Y1086417D03*
Y1082677D03*
Y1105117D03*
X695669Y1101376D03*
X699408Y1097637D03*
X695669Y1105117D03*
X691928Y1093897D03*
Y1097637D03*
X699408Y1093897D03*
X688189Y1101376D03*
Y1228543D03*
X691929Y1236023D03*
X699409Y1232283D03*
Y1236023D03*
X691929Y1232283D03*
X695669Y1228543D03*
Y1224803D03*
X688189Y1254724D03*
Y1250984D03*
X699409Y1239763D03*
X691929D03*
Y1243503D03*
X714370Y1101377D03*
X703149Y1105117D03*
X718110D03*
Y1101376D03*
X710630Y1105117D03*
X703149Y1101376D03*
X710630D03*
X706890Y1236023D03*
X718110Y1228543D03*
X714370Y1236023D03*
X710630Y1228543D03*
X703149D03*
X714370Y1232283D03*
X703149Y1224803D03*
X718110D03*
X710630D03*
X706890Y1232283D03*
X714370Y1243503D03*
X706890D03*
X729331Y1101377D03*
X721850D03*
X725590Y1101376D03*
X733071Y1105117D03*
X725590D03*
X721849Y1097637D03*
Y1093897D03*
X729330Y1097637D03*
X733071Y1101376D03*
X729330Y1093897D03*
X734941Y1121948D03*
Y1129429D03*
X725590Y1228543D03*
X733071D03*
X721850Y1236023D03*
X733071Y1224803D03*
X721850Y1232283D03*
X725590Y1224803D03*
X729331Y1236023D03*
Y1232283D03*
X733071Y1239763D03*
X721850D03*
X744291Y1086417D03*
X740551Y1097637D03*
X736811Y1101377D03*
X736810Y1097637D03*
X748031Y1105117D03*
X744290Y1093897D03*
X740551Y1105117D03*
X744290Y1097637D03*
X736810Y1093897D03*
X740551Y1101376D03*
X748031D03*
X746161Y1144389D03*
X744291Y1236023D03*
X736811Y1232283D03*
X744291D03*
X736811Y1236023D03*
X740551Y1224803D03*
Y1228543D03*
X748031Y1224803D03*
Y1228543D03*
X736811Y1239763D03*
X766731Y1090157D03*
X759251D03*
X762991D03*
X751771Y1101377D03*
X759252D03*
X766732D03*
X751771Y1097637D03*
X762992Y1101376D03*
Y1105117D03*
X755512D03*
X759251Y1097637D03*
Y1093897D03*
X766731Y1097637D03*
X755512Y1101376D03*
X766731Y1093897D03*
X751771D03*
X766731Y1108858D03*
X766732Y1116338D03*
Y1123818D03*
X755512D03*
X759252Y1112598D03*
X751771Y1123818D03*
X762992Y1112598D03*
X755512Y1116338D03*
X751771D03*
X759252Y1120078D03*
X762992D03*
X764862Y1140649D03*
X766732Y1131299D03*
X755512Y1127558D03*
Y1135039D03*
X751771Y1131299D03*
X762992Y1135039D03*
X755512Y1131299D03*
X762992Y1127559D03*
X759252Y1135039D03*
Y1127559D03*
X764862Y1155610D03*
Y1148129D03*
X757382Y1144389D03*
Y1151869D03*
X764862Y1159350D03*
X762992Y1202362D03*
X755512Y1198621D03*
X759252Y1202362D03*
X751772Y1198621D03*
X762992Y1217322D03*
X751772Y1213582D03*
X762992Y1209842D03*
X755512Y1213582D03*
X751772Y1206102D03*
X759252Y1217322D03*
Y1209842D03*
X755512Y1206102D03*
Y1228543D03*
X751772Y1236023D03*
X762992Y1228543D03*
X751772Y1232283D03*
X766732D03*
Y1236023D03*
X759252Y1232283D03*
X762992Y1224803D03*
X759252Y1236023D03*
X755512Y1224803D03*
X762992Y1239763D03*
X751772D03*
X774212Y1090157D03*
X781693D03*
X777953D03*
X774212Y1101377D03*
X774213Y1105117D03*
X770472Y1101377D03*
X781693D03*
X777953D03*
X774212Y1097637D03*
Y1093897D03*
Y1131299D03*
X776083Y1151869D03*
Y1144389D03*
X783563Y1166830D03*
X776083D03*
Y1159350D03*
X779823Y1166830D03*
X776083Y1174310D03*
Y1181791D03*
Y1196751D03*
X774212Y1198621D03*
Y1213582D03*
Y1206102D03*
X770472Y1228543D03*
X781693D03*
X770472Y1224803D03*
X777953Y1228543D03*
X774212Y1232283D03*
Y1236023D03*
X777953Y1243503D03*
X770472Y1239763D03*
X1059251Y1228543D03*
Y1243503D03*
Y1250984D03*
X1072342Y1151869D03*
X1068602D03*
Y1166830D03*
X1074212Y1194881D03*
Y1202362D03*
Y1217322D03*
Y1209842D03*
X1066732Y1236023D03*
Y1232283D03*
X1074212Y1236023D03*
Y1232283D03*
X1062991Y1228543D03*
X1070472Y1250984D03*
Y1254724D03*
X1066732Y1247243D03*
X1074212D03*
X1070472Y1239763D03*
X1062991Y1250984D03*
Y1254724D03*
Y1243503D03*
X1083562Y1073326D03*
X1089172Y1075196D03*
X1083562Y1077066D03*
X1089172Y1082677D03*
Y1086417D03*
Y1078936D03*
Y1097637D03*
Y1093897D03*
X1083562Y1099507D03*
Y1136909D03*
X1087302D03*
X1083562Y1129428D03*
X1087302D03*
X1076082Y1133169D03*
Y1125688D03*
X1089172Y1209842D03*
X1081692Y1221062D03*
X1089172Y1232283D03*
X1081692D03*
Y1236023D03*
X1089172D03*
X1077952Y1250984D03*
Y1254724D03*
X1081692Y1247243D03*
X1085432Y1254724D03*
X1089172Y1243503D03*
X1092913Y1075196D03*
X1107873D03*
X1100393D03*
X1096653D03*
X1104133D03*
X1092913Y1078936D03*
X1104133Y1086417D03*
Y1082677D03*
X1107873Y1078936D03*
X1100393D03*
X1096653Y1082677D03*
Y1086417D03*
X1100393Y1082677D03*
X1104133Y1078936D03*
X1107873Y1082677D03*
Y1086417D03*
X1092913Y1082677D03*
X1100393Y1086417D03*
X1092913D03*
X1096653Y1078936D03*
X1092913Y1105117D03*
X1104133Y1097637D03*
X1096653D03*
X1100393Y1105117D03*
Y1101376D03*
X1096653Y1093897D03*
X1092913Y1101376D03*
X1107873Y1105117D03*
Y1101376D03*
X1094783Y1170570D03*
X1102263Y1178051D03*
Y1193011D03*
X1104133Y1236023D03*
Y1232283D03*
X1096653Y1236023D03*
Y1232283D03*
X1092913Y1250984D03*
Y1254724D03*
Y1239763D03*
X1100393Y1250984D03*
Y1254724D03*
X1104133Y1247243D03*
X1107873Y1250984D03*
Y1254724D03*
X1104133Y1239763D03*
X1096653Y1247243D03*
Y1239763D03*
X1115354Y1075196D03*
X1122834D03*
X1111613D03*
X1119094D03*
X1115354Y1078936D03*
X1119094Y1082677D03*
Y1086417D03*
X1122834Y1078936D03*
X1111613Y1082677D03*
Y1086417D03*
X1122834D03*
X1119094Y1078936D03*
X1115354Y1082677D03*
X1111613Y1078936D03*
X1115354Y1086417D03*
X1122834Y1082677D03*
X1119094Y1097637D03*
X1115354Y1101376D03*
X1111613Y1093897D03*
Y1097637D03*
X1122834Y1105117D03*
X1119094Y1093897D03*
X1122834Y1101376D03*
X1115354Y1105117D03*
X1119094Y1232283D03*
X1111613D03*
X1119094Y1236023D03*
X1111613D03*
X1115354Y1250984D03*
Y1254724D03*
X1119094Y1247243D03*
X1122834Y1254724D03*
Y1250984D03*
X1115354Y1239763D03*
X1119094D03*
X1111613Y1247243D03*
X1130314Y1075196D03*
X1137795D03*
X1126574D03*
X1134054D03*
X1126574Y1086417D03*
Y1082677D03*
X1130314Y1078936D03*
X1134054Y1082677D03*
Y1086417D03*
X1137795Y1078936D03*
X1134054D03*
X1126574D03*
X1130314Y1086417D03*
Y1082677D03*
X1137795Y1086417D03*
Y1082677D03*
X1126574Y1093897D03*
X1130314Y1105117D03*
X1134054Y1093897D03*
X1130314Y1101376D03*
X1134054Y1097637D03*
X1137794Y1105117D03*
X1126574Y1097637D03*
X1137794Y1101376D03*
X1134054Y1236023D03*
Y1232283D03*
X1126574D03*
Y1236023D03*
Y1247243D03*
Y1239763D03*
X1130314Y1250984D03*
Y1254724D03*
X1134054Y1247243D03*
X1137795Y1250984D03*
Y1254724D03*
X1134054Y1239763D03*
X1145275Y1075196D03*
X1141535D03*
Y1082677D03*
Y1086417D03*
X1145275Y1078936D03*
Y1086417D03*
Y1082677D03*
X1141535Y1078936D03*
X1145275Y1105117D03*
X1141535Y1093897D03*
X1145275Y1101376D03*
X1141535Y1097637D03*
X1149014D03*
X1156494Y1093897D03*
X1152755Y1101376D03*
X1156494Y1097637D03*
X1149014Y1093897D03*
X1152755Y1105117D03*
X1149015Y1236023D03*
Y1232283D03*
X1152755Y1228543D03*
X1156495Y1232283D03*
Y1236023D03*
X1141535D03*
X1145275Y1228543D03*
X1152755Y1224803D03*
X1141535Y1232283D03*
Y1239763D03*
Y1247243D03*
X1149015Y1243503D03*
Y1239763D03*
X1156495D03*
X1145275Y1250984D03*
Y1254724D03*
X1171456Y1101377D03*
X1160235Y1105117D03*
Y1101376D03*
X1167716Y1105117D03*
Y1101376D03*
X1160235Y1224803D03*
X1163976Y1232283D03*
X1167716Y1224803D03*
X1160235Y1228543D03*
X1171456Y1232283D03*
X1163976Y1236023D03*
X1171456D03*
X1167716Y1228543D03*
X1163976Y1243503D03*
X1171456D03*
X1178936Y1101377D03*
X1186417D03*
X1178935Y1097637D03*
X1186416Y1093897D03*
X1182676Y1105117D03*
X1175196D03*
X1178935Y1093897D03*
X1182676Y1101376D03*
X1175196D03*
X1186416Y1097637D03*
X1182676Y1228543D03*
X1186417Y1236023D03*
X1178936D03*
X1186417Y1232283D03*
X1175196Y1228543D03*
X1178936Y1232283D03*
X1182676Y1224803D03*
X1175196D03*
X1178936Y1239763D03*
X1201377Y1086417D03*
X1197637Y1097637D03*
X1193897Y1101377D03*
X1201376Y1093897D03*
X1193896Y1097637D03*
X1197637Y1105117D03*
X1205117D03*
X1197637Y1101376D03*
X1205117D03*
X1190157D03*
X1193896Y1093897D03*
X1201376Y1097637D03*
X1190157Y1105117D03*
X1192027Y1121948D03*
Y1129429D03*
X1203247Y1144389D03*
X1197637Y1224803D03*
X1193897Y1236023D03*
X1190157Y1228543D03*
X1201377Y1236023D03*
X1190157Y1224803D03*
X1193897Y1232283D03*
X1197637Y1228543D03*
X1201377Y1232283D03*
X1205117Y1228543D03*
Y1224803D03*
X1190157Y1239763D03*
X1193897D03*
X1216337Y1090157D03*
X1220077D03*
X1216338Y1101377D03*
X1208857D03*
X1220078Y1105117D03*
X1216337Y1093897D03*
X1212598Y1101376D03*
Y1105117D03*
X1208857Y1093897D03*
X1216337Y1097637D03*
X1220078Y1101376D03*
X1208857Y1097637D03*
X1212598Y1123818D03*
X1208857Y1116338D03*
X1212598D03*
X1216338Y1120078D03*
Y1112598D03*
X1208857Y1123818D03*
X1220078Y1112598D03*
Y1120078D03*
X1221948Y1140649D03*
X1212598Y1127558D03*
Y1135039D03*
X1216338Y1127559D03*
Y1135039D03*
X1212598Y1131299D03*
X1208857D03*
X1220078Y1135039D03*
Y1127559D03*
X1221948Y1155610D03*
X1214468Y1151869D03*
Y1144389D03*
X1221948Y1148129D03*
Y1159350D03*
X1212598Y1198621D03*
X1208858D03*
X1216338Y1202362D03*
X1220078D03*
Y1217322D03*
Y1209842D03*
X1212598Y1206102D03*
X1216338Y1217322D03*
X1212598Y1213582D03*
X1208858Y1206102D03*
Y1213582D03*
X1216338Y1209842D03*
X1220078Y1224803D03*
X1212598Y1228543D03*
X1208858Y1232283D03*
X1216338Y1236023D03*
Y1232283D03*
X1212598Y1224803D03*
X1220078Y1228543D03*
X1208858Y1236023D03*
X1220078Y1239763D03*
X1208858D03*
X1223817Y1090157D03*
X1231298D03*
X1235039D03*
X1223818Y1101377D03*
X1231298D03*
X1231299Y1105117D03*
X1227558Y1101377D03*
X1231298Y1093897D03*
X1235039Y1101377D03*
X1223817Y1093897D03*
Y1097637D03*
X1231298D03*
X1223817Y1108858D03*
X1223818Y1116338D03*
Y1123818D03*
X1233169Y1136909D03*
X1223818Y1131299D03*
X1231298D03*
X1233169Y1144389D03*
Y1151869D03*
X1236909Y1166830D03*
X1233169Y1159350D03*
Y1166830D03*
Y1189271D03*
Y1181791D03*
Y1174310D03*
Y1196751D03*
X1231298Y1198621D03*
Y1202362D03*
X1235039Y1198621D03*
X1227558Y1202362D03*
X1231298Y1206102D03*
Y1213582D03*
X1235039D03*
X1231298Y1209842D03*
X1227558D03*
X1231298Y1217322D03*
X1227558D03*
X1231298Y1232283D03*
X1227558Y1228543D03*
Y1224803D03*
X1223818Y1236023D03*
X1231298D03*
X1235039Y1228543D03*
X1223818Y1232283D03*
X1235039Y1243503D03*
X1227558Y1239763D03*
X1235039Y1247243D03*
X1238779Y1090157D03*
Y1101377D03*
X1243149Y1136909D03*
X1240649Y1166830D03*
X1238779Y1198621D03*
Y1206102D03*
Y1213582D03*
Y1228543D03*
Y1247243D03*
X1511968Y1170570D03*
Y1178050D03*
X1529429Y1151869D03*
X1525689D03*
Y1166830D03*
X1516338Y1228543D03*
X1523819Y1232283D03*
X1520078Y1228543D03*
X1523819Y1236023D03*
X1516338Y1243503D03*
Y1250984D03*
X1527559D03*
Y1254724D03*
X1523819Y1247243D03*
X1527559Y1239763D03*
X1520078Y1250984D03*
Y1254724D03*
Y1243503D03*
X1540649Y1073326D03*
X1546259Y1075196D03*
X1540649Y1077066D03*
X1546259Y1082677D03*
Y1086417D03*
Y1078936D03*
X1540649Y1099507D03*
X1546259Y1097637D03*
Y1093897D03*
X1533169Y1125688D03*
X1544389Y1129428D03*
X1540649D03*
X1544389Y1136909D03*
X1533169Y1133169D03*
X1540649Y1136909D03*
X1531299Y1194881D03*
Y1202362D03*
Y1217322D03*
Y1209842D03*
X1546259D03*
X1538779Y1221062D03*
X1546259Y1232283D03*
X1538779Y1236023D03*
X1531299Y1232283D03*
X1546259Y1236023D03*
X1531299D03*
X1538779Y1232283D03*
X1531299Y1247243D03*
X1535039Y1250984D03*
Y1254724D03*
X1538779Y1247243D03*
X1542519Y1254724D03*
X1546259Y1243503D03*
X1557480Y1075196D03*
X1550000D03*
X1553740D03*
X1561220D03*
Y1086417D03*
Y1082677D03*
X1557480Y1078936D03*
X1553740Y1082677D03*
Y1086417D03*
X1550000Y1078936D03*
X1557480Y1082677D03*
X1553740Y1078936D03*
X1561220D03*
X1550000Y1086417D03*
Y1082677D03*
X1557480Y1086417D03*
Y1101376D03*
Y1105117D03*
X1561220Y1097637D03*
X1550000Y1101376D03*
Y1105117D03*
X1553740Y1093897D03*
Y1097637D03*
X1551870Y1170570D03*
X1559350Y1178051D03*
Y1193011D03*
X1553740Y1232283D03*
Y1236023D03*
X1561220D03*
Y1232283D03*
X1550000Y1250984D03*
Y1254724D03*
Y1239763D03*
X1557480Y1250984D03*
Y1254724D03*
X1561220Y1247243D03*
Y1239763D03*
X1553740Y1247243D03*
Y1239763D03*
X1572441Y1075196D03*
X1564960D03*
X1576181D03*
X1568700D03*
X1564960Y1078936D03*
X1572441D03*
X1576181Y1082677D03*
Y1086417D03*
X1568700Y1082677D03*
Y1086417D03*
Y1078936D03*
X1572441Y1086417D03*
X1564960Y1082677D03*
Y1086417D03*
X1572441Y1082677D03*
X1576181Y1078936D03*
X1564960Y1105117D03*
X1576181Y1097637D03*
X1568700D03*
X1576181Y1093897D03*
X1568700D03*
X1572441Y1101376D03*
Y1105117D03*
X1564960Y1101376D03*
X1568700Y1236023D03*
X1576181D03*
Y1232283D03*
X1568700D03*
X1564960Y1250984D03*
Y1254724D03*
X1572441Y1250984D03*
Y1254724D03*
X1576181Y1247243D03*
X1572441Y1239763D03*
X1576181D03*
X1568700Y1247243D03*
X1579921Y1075196D03*
X1587401D03*
X1594882D03*
X1583661D03*
X1591141D03*
X1583661Y1086417D03*
Y1082677D03*
X1579921Y1078936D03*
X1587401D03*
X1591141Y1082677D03*
Y1086417D03*
X1594882Y1078936D03*
Y1082677D03*
X1579921D03*
X1583661Y1078936D03*
X1594882Y1086417D03*
X1587401Y1082677D03*
X1579921Y1086417D03*
X1587401D03*
X1591141Y1078936D03*
X1594881Y1105117D03*
X1591141Y1097637D03*
X1583661Y1093897D03*
X1594881Y1101376D03*
X1583661Y1097637D03*
X1587401Y1105117D03*
X1579921Y1101376D03*
X1591141Y1093897D03*
X1587401Y1101376D03*
X1579921Y1105117D03*
X1591141Y1232283D03*
X1583661Y1236023D03*
Y1232283D03*
X1591141Y1236023D03*
X1583661Y1247243D03*
X1579921Y1254724D03*
Y1250984D03*
X1583661Y1239763D03*
X1587401Y1250984D03*
Y1254724D03*
X1591141Y1247243D03*
X1594882Y1250984D03*
Y1254724D03*
X1591141Y1239763D03*
X1602362Y1075196D03*
X1598622D03*
Y1082677D03*
Y1086417D03*
X1602362Y1078936D03*
Y1082677D03*
Y1086417D03*
X1598622Y1078936D03*
X1606101Y1093897D03*
X1602362Y1101376D03*
X1598622Y1097637D03*
Y1093897D03*
X1602362Y1105117D03*
X1609842Y1101376D03*
Y1105117D03*
X1606101Y1097637D03*
X1598622Y1236023D03*
X1606102D03*
X1609842Y1228543D03*
X1606102Y1232283D03*
X1609842Y1224803D03*
X1602362Y1228543D03*
X1598622Y1232283D03*
Y1239763D03*
Y1247243D03*
X1606102Y1243503D03*
Y1239763D03*
X1602362Y1250984D03*
Y1254724D03*
X1617322Y1105117D03*
Y1101376D03*
X1613581Y1093897D03*
Y1097637D03*
X1624803Y1101376D03*
Y1105117D03*
X1617322Y1228543D03*
X1624803Y1224803D03*
X1617322D03*
X1621063Y1236023D03*
X1613582D03*
X1621063Y1232283D03*
X1624803Y1228543D03*
X1613582Y1232283D03*
Y1239763D03*
X1621063Y1243503D03*
X1639763Y1101376D03*
X1636022Y1093897D03*
X1636023Y1101377D03*
X1643504D03*
X1628543D03*
X1639763Y1105117D03*
X1632283D03*
Y1101376D03*
X1636022Y1097637D03*
X1643503D03*
Y1093897D03*
X1632283Y1228543D03*
X1628543Y1236023D03*
Y1232283D03*
X1639763Y1224803D03*
X1636023Y1236023D03*
X1643504Y1232283D03*
X1632283Y1224803D03*
X1643504Y1236023D03*
X1636023Y1232283D03*
X1639763Y1228543D03*
X1628543Y1243503D03*
X1636023Y1239763D03*
X1658464Y1086417D03*
X1658463Y1097637D03*
X1647244Y1101376D03*
X1654724Y1097637D03*
X1650984Y1101377D03*
X1658463Y1093897D03*
X1654724Y1105117D03*
X1650983Y1093897D03*
X1647244Y1105117D03*
X1654724Y1101376D03*
X1650983Y1097637D03*
X1649114Y1121948D03*
Y1129429D03*
X1660334Y1144389D03*
X1654724Y1228543D03*
X1647244D03*
X1658464Y1232283D03*
X1654724Y1224803D03*
X1658464Y1236023D03*
X1650984D03*
X1647244Y1224803D03*
X1650984Y1232283D03*
X1647244Y1239763D03*
X1650984D03*
X1673424Y1090157D03*
X1665944Y1093897D03*
X1662204Y1105117D03*
X1669685D03*
X1673424Y1097637D03*
X1669685Y1101376D03*
X1673425Y1101377D03*
X1665944D03*
X1673424Y1093897D03*
X1665944Y1097637D03*
X1662204Y1101376D03*
X1673425Y1112598D03*
X1665944Y1123818D03*
X1673425Y1120078D03*
X1669685Y1123818D03*
X1665944Y1116338D03*
X1669685D03*
X1665944Y1131299D03*
X1671555Y1136909D03*
X1669685Y1127558D03*
Y1135039D03*
Y1131299D03*
X1673425Y1127559D03*
Y1135039D03*
X1671555Y1151869D03*
Y1144389D03*
X1673425Y1202362D03*
X1665945Y1198621D03*
X1669685D03*
X1665945Y1206102D03*
X1669685Y1213582D03*
X1673425Y1209842D03*
X1669685Y1206102D03*
X1665945Y1213582D03*
X1673425Y1217322D03*
Y1236023D03*
X1662204Y1228543D03*
X1669685D03*
X1673425Y1232283D03*
X1665945D03*
Y1236023D03*
X1662204Y1224803D03*
X1669685D03*
X1665945Y1239763D03*
X1677164Y1090157D03*
X1680904D03*
X1688385D03*
X1692126D03*
Y1101377D03*
X1684645D03*
X1677165Y1105117D03*
X1680905Y1101377D03*
X1688385D03*
X1688386Y1105117D03*
X1680904Y1097637D03*
X1677165Y1101376D03*
X1688385Y1097637D03*
X1680904Y1093897D03*
X1688385D03*
X1677165Y1120078D03*
Y1112598D03*
X1680904Y1108858D03*
X1680905Y1116338D03*
Y1123818D03*
X1690256Y1136909D03*
X1679035Y1140649D03*
X1680905Y1131299D03*
X1688385D03*
X1677165Y1135039D03*
Y1127559D03*
X1690256Y1144389D03*
X1679035Y1148129D03*
Y1155610D03*
X1690256Y1151869D03*
Y1159350D03*
X1679035D03*
X1690256Y1166830D03*
Y1174310D03*
Y1189271D03*
Y1181791D03*
X1688385Y1198621D03*
X1677165Y1202362D03*
X1688385Y1213582D03*
Y1206102D03*
X1677165Y1209842D03*
Y1217322D03*
Y1228543D03*
X1680905Y1236023D03*
Y1232283D03*
X1692126Y1228543D03*
X1684645Y1224803D03*
Y1228543D03*
X1677165Y1224803D03*
X1688385Y1232283D03*
Y1236023D03*
X1692126Y1243503D03*
X1684645Y1239763D03*
X1677165D03*
X1695866Y1090157D03*
Y1101377D03*
X1700236Y1136909D03*
X1693996Y1166830D03*
X1697736D03*
X1695866Y1228543D03*
G54D46*
X718503Y-38525D03*
X718500Y-33320D03*
Y-30420D03*
X718488Y-36010D03*
X721756Y-38539D03*
X724781Y-37219D03*
X721741Y-36024D03*
X838503Y-77705D03*
X841756Y-77719D03*
X838500Y-72500D03*
X838488Y-75190D03*
X841741Y-75204D03*
X844781Y-76399D03*
X838500Y-69600D03*
X1005256Y-48539D03*
X1002003D03*
X1005241Y-46024D03*
X1001988D03*
X1008281Y-47219D03*
X1002000Y-40834D03*
X1005256Y-38239D03*
X1002003Y-38225D03*
X1002000Y-43334D03*
X1005241Y-35724D03*
X1002000Y-32720D03*
X1001988Y-35710D03*
X1002000Y-30120D03*
X1008281Y-36919D03*
X1075256Y-77419D03*
X1072003Y-77405D03*
X1071988Y-85290D03*
X1075241D03*
X1072000Y-82600D03*
X1072003Y-87805D03*
X1075256D03*
X1072000Y-80100D03*
Y-72000D03*
Y-69400D03*
X1075241Y-74904D03*
X1071988Y-74890D03*
X1078281Y-86399D03*
Y-76099D03*
X1291756Y-48669D03*
X1288503D03*
X1291741Y-46154D03*
X1288488D03*
X1294781Y-47349D03*
X1288500Y-40964D03*
X1291756Y-38369D03*
X1288503Y-38355D03*
X1288500Y-43464D03*
X1291741Y-35854D03*
X1288500Y-32950D03*
X1288488Y-35840D03*
X1288500Y-30350D03*
X1294781Y-37049D03*
X1328500Y-80100D03*
X1331756Y-77419D03*
X1328503Y-77405D03*
X1331756Y-87805D03*
X1328503D03*
X1328500Y-82600D03*
X1331741Y-85290D03*
X1328488D03*
X1334781Y-86499D03*
X1331741Y-74904D03*
X1328500Y-72000D03*
X1328488Y-74890D03*
X1328500Y-69400D03*
X1334781Y-76099D03*
X1576256Y-48799D03*
X1573003D03*
X1576241Y-46284D03*
X1572988D03*
X1579281Y-47479D03*
X1573000Y-41094D03*
X1576256Y-38499D03*
X1573003Y-38485D03*
X1573000Y-43594D03*
X1576241Y-35984D03*
X1573000Y-33080D03*
X1572988Y-35970D03*
X1573000Y-30480D03*
X1579281Y-37179D03*
X1583000Y-80014D03*
X1586256Y-77419D03*
X1583003Y-77405D03*
X1586256Y-87719D03*
X1583003D03*
X1583000Y-82514D03*
X1586241Y-85204D03*
X1582988D03*
X1589281Y-86399D03*
X1586241Y-74904D03*
X1583000Y-72000D03*
X1582988Y-74890D03*
X1583000Y-69400D03*
X1589281Y-76099D03*
G54D25*
X56348Y1727941D03*
Y1737941D03*
X56248Y1750941D03*
X56348Y1773941D03*
X56248Y1760941D03*
X56348Y1783941D03*
X56248Y1806941D03*
Y1796941D03*
X308448Y1737941D03*
Y1727941D03*
Y1750941D03*
Y1760941D03*
Y1773941D03*
Y1783941D03*
X308348Y1796941D03*
Y1806941D03*
X343286Y1738583D03*
Y1728583D03*
X343112Y1751624D03*
X343212Y1774624D03*
X343112Y1761624D03*
X343212Y1784624D03*
Y1797624D03*
Y1807624D03*
X595386Y1728583D03*
Y1738583D03*
X595312Y1751624D03*
Y1774624D03*
Y1761624D03*
Y1784624D03*
Y1807624D03*
Y1797624D03*
X630083Y1738286D03*
Y1728286D03*
X629861Y1751765D03*
X629711Y1775438D03*
X629861Y1761765D03*
X629711Y1785438D03*
X629475Y1798845D03*
Y1808845D03*
X882183Y1728286D03*
Y1738286D03*
X881911Y1751765D03*
X881761Y1775438D03*
X881911Y1761765D03*
X881761Y1785438D03*
X881525Y1798845D03*
Y1808845D03*
X917279Y1738990D03*
Y1728990D03*
X917163Y1752566D03*
Y1762566D03*
X917073Y1786014D03*
Y1776014D03*
X917166Y1800435D03*
Y1810435D03*
X1169329Y1728990D03*
Y1738990D03*
X1169263Y1752566D03*
Y1762566D03*
X1169123Y1776014D03*
Y1786014D03*
X1169216Y1800435D03*
Y1810435D03*
G54D42*
X318448Y1727941D03*
Y1737941D03*
Y1773941D03*
Y1783941D03*
X605312Y1751624D03*
Y1761624D03*
Y1807624D03*
Y1797624D03*
X891911Y1751765D03*
Y1761765D03*
X891525Y1808845D03*
Y1798845D03*
X1179263Y1752566D03*
Y1762566D03*
X1179216Y1800435D03*
Y1810435D03*
G54D34*
X145078Y1198621D03*
Y1191141D03*
X148818D03*
Y1198621D03*
X145078Y1221062D03*
X148818D03*
Y1213582D03*
X145078D03*
Y1206102D03*
X148818D03*
Y1247243D03*
X145078D03*
X156299Y1187401D03*
X152559D03*
X156299Y1202362D03*
Y1194881D03*
X152559Y1202362D03*
Y1194881D03*
X156299Y1217322D03*
Y1209842D03*
X152559D03*
Y1217322D03*
Y1250984D03*
Y1254724D03*
X160039D03*
X156299Y1243503D03*
Y1247243D03*
X163779Y1243503D03*
X160039Y1250984D03*
X163779Y1247243D03*
X167519Y1254724D03*
Y1250984D03*
X178740Y1247243D03*
X182480Y1254724D03*
Y1250984D03*
X171259Y1247243D03*
X174999Y1250984D03*
X171259Y1243503D03*
X174999Y1254724D03*
X178740Y1243503D03*
X197440Y1254724D03*
Y1250984D03*
X193700Y1247243D03*
Y1243503D03*
X189960Y1254724D03*
Y1250984D03*
X186220Y1247243D03*
Y1243503D03*
X234841Y1075195D03*
X242321Y1075196D03*
Y1078936D03*
X246061Y1082677D03*
X238581Y1082676D03*
X234841Y1078935D03*
X246061Y1086417D03*
X238581Y1086416D03*
X249802Y1075196D03*
X257282D03*
X249802Y1078936D03*
X261022Y1086417D03*
X253542Y1082676D03*
X257282Y1078936D03*
X253542Y1086416D03*
X261022Y1082677D03*
X261023Y1243503D03*
Y1247243D03*
X279723Y1075196D03*
X264762D03*
X272243D03*
X275982Y1082677D03*
Y1086417D03*
X268502Y1082676D03*
X272243Y1078936D03*
X268502Y1086416D03*
X279723Y1078936D03*
X264762D03*
X264763Y1254724D03*
Y1250984D03*
X268503Y1243503D03*
Y1247243D03*
X272244Y1254724D03*
Y1250984D03*
X275984Y1243503D03*
Y1247243D03*
X279724Y1250984D03*
Y1254724D03*
X287203Y1075196D03*
X294684D03*
X290943Y1086417D03*
X287203Y1078936D03*
X290943Y1082677D03*
X283463Y1082676D03*
Y1086416D03*
X294684Y1078936D03*
X287204Y1254724D03*
X283464Y1243503D03*
Y1247243D03*
X287204Y1250984D03*
X302164Y1075196D03*
X309644D03*
X305904Y1082677D03*
X302164Y1078936D03*
X305904Y1086417D03*
X309644Y1078936D03*
X298424Y1086416D03*
Y1082676D03*
X317124Y1075196D03*
X324606Y1082676D03*
X317124Y1078936D03*
X313384Y1082677D03*
Y1086417D03*
X320866Y1082676D03*
X313385Y1120078D03*
X324606Y1123818D03*
Y1108858D03*
X320866D03*
X317125Y1112598D03*
X324606Y1116338D03*
X313385Y1112598D03*
X317125Y1120078D03*
X320866Y1116338D03*
Y1123818D03*
X313385Y1127558D03*
X317125Y1135039D03*
X313385D03*
X324606Y1131299D03*
X317125Y1127558D03*
X320866Y1131299D03*
X662008Y1254724D03*
X665748Y1247243D03*
X669488Y1250984D03*
X658268Y1247243D03*
X662008Y1250984D03*
X665748Y1243503D03*
X669488Y1254724D03*
X658268Y1243503D03*
X673228D03*
X680709Y1247243D03*
X673228D03*
X684449Y1254724D03*
Y1250984D03*
X676968Y1254724D03*
Y1250984D03*
X680709Y1243503D03*
X699408Y1075196D03*
X691928Y1075195D03*
Y1078935D03*
X699408Y1078936D03*
X695668Y1086416D03*
Y1082676D03*
X699409Y1254724D03*
X691929Y1250984D03*
X688189Y1247243D03*
Y1243503D03*
X691929Y1254724D03*
X695669Y1247243D03*
X699409Y1250984D03*
X695669Y1243503D03*
X706889Y1075196D03*
X714369D03*
X706889Y1078936D03*
X718109Y1086417D03*
X714369Y1078936D03*
X703148Y1082677D03*
X710629Y1086416D03*
X703148Y1086417D03*
X718109Y1082677D03*
X710629Y1082676D03*
X706890Y1250984D03*
X703149Y1243503D03*
X714370Y1254724D03*
Y1250984D03*
X710630Y1247243D03*
X706890Y1254724D03*
X710630Y1243503D03*
X703149Y1247243D03*
X721849Y1075196D03*
X729330D03*
X725589Y1086416D03*
X733069Y1086417D03*
X721849Y1078936D03*
X729330D03*
X733069Y1082677D03*
X725589Y1082676D03*
X736810Y1075196D03*
X744290D03*
Y1078936D03*
X748030Y1086417D03*
X740550Y1086416D03*
Y1082676D03*
X736810Y1078936D03*
X748030Y1082677D03*
X748031Y1247243D03*
Y1243503D03*
X751771Y1075196D03*
X766731D03*
X759251D03*
X762991Y1086417D03*
X766731Y1078936D03*
X755511Y1086416D03*
X759251Y1078936D03*
X755511Y1082676D03*
X762991Y1082677D03*
X751771Y1078936D03*
X766732Y1250984D03*
X755512Y1243503D03*
X762992D03*
Y1247243D03*
X751772Y1250984D03*
Y1254724D03*
X759252D03*
X766732D03*
X759252Y1250984D03*
X755512Y1247243D03*
X774211Y1075196D03*
X781693Y1082676D03*
X774211Y1078936D03*
X770471Y1086417D03*
Y1082677D03*
X777953Y1082676D03*
X774212Y1112598D03*
X770472D03*
X781693Y1123818D03*
X777953D03*
X781693Y1116338D03*
X777953Y1108858D03*
X770472Y1120078D03*
X781693Y1108858D03*
X777953Y1116338D03*
X774212Y1120078D03*
X770472Y1127558D03*
Y1135039D03*
X781693Y1131299D03*
X774212Y1127558D03*
Y1135039D03*
X777953Y1131299D03*
X781693Y1198621D03*
X774212Y1202362D03*
X770472D03*
X777953Y1198621D03*
Y1206102D03*
X770472Y1209842D03*
X781693Y1213582D03*
X774212Y1209842D03*
X777953Y1221062D03*
X781693D03*
Y1206102D03*
X770472Y1217322D03*
X774212D03*
X777953Y1213582D03*
Y1247243D03*
X770472Y1243503D03*
X781693Y1247243D03*
X770472D03*
X774212Y1250984D03*
Y1254724D03*
X1059251Y1198621D03*
Y1191141D03*
Y1221062D03*
Y1206102D03*
Y1213582D03*
Y1247243D03*
X1070472Y1187401D03*
X1066732D03*
X1062991Y1198621D03*
X1066732Y1194881D03*
X1062991Y1191141D03*
X1070472Y1194881D03*
Y1202362D03*
X1066732D03*
X1070472Y1217322D03*
X1066732D03*
X1062991Y1221062D03*
Y1206102D03*
X1070472Y1209842D03*
X1062991Y1213582D03*
X1066732Y1209842D03*
X1074212Y1250984D03*
X1066732Y1254724D03*
X1070472Y1247243D03*
X1074212Y1254724D03*
X1062991Y1247243D03*
X1070472Y1243503D03*
X1066732Y1250984D03*
X1077952Y1243503D03*
X1081692Y1250984D03*
X1077952Y1247243D03*
X1081692Y1254724D03*
X1085432Y1243503D03*
X1089172Y1254724D03*
Y1250984D03*
X1085432Y1247243D03*
X1096653Y1254724D03*
X1104133D03*
X1092913Y1247243D03*
X1096653Y1250984D03*
X1092913Y1243503D03*
X1107873D03*
X1100393D03*
X1107873Y1247243D03*
X1100393D03*
X1104133Y1250984D03*
X1111613Y1254724D03*
Y1250984D03*
X1156494Y1075196D03*
X1149014Y1075195D03*
Y1078935D03*
X1156494Y1078936D03*
X1152754Y1086416D03*
Y1082676D03*
X1163975Y1075196D03*
X1171455D03*
X1160234Y1086417D03*
X1167715Y1086416D03*
X1163975Y1078936D03*
X1160234Y1082677D03*
X1171455Y1078936D03*
X1167715Y1082676D03*
X1178935Y1075196D03*
X1186416D03*
X1175195Y1086417D03*
X1182675Y1086416D03*
X1175195Y1082677D03*
X1178935Y1078936D03*
X1182675Y1082676D03*
X1186416Y1078936D03*
X1178936Y1254724D03*
X1175196Y1243503D03*
X1182676Y1247243D03*
X1178936Y1250984D03*
X1186417D03*
X1182676Y1243503D03*
X1186417Y1254724D03*
X1175196Y1247243D03*
X1193896Y1075196D03*
X1201376D03*
X1190155Y1086417D03*
X1205116Y1082677D03*
X1190155D03*
X1197636Y1082676D03*
X1193896Y1078936D03*
X1205116Y1086417D03*
X1201376Y1078936D03*
X1197636Y1086416D03*
X1190157Y1243503D03*
X1201377Y1250984D03*
X1197637Y1247243D03*
X1193897Y1250984D03*
X1201377Y1254724D03*
X1197637Y1243503D03*
X1193897Y1254724D03*
X1190157Y1247243D03*
X1216337Y1075196D03*
X1208857D03*
X1212597Y1082676D03*
Y1086416D03*
X1220077Y1086417D03*
X1208857Y1078936D03*
X1216337D03*
X1220077Y1082677D03*
X1231297Y1075196D03*
X1223817D03*
X1231297Y1078936D03*
X1235039Y1082676D03*
X1227557Y1086417D03*
X1223817Y1078936D03*
X1227557Y1082677D03*
X1227558Y1112598D03*
X1235039Y1123818D03*
X1231298Y1120078D03*
Y1112598D03*
X1235039Y1108858D03*
Y1116338D03*
X1227558Y1120078D03*
X1231298Y1135039D03*
X1227558Y1127558D03*
X1235039Y1131299D03*
X1231298Y1127558D03*
X1227558Y1135039D03*
X1238779Y1082676D03*
Y1108858D03*
Y1116338D03*
Y1123818D03*
Y1131299D03*
X1572441Y1247243D03*
X1576181Y1254724D03*
Y1250984D03*
X1572441Y1243503D03*
X1583661Y1254724D03*
X1579921Y1247243D03*
X1591141Y1254724D03*
X1587401Y1247243D03*
Y1243503D03*
X1594882D03*
X1579921D03*
X1594882Y1247243D03*
X1583661Y1250984D03*
X1591141D03*
X1606101Y1075195D03*
X1609841Y1086416D03*
X1606101Y1078935D03*
X1609841Y1082676D03*
X1598622Y1254724D03*
Y1250984D03*
X1609842Y1247243D03*
X1606102Y1250984D03*
Y1254724D03*
X1609842Y1243503D03*
X1602362Y1247243D03*
Y1243503D03*
X1613581Y1075196D03*
X1621062D03*
X1613581Y1078936D03*
X1624802Y1082676D03*
X1617321Y1082677D03*
X1621062Y1078936D03*
X1617321Y1086417D03*
X1624802Y1086416D03*
X1624803Y1247243D03*
Y1243503D03*
X1621063Y1254724D03*
X1613582Y1250984D03*
X1617322Y1243503D03*
Y1247243D03*
X1613582Y1254724D03*
X1621063Y1250984D03*
X1636022Y1075196D03*
X1643503D03*
X1628542D03*
X1632282Y1082677D03*
X1643503Y1078936D03*
X1628542D03*
X1639762Y1086416D03*
X1632282Y1086417D03*
X1636022Y1078936D03*
X1639762Y1082676D03*
X1628543Y1250984D03*
Y1254724D03*
X1650983Y1075196D03*
X1658463D03*
X1654723Y1086416D03*
Y1082676D03*
X1650983Y1078936D03*
X1647242Y1082677D03*
Y1086417D03*
X1658463Y1078936D03*
X1673424Y1075196D03*
X1665944D03*
X1662203Y1086417D03*
Y1082677D03*
X1669684Y1086416D03*
X1665944Y1078936D03*
X1673424D03*
X1669684Y1082676D03*
X1673425Y1250984D03*
X1662204Y1247243D03*
X1665945Y1254724D03*
X1673425D03*
X1662204Y1243503D03*
X1665945Y1250984D03*
X1669685Y1247243D03*
Y1243503D03*
X1680904Y1075196D03*
X1688384D03*
X1692126Y1082676D03*
X1684644Y1082677D03*
Y1086417D03*
X1680904Y1078936D03*
X1688384D03*
X1677164Y1086417D03*
Y1082677D03*
X1692126Y1116338D03*
Y1108858D03*
X1684645Y1120078D03*
X1688385D03*
X1684645Y1112598D03*
X1692126Y1123818D03*
X1688385Y1112598D03*
X1684645Y1135039D03*
Y1127558D03*
X1692126Y1131299D03*
X1688385Y1127558D03*
Y1135039D03*
X1684645Y1202362D03*
X1692126Y1198621D03*
X1688385Y1202362D03*
X1692126Y1213582D03*
X1684645Y1217322D03*
Y1209842D03*
X1692126Y1206102D03*
Y1221062D03*
X1688385Y1209842D03*
Y1217322D03*
X1684645Y1243503D03*
X1677165D03*
X1692126Y1247243D03*
X1684645D03*
X1677165D03*
X1688385Y1254724D03*
Y1250984D03*
X1680905Y1254724D03*
Y1250984D03*
X1695866Y1082676D03*
Y1123818D03*
Y1116338D03*
Y1108858D03*
Y1131299D03*
Y1198621D03*
Y1221062D03*
Y1213582D03*
Y1206102D03*
Y1247243D03*
G54D58*
X1250055Y1710189D03*
Y1720189D03*
Y1739208D03*
Y1749208D03*
X1250048Y1768377D03*
Y1778377D03*
X1248555Y1797909D03*
Y1807909D03*
X1734069Y1710189D03*
Y1720189D03*
Y1739208D03*
Y1749208D03*
X1734062Y1768377D03*
Y1778377D03*
X1734069Y1797909D03*
Y1807909D03*
G54D39*
X212980Y390995D03*
Y405168D03*
Y394395D03*
X205680Y401482D03*
Y398082D03*
X212980Y408568D03*
Y419341D03*
Y422741D03*
X205680Y415655D03*
Y412255D03*
Y426428D03*
Y440602D03*
Y429828D03*
X212980Y433515D03*
Y436915D03*
X205680Y444002D03*
X212980Y469381D03*
Y472781D03*
X205680Y490641D03*
Y479868D03*
X212980Y483554D03*
X205680Y476468D03*
X212980Y486954D03*
X205680Y494041D03*
Y524002D03*
X212980Y516915D03*
Y513515D03*
X205680Y520602D03*
Y534775D03*
X212980Y527688D03*
X205680Y538175D03*
X212980Y531088D03*
X264005Y467337D03*
Y470737D03*
X256705Y474424D03*
X264005Y484910D03*
X256705Y488597D03*
X264005Y481510D03*
X256705Y477824D03*
Y491997D03*
X264005Y514871D03*
X256705Y518558D03*
X264005Y511471D03*
X256705Y521958D03*
Y532731D03*
Y536131D03*
X264005Y525644D03*
Y529044D03*
Y561510D03*
X256705Y571997D03*
Y568597D03*
X264005Y564910D03*
X256705Y586171D03*
X264005Y575684D03*
Y579084D03*
X256705Y582771D03*
X264005Y589857D03*
X256705Y600344D03*
X264005Y593257D03*
Y604030D03*
X256705Y596944D03*
Y611117D03*
Y614517D03*
X264005Y607430D03*
X670066Y390995D03*
Y405168D03*
X662766Y398082D03*
X670066Y408568D03*
Y394395D03*
X662766Y401482D03*
X670066Y422741D03*
Y419341D03*
X662766Y415655D03*
Y426428D03*
Y412255D03*
Y440602D03*
X670066Y433515D03*
X662766Y429828D03*
X670066Y436915D03*
X662766Y444002D03*
X670066Y469381D03*
Y472781D03*
X662766Y476468D03*
Y490641D03*
X670066Y483554D03*
Y486954D03*
X662766Y479868D03*
Y494041D03*
X670066Y516915D03*
X662766Y520602D03*
Y524002D03*
X670066Y513515D03*
Y527688D03*
X662766Y534775D03*
X670066Y531088D03*
X662766Y538175D03*
X713791Y474424D03*
Y488597D03*
Y477824D03*
Y491997D03*
Y518558D03*
Y521958D03*
Y536131D03*
Y532731D03*
Y571997D03*
Y568597D03*
Y582771D03*
Y586171D03*
Y596944D03*
Y600344D03*
Y611117D03*
Y614517D03*
X721091Y470737D03*
Y467337D03*
Y484910D03*
Y481510D03*
Y514871D03*
Y511471D03*
Y525644D03*
Y529044D03*
Y561510D03*
Y564910D03*
Y579084D03*
Y575684D03*
Y593257D03*
Y604030D03*
Y589857D03*
Y607430D03*
X919163Y848442D03*
Y851592D03*
X945982Y886737D03*
X949382D03*
X1011187Y-33526D03*
Y-30126D03*
Y-43526D03*
Y-40126D03*
X1081187Y-79306D03*
Y-82706D03*
Y-72706D03*
Y-69306D03*
X1119853Y398082D03*
Y401482D03*
Y412255D03*
Y426428D03*
Y415655D03*
Y440602D03*
Y429828D03*
Y444002D03*
Y490641D03*
Y476468D03*
Y479868D03*
Y494041D03*
Y524002D03*
Y520602D03*
Y538175D03*
Y534775D03*
X1127153Y390995D03*
Y408568D03*
Y405168D03*
Y394395D03*
Y422741D03*
Y419341D03*
Y436915D03*
Y433515D03*
Y472781D03*
Y469381D03*
Y486954D03*
Y483554D03*
Y516915D03*
Y513515D03*
Y527688D03*
Y531088D03*
X1170878Y474424D03*
Y477824D03*
Y488597D03*
Y491997D03*
Y518558D03*
Y521958D03*
Y532731D03*
Y536131D03*
Y571997D03*
Y568597D03*
Y586171D03*
Y582771D03*
Y596944D03*
Y600344D03*
Y614517D03*
Y611117D03*
X1178178Y467337D03*
Y470737D03*
Y484910D03*
Y481510D03*
Y511471D03*
Y514871D03*
Y529044D03*
Y525644D03*
Y564910D03*
Y561510D03*
Y579084D03*
Y575684D03*
Y604030D03*
Y593257D03*
Y589857D03*
Y607430D03*
X1225405Y-79278D03*
Y-82678D03*
Y-72678D03*
Y-69278D03*
X1230761Y-33628D03*
Y-30228D03*
Y-43628D03*
Y-40228D03*
X1297687Y-40256D03*
Y-43656D03*
X1337687Y-79306D03*
Y-82706D03*
X1481905Y-79278D03*
Y-82678D03*
X1517261Y-40358D03*
Y-43758D03*
X1576940Y398082D03*
Y401482D03*
Y415655D03*
Y412255D03*
Y426428D03*
Y440602D03*
Y429828D03*
Y444002D03*
Y476468D03*
Y490641D03*
Y479868D03*
Y494041D03*
Y520602D03*
Y524002D03*
Y534775D03*
Y538175D03*
X1592187Y-79306D03*
Y-82706D03*
X1582187Y-43786D03*
Y-40386D03*
X1584240Y390995D03*
Y408568D03*
Y405168D03*
Y394395D03*
Y419341D03*
Y422741D03*
Y433515D03*
Y436915D03*
Y472781D03*
Y469381D03*
Y483554D03*
Y486954D03*
Y516915D03*
Y513515D03*
Y531088D03*
Y527688D03*
X1627965Y474424D03*
Y488597D03*
Y477824D03*
Y491997D03*
Y521958D03*
Y518558D03*
Y536131D03*
Y532731D03*
Y571997D03*
Y568597D03*
Y582771D03*
Y586171D03*
Y596944D03*
Y600344D03*
Y614517D03*
Y611117D03*
X1635265Y470737D03*
Y467337D03*
Y484910D03*
Y481510D03*
Y514871D03*
Y511471D03*
Y529044D03*
Y525644D03*
Y564910D03*
Y561510D03*
Y575684D03*
Y579084D03*
Y593257D03*
Y604030D03*
Y589857D03*
Y607430D03*
X1736405Y-79278D03*
Y-82678D03*
X1801761Y-43888D03*
Y-40488D03*
G54D11*
X13780Y1226024D03*
X79331Y1186654D03*
X390354Y1141024D03*
X536418Y1086654D03*
X854291Y1225118D03*
X993504Y1170748D03*
X1304528Y1141024D03*
X1450591Y1086654D03*
X1761614Y1215000D03*
X1827165Y1235630D03*
G54D44*
X661674Y23622D03*
G54D18*
X23622Y1604724D03*
X62205Y765197D03*
X74016Y333464D03*
X102224Y70866D03*
X409488Y1604724D03*
X433130Y70866D03*
X463387Y286221D03*
X463386Y765197D03*
X785039Y1547638D03*
X890217Y23622D03*
X920473Y765196D03*
X1055905Y1547637D03*
X1118760Y23622D03*
X1347303Y70866D03*
X1377559Y286220D03*
Y765197D03*
X1431457Y1604724D03*
X1575846Y23622D03*
X1766929Y333464D03*
X1778740Y765197D03*
X1795010Y23622D03*
X1817323Y1604724D03*
G54D19*
X28819Y81575D03*
X73307Y61614D03*
X131181Y81575D03*
X175669Y61614D03*
X233543Y81575D03*
X278032Y61614D03*
X335906Y81575D03*
X380394Y61614D03*
X485886Y81595D03*
X530394Y61614D03*
X588248Y81594D03*
X632756Y61614D03*
X690611Y81595D03*
X735118Y61614D03*
X792973Y81595D03*
X837480Y61614D03*
X942973Y81595D03*
X987480Y61614D03*
X1045335Y81595D03*
X1089843Y61614D03*
X1147697Y81595D03*
X1192205Y61614D03*
X1250060Y81595D03*
X1294567Y61614D03*
X1400060Y81595D03*
X1444567Y61614D03*
X1502441Y81575D03*
X1546929Y61614D03*
X1604784Y81595D03*
X1649291Y61614D03*
X1707146Y81595D03*
X1751654Y61614D03*
G54D33*
X109882Y1504685D03*
Y1509804D03*
Y1607048D03*
Y1612166D03*
X127205Y1504685D03*
Y1509804D03*
X118543Y1509016D03*
Y1514134D03*
X127205Y1607048D03*
Y1612166D03*
X118543Y1611378D03*
Y1616496D03*
X144528Y1504685D03*
Y1509804D03*
X135866Y1509016D03*
Y1514134D03*
X144528Y1607048D03*
Y1612166D03*
X135866Y1611378D03*
Y1616496D03*
X161850Y1504685D03*
Y1509804D03*
X153189Y1509016D03*
Y1514134D03*
X161850Y1607048D03*
Y1612166D03*
X153189Y1611378D03*
Y1616496D03*
X170512Y1509016D03*
Y1514134D03*
Y1611378D03*
Y1616496D03*
X283110Y1458622D03*
X291771Y1462953D03*
X283110Y1463741D03*
X291771Y1468071D03*
X283110Y1576339D03*
X291771Y1580670D03*
X283110Y1581457D03*
X291771Y1585788D03*
X300433Y1458622D03*
X309094Y1462953D03*
X300433Y1463741D03*
X309094Y1468071D03*
X300433Y1576339D03*
X309094Y1580670D03*
X300433Y1581457D03*
X309094Y1585788D03*
X317756Y1458622D03*
X326417Y1462953D03*
X317756Y1463741D03*
X326417Y1468071D03*
X317756Y1576339D03*
X326417Y1580670D03*
X317756Y1581457D03*
X326417Y1585788D03*
X335078Y1458622D03*
X343740Y1462953D03*
X335078Y1463741D03*
X343740Y1468071D03*
X335078Y1576339D03*
X343740Y1580670D03*
X335078Y1581457D03*
X343740Y1585788D03*
X456339Y1473977D03*
Y1479095D03*
Y1560985D03*
Y1566103D03*
X473662Y1473977D03*
Y1479095D03*
X465000Y1478308D03*
Y1483426D03*
X473662Y1560985D03*
Y1566103D03*
X465000Y1565315D03*
Y1570434D03*
X490985Y1473977D03*
Y1479095D03*
X482323Y1478308D03*
Y1483426D03*
X490985Y1560985D03*
Y1566103D03*
X482323Y1565315D03*
Y1570434D03*
X499646Y1478308D03*
Y1483426D03*
Y1565315D03*
Y1570434D03*
X508307Y1473977D03*
X516969Y1478308D03*
X508307Y1479095D03*
X516969Y1483426D03*
X508307Y1560985D03*
X516969Y1565315D03*
X508307Y1566103D03*
X516969Y1570434D03*
X629567Y1489331D03*
Y1494449D03*
Y1591693D03*
Y1596811D03*
X646890Y1489331D03*
Y1494449D03*
X638228Y1493662D03*
Y1498780D03*
X646890Y1591693D03*
X638228Y1596024D03*
X646890Y1596811D03*
X638228Y1601142D03*
X664213Y1489331D03*
Y1494449D03*
X655551Y1493662D03*
Y1498780D03*
X664213Y1591693D03*
X655551Y1596024D03*
X664213Y1596811D03*
X655551Y1601142D03*
X681535Y1489331D03*
Y1494449D03*
X672874Y1493662D03*
Y1498780D03*
X681535Y1591693D03*
X672874Y1596024D03*
X681535Y1596811D03*
X672874Y1601142D03*
X690197Y1493662D03*
Y1498780D03*
Y1596024D03*
Y1601142D03*
X1131850Y1504685D03*
X1140511Y1509016D03*
X1131850Y1509804D03*
X1140511Y1514134D03*
X1131850Y1607048D03*
X1140511Y1611378D03*
X1131850Y1612166D03*
X1140511Y1616496D03*
X1149173Y1504685D03*
Y1509804D03*
Y1607048D03*
Y1612166D03*
X1166496Y1504685D03*
Y1509804D03*
X1157834Y1509016D03*
Y1514134D03*
X1166496Y1607048D03*
Y1612166D03*
X1157834Y1611378D03*
Y1616496D03*
X1183818Y1504685D03*
Y1509804D03*
X1175157Y1509016D03*
Y1514134D03*
X1183818Y1607048D03*
Y1612166D03*
X1175157Y1611378D03*
Y1616496D03*
X1192480Y1509016D03*
Y1514134D03*
Y1611378D03*
Y1616496D03*
X1305079Y1458622D03*
X1313740Y1462953D03*
X1305079Y1463741D03*
X1313740Y1468071D03*
X1305079Y1576339D03*
X1313740Y1580670D03*
X1305079Y1581457D03*
X1313740Y1585788D03*
X1322402Y1458622D03*
X1331063Y1462953D03*
X1322402Y1463741D03*
X1331063Y1468071D03*
X1322402Y1576339D03*
X1331063Y1580670D03*
X1322402Y1581457D03*
X1331063Y1585788D03*
X1339725Y1458622D03*
X1348386Y1462953D03*
X1339725Y1463741D03*
X1348386Y1468071D03*
X1339725Y1576339D03*
X1348386Y1580670D03*
X1339725Y1581457D03*
X1348386Y1585788D03*
X1357047Y1458622D03*
X1365709Y1462953D03*
X1357047Y1463741D03*
X1365709Y1468071D03*
X1357047Y1576339D03*
X1365709Y1580670D03*
X1357047Y1581457D03*
X1365709Y1585788D03*
X1478307Y1473977D03*
Y1479095D03*
Y1560985D03*
Y1566103D03*
X1495630Y1473977D03*
Y1479095D03*
X1486968Y1478308D03*
Y1483426D03*
X1495630Y1560985D03*
Y1566103D03*
X1486968Y1565315D03*
Y1570434D03*
X1512953Y1473977D03*
Y1479095D03*
X1504291Y1478308D03*
Y1483426D03*
X1512953Y1560985D03*
Y1566103D03*
X1504291Y1565315D03*
Y1570434D03*
X1530275Y1473977D03*
Y1479095D03*
X1521614Y1478308D03*
Y1483426D03*
X1530275Y1560985D03*
Y1566103D03*
X1521614Y1565315D03*
Y1570434D03*
X1538937Y1478308D03*
Y1483426D03*
Y1565315D03*
Y1570434D03*
X1651535Y1489331D03*
X1660196Y1493662D03*
X1651535Y1494449D03*
X1660196Y1498780D03*
X1651535Y1591693D03*
X1660196Y1596024D03*
X1651535Y1596811D03*
X1660196Y1601142D03*
X1668858Y1489331D03*
Y1494449D03*
Y1591693D03*
Y1596811D03*
X1686181Y1489331D03*
Y1494449D03*
X1677519Y1493662D03*
Y1498780D03*
X1686181Y1591693D03*
X1677519Y1596024D03*
X1686181Y1596811D03*
X1677519Y1601142D03*
X1703503Y1489331D03*
Y1494449D03*
X1694842Y1493662D03*
Y1498780D03*
X1703503Y1591693D03*
X1694842Y1596024D03*
X1703503Y1596811D03*
X1694842Y1601142D03*
X1712165Y1493662D03*
Y1498780D03*
Y1596024D03*
Y1601142D03*
G54D37*
X173829Y455492D03*
Y583957D03*
X202844Y455492D03*
Y583957D03*
X630915Y455492D03*
Y583957D03*
X659930Y455492D03*
Y583957D03*
X1088002Y455492D03*
Y583957D03*
X1117017Y455492D03*
Y583957D03*
X1545089Y455492D03*
Y583957D03*
X1574104Y455492D03*
Y583957D03*
G54D61*
X1795453Y812874D03*
Y834922D03*
G54D48*
X849441Y1367717D03*
G54D50*
X895384Y228740D03*
Y276772D03*
X923336Y226772D03*
Y278740D03*
G54D55*
X1030635Y764546D03*
G54D62*
X1803917Y823898D03*
G54D59*
X1747253Y1715189D03*
Y1744208D03*
X1747246Y1773377D03*
G54D60*
X1747253Y1802909D03*
G54D63*
X1817323Y1567323D03*
G54D13*
X19685Y-83298D03*
Y1801195D03*
X1821260Y-83298D03*
Y1801195D03*
G54D29*
X116731Y1066535D03*
Y1263386D03*
X352952Y1066535D03*
Y1263386D03*
X573818Y1066535D03*
Y1263386D03*
X810038Y1066535D03*
Y1263386D03*
X1030905Y1066535D03*
Y1263386D03*
X1267125Y1066535D03*
Y1263386D03*
X1487991Y1066535D03*
Y1263386D03*
X1724212Y1066535D03*
Y1263386D03*
G54D17*
X26789Y1373669D03*
X184851Y334492D03*
X235433Y1580079D03*
Y1626339D03*
X581890Y1580079D03*
Y1626339D03*
X1259055Y1580079D03*
Y1626339D03*
X1605512Y1580079D03*
Y1626339D03*
X1796847Y1517889D03*
X1809883Y120792D03*
G54D47*
X770472Y1490945D03*
X820079Y388583D03*
X1020866D03*
X1070472Y1490945D03*
G54D31*
X109882Y1453504D03*
Y1468859D03*
Y1484213D03*
Y1499567D03*
Y1514922D03*
Y1555867D03*
Y1571221D03*
Y1586575D03*
Y1601930D03*
Y1617284D03*
X127205Y1453504D03*
X118543Y1457835D03*
X127205Y1468859D03*
X118543Y1473189D03*
X127205Y1484213D03*
X118543Y1488544D03*
X127205Y1499567D03*
Y1514922D03*
X118543Y1503898D03*
Y1519252D03*
X127205Y1555867D03*
X118543Y1560197D03*
X127205Y1571221D03*
X118543Y1575552D03*
X127205Y1586575D03*
X118543Y1590906D03*
X127205Y1601930D03*
X118543Y1606260D03*
X127205Y1617284D03*
X118543Y1621615D03*
X144528Y1453504D03*
X135866Y1457835D03*
X144528Y1468859D03*
X135866Y1473189D03*
X144528Y1484213D03*
X135866Y1488544D03*
X144528Y1499567D03*
Y1514922D03*
X135866Y1503898D03*
Y1519252D03*
X144528Y1555867D03*
X135866Y1560197D03*
X144528Y1571221D03*
X135866Y1575552D03*
X144528Y1586575D03*
X135866Y1590906D03*
X144528Y1601930D03*
X135866Y1606260D03*
X144528Y1617284D03*
X135866Y1621615D03*
X161850Y1453504D03*
X153189Y1457835D03*
X161850Y1468859D03*
X153189Y1473189D03*
X161850Y1484213D03*
X153189Y1488544D03*
X161850Y1499567D03*
Y1514922D03*
X153189Y1503898D03*
Y1519252D03*
X161850Y1555867D03*
X153189Y1560197D03*
X161850Y1571221D03*
X153189Y1575552D03*
X161850Y1586575D03*
X153189Y1590906D03*
X161850Y1601930D03*
X153189Y1606260D03*
X161850Y1617284D03*
X153189Y1621615D03*
X179173Y1453504D03*
X170512Y1457835D03*
X179173Y1468859D03*
X170512Y1473189D03*
X179173Y1484213D03*
X170512Y1488544D03*
X179173Y1499567D03*
Y1514922D03*
X170512Y1503898D03*
Y1519252D03*
X179173Y1555867D03*
X170512Y1560197D03*
X179173Y1571221D03*
X170512Y1575552D03*
X179173Y1586575D03*
X170512Y1590906D03*
X179173Y1601930D03*
X170512Y1606260D03*
X179173Y1617284D03*
X170512Y1621615D03*
X187835Y1457835D03*
Y1473189D03*
Y1488544D03*
Y1503898D03*
Y1519252D03*
Y1560197D03*
Y1575552D03*
Y1590906D03*
Y1606260D03*
Y1621615D03*
X283110Y1453504D03*
X291771Y1457835D03*
X283110Y1468859D03*
X291771Y1473189D03*
X283110Y1484213D03*
X291771Y1488544D03*
X283110Y1499567D03*
X291771Y1503898D03*
X283110Y1514922D03*
X291771Y1519252D03*
X283110Y1555867D03*
X291771Y1560197D03*
X283110Y1571221D03*
X291771Y1575552D03*
X283110Y1586575D03*
X291771Y1590906D03*
X283110Y1601930D03*
X291771Y1606260D03*
X283110Y1617284D03*
X291771Y1621615D03*
X300433Y1453504D03*
X309094Y1457835D03*
X300433Y1468859D03*
X309094Y1473189D03*
X300433Y1484213D03*
X309094Y1488544D03*
X300433Y1499567D03*
X309094Y1503898D03*
X300433Y1514922D03*
X309094Y1519252D03*
X300433Y1555867D03*
X309094Y1560197D03*
X300433Y1571221D03*
X309094Y1575552D03*
X300433Y1586575D03*
X309094Y1590906D03*
X300433Y1601930D03*
X309094Y1606260D03*
X300433Y1617284D03*
X309094Y1621615D03*
X317756Y1453504D03*
X326417Y1457835D03*
X317756Y1468859D03*
X326417Y1473189D03*
X317756Y1484213D03*
X326417Y1488544D03*
X317756Y1499567D03*
X326417Y1503898D03*
X317756Y1514922D03*
X326417Y1519252D03*
X317756Y1555867D03*
X326417Y1560197D03*
X317756Y1571221D03*
X326417Y1575552D03*
X317756Y1586575D03*
X326417Y1590906D03*
X317756Y1601930D03*
X326417Y1606260D03*
X317756Y1617284D03*
X326417Y1621615D03*
X335078Y1453504D03*
X343740Y1457835D03*
X335078Y1468859D03*
X343740Y1473189D03*
X335078Y1484213D03*
X343740Y1488544D03*
X335078Y1499567D03*
X343740Y1503898D03*
X335078Y1514922D03*
X343740Y1519252D03*
X335078Y1555867D03*
X343740Y1560197D03*
X335078Y1571221D03*
X343740Y1575552D03*
X335078Y1586575D03*
X343740Y1590906D03*
X335078Y1601930D03*
X343740Y1606260D03*
X335078Y1617284D03*
X343740Y1621615D03*
X352401Y1453504D03*
X361063Y1457835D03*
X352401Y1468859D03*
X361063Y1473189D03*
X352401Y1484213D03*
X361063Y1488544D03*
X352401Y1499567D03*
X361063Y1503898D03*
X352401Y1514922D03*
X361063Y1519252D03*
X352401Y1555867D03*
X361063Y1560197D03*
X352401Y1571221D03*
X361063Y1575552D03*
X352401Y1586575D03*
X361063Y1590906D03*
X352401Y1601930D03*
X361063Y1606260D03*
X352401Y1617284D03*
X361063Y1621615D03*
X456339Y1453504D03*
Y1468859D03*
Y1484213D03*
Y1499567D03*
Y1514922D03*
Y1555867D03*
Y1571221D03*
Y1586575D03*
Y1601930D03*
Y1617284D03*
X473662Y1453504D03*
X465000Y1457835D03*
X473662Y1468859D03*
X465000Y1473189D03*
X473662Y1484213D03*
X465000Y1488544D03*
X473662Y1499567D03*
Y1514922D03*
X465000Y1503898D03*
Y1519252D03*
X473662Y1555867D03*
X465000Y1560197D03*
X473662Y1571221D03*
X465000Y1575552D03*
X473662Y1586575D03*
X465000Y1590906D03*
X473662Y1601930D03*
X465000Y1606260D03*
X473662Y1617284D03*
X465000Y1621615D03*
X490985Y1453504D03*
X482323Y1457835D03*
X490985Y1468859D03*
X482323Y1473189D03*
X490985Y1484213D03*
X482323Y1488544D03*
X490985Y1499567D03*
Y1514922D03*
X482323Y1503898D03*
Y1519252D03*
X490985Y1555867D03*
X482323Y1560197D03*
X490985Y1571221D03*
X482323Y1575552D03*
X490985Y1586575D03*
X482323Y1590906D03*
X490985Y1601930D03*
X482323Y1606260D03*
X490985Y1617284D03*
X482323Y1621615D03*
X508307Y1453504D03*
X499646Y1457835D03*
X508307Y1468859D03*
X499646Y1473189D03*
X508307Y1484213D03*
X499646Y1488544D03*
X508307Y1499567D03*
Y1514922D03*
X499646Y1503898D03*
Y1519252D03*
X508307Y1555867D03*
X499646Y1560197D03*
X508307Y1571221D03*
X499646Y1575552D03*
X508307Y1586575D03*
X499646Y1590906D03*
X508307Y1601930D03*
X499646Y1606260D03*
X508307Y1617284D03*
X499646Y1621615D03*
X516969Y1457835D03*
Y1473189D03*
Y1488544D03*
Y1503898D03*
Y1519252D03*
Y1560197D03*
Y1575552D03*
Y1590906D03*
Y1606260D03*
Y1621615D03*
X525630Y1453504D03*
X534292Y1457835D03*
X525630Y1468859D03*
X534292Y1473189D03*
X525630Y1484213D03*
X534292Y1488544D03*
X525630Y1499567D03*
X534292Y1503898D03*
X525630Y1514922D03*
X534292Y1519252D03*
X525630Y1555867D03*
X534292Y1560197D03*
X525630Y1571221D03*
X534292Y1575552D03*
X525630Y1586575D03*
X534292Y1590906D03*
X525630Y1601930D03*
X534292Y1606260D03*
X525630Y1617284D03*
X534292Y1621615D03*
X629567Y1453504D03*
X638228Y1457835D03*
X629567Y1468859D03*
X638228Y1473189D03*
X629567Y1484213D03*
X638228Y1488544D03*
X629567Y1499567D03*
X638228Y1503898D03*
X629567Y1514922D03*
X638228Y1519252D03*
X629567Y1555867D03*
X638228Y1560197D03*
X629567Y1571221D03*
X638228Y1575552D03*
X629567Y1586575D03*
X638228Y1590906D03*
X629567Y1601930D03*
X638228Y1606260D03*
X629567Y1617284D03*
X638228Y1621615D03*
X646890Y1453504D03*
Y1468859D03*
Y1484213D03*
Y1499567D03*
Y1514922D03*
Y1555867D03*
Y1571221D03*
Y1586575D03*
Y1601930D03*
Y1617284D03*
X664213Y1453504D03*
X655551Y1457835D03*
X664213Y1468859D03*
X655551Y1473189D03*
X664213Y1484213D03*
X655551Y1488544D03*
X664213Y1499567D03*
Y1514922D03*
X655551Y1503898D03*
Y1519252D03*
X664213Y1555867D03*
X655551Y1560197D03*
X664213Y1571221D03*
X655551Y1575552D03*
X664213Y1586575D03*
X655551Y1590906D03*
X664213Y1601930D03*
X655551Y1606260D03*
X664213Y1617284D03*
X655551Y1621615D03*
X681535Y1453504D03*
X672874Y1457835D03*
X681535Y1468859D03*
X672874Y1473189D03*
X681535Y1484213D03*
X672874Y1488544D03*
X681535Y1499567D03*
Y1514922D03*
X672874Y1503898D03*
Y1519252D03*
X681535Y1555867D03*
X672874Y1560197D03*
X681535Y1571221D03*
X672874Y1575552D03*
X681535Y1586575D03*
X672874Y1590906D03*
X681535Y1601930D03*
X672874Y1606260D03*
X681535Y1617284D03*
X672874Y1621615D03*
X698858Y1453504D03*
X690197Y1457835D03*
X698858Y1468859D03*
X690197Y1473189D03*
X698858Y1484213D03*
X690197Y1488544D03*
X698858Y1499567D03*
Y1514922D03*
X690197Y1503898D03*
Y1519252D03*
X698858Y1555867D03*
X690197Y1560197D03*
X698858Y1571221D03*
X690197Y1575552D03*
X698858Y1586575D03*
X690197Y1590906D03*
X698858Y1601930D03*
X690197Y1606260D03*
X698858Y1617284D03*
X690197Y1621615D03*
X707520Y1457835D03*
Y1473189D03*
Y1488544D03*
Y1503898D03*
Y1519252D03*
Y1560197D03*
Y1575552D03*
Y1590906D03*
Y1606260D03*
Y1621615D03*
X1131850Y1453504D03*
X1140511Y1457835D03*
X1131850Y1468859D03*
X1140511Y1473189D03*
X1131850Y1484213D03*
X1140511Y1488544D03*
X1131850Y1499567D03*
X1140511Y1503898D03*
X1131850Y1514922D03*
X1140511Y1519252D03*
X1131850Y1555867D03*
X1140511Y1560197D03*
X1131850Y1571221D03*
X1140511Y1575552D03*
X1131850Y1586575D03*
X1140511Y1590906D03*
X1131850Y1601930D03*
X1140511Y1606260D03*
X1131850Y1617284D03*
X1140511Y1621615D03*
X1149173Y1453504D03*
X1157834Y1457835D03*
X1149173Y1468859D03*
X1157834Y1473189D03*
X1149173Y1484213D03*
X1157834Y1488544D03*
X1149173Y1499567D03*
X1157834Y1503898D03*
X1149173Y1514922D03*
X1157834Y1519252D03*
X1149173Y1555867D03*
X1157834Y1560197D03*
X1149173Y1571221D03*
X1157834Y1575552D03*
X1149173Y1586575D03*
X1157834Y1590906D03*
X1149173Y1601930D03*
X1157834Y1606260D03*
X1149173Y1617284D03*
X1157834Y1621615D03*
X1166496Y1453504D03*
Y1468859D03*
Y1484213D03*
Y1499567D03*
Y1514922D03*
Y1555867D03*
Y1571221D03*
Y1586575D03*
Y1601930D03*
Y1617284D03*
X1183818Y1453504D03*
X1175157Y1457835D03*
X1183818Y1468859D03*
X1175157Y1473189D03*
X1183818Y1484213D03*
X1175157Y1488544D03*
X1183818Y1499567D03*
Y1514922D03*
X1175157Y1503898D03*
Y1519252D03*
X1183818Y1555867D03*
X1175157Y1560197D03*
X1183818Y1571221D03*
X1175157Y1575552D03*
X1183818Y1586575D03*
X1175157Y1590906D03*
X1183818Y1601930D03*
X1175157Y1606260D03*
X1183818Y1617284D03*
X1175157Y1621615D03*
X1201141Y1453504D03*
X1192480Y1457835D03*
X1201141Y1468859D03*
X1192480Y1473189D03*
X1201141Y1484213D03*
X1192480Y1488544D03*
X1201141Y1499567D03*
Y1514922D03*
X1192480Y1503898D03*
Y1519252D03*
X1201141Y1555867D03*
X1192480Y1560197D03*
X1201141Y1571221D03*
X1192480Y1575552D03*
X1201141Y1586575D03*
X1192480Y1590906D03*
X1201141Y1601930D03*
X1192480Y1606260D03*
X1201141Y1617284D03*
X1192480Y1621615D03*
X1209803Y1457835D03*
Y1473189D03*
Y1488544D03*
Y1503898D03*
Y1519252D03*
Y1560197D03*
Y1575552D03*
Y1590906D03*
Y1606260D03*
Y1621615D03*
X1305079Y1453504D03*
X1313740Y1457835D03*
X1305079Y1468859D03*
X1313740Y1473189D03*
X1305079Y1484213D03*
X1313740Y1488544D03*
X1305079Y1499567D03*
X1313740Y1503898D03*
X1305079Y1514922D03*
X1313740Y1519252D03*
X1305079Y1555867D03*
X1313740Y1560197D03*
X1305079Y1571221D03*
X1313740Y1575552D03*
X1305079Y1586575D03*
X1313740Y1590906D03*
X1305079Y1601930D03*
X1313740Y1606260D03*
X1305079Y1617284D03*
X1313740Y1621615D03*
X1322402Y1453504D03*
X1331063Y1457835D03*
X1322402Y1468859D03*
X1331063Y1473189D03*
X1322402Y1484213D03*
X1331063Y1488544D03*
X1322402Y1499567D03*
X1331063Y1503898D03*
X1322402Y1514922D03*
X1331063Y1519252D03*
X1322402Y1555867D03*
X1331063Y1560197D03*
X1322402Y1571221D03*
X1331063Y1575552D03*
X1322402Y1586575D03*
X1331063Y1590906D03*
X1322402Y1601930D03*
X1331063Y1606260D03*
X1322402Y1617284D03*
X1331063Y1621615D03*
X1339725Y1453504D03*
X1348386Y1457835D03*
X1339725Y1468859D03*
X1348386Y1473189D03*
X1339725Y1484213D03*
X1348386Y1488544D03*
X1339725Y1499567D03*
X1348386Y1503898D03*
X1339725Y1514922D03*
X1348386Y1519252D03*
X1339725Y1555867D03*
X1348386Y1560197D03*
X1339725Y1571221D03*
X1348386Y1575552D03*
X1339725Y1586575D03*
X1348386Y1590906D03*
X1339725Y1601930D03*
X1348386Y1606260D03*
X1339725Y1617284D03*
X1348386Y1621615D03*
X1357047Y1453504D03*
X1365709Y1457835D03*
X1357047Y1468859D03*
X1365709Y1473189D03*
X1357047Y1484213D03*
X1365709Y1488544D03*
X1357047Y1499567D03*
X1365709Y1503898D03*
X1357047Y1514922D03*
X1365709Y1519252D03*
X1357047Y1555867D03*
X1365709Y1560197D03*
X1357047Y1571221D03*
X1365709Y1575552D03*
X1357047Y1586575D03*
X1365709Y1590906D03*
X1357047Y1601930D03*
X1365709Y1606260D03*
X1357047Y1617284D03*
X1365709Y1621615D03*
X1374370Y1453504D03*
X1383032Y1457835D03*
X1374370Y1468859D03*
X1383032Y1473189D03*
X1374370Y1484213D03*
X1383032Y1488544D03*
X1374370Y1499567D03*
X1383032Y1503898D03*
X1374370Y1514922D03*
X1383032Y1519252D03*
X1374370Y1555867D03*
X1383032Y1560197D03*
X1374370Y1571221D03*
X1383032Y1575552D03*
X1374370Y1586575D03*
X1383032Y1590906D03*
X1374370Y1601930D03*
X1383032Y1606260D03*
X1374370Y1617284D03*
X1383032Y1621615D03*
X1478307Y1453504D03*
Y1468859D03*
Y1484213D03*
Y1499567D03*
Y1514922D03*
Y1555867D03*
Y1571221D03*
Y1586575D03*
Y1601930D03*
Y1617284D03*
X1495630Y1453504D03*
X1486968Y1457835D03*
X1495630Y1468859D03*
X1486968Y1473189D03*
X1495630Y1484213D03*
X1486968Y1488544D03*
X1495630Y1499567D03*
Y1514922D03*
X1486968Y1503898D03*
Y1519252D03*
X1495630Y1555867D03*
X1486968Y1560197D03*
X1495630Y1571221D03*
X1486968Y1575552D03*
X1495630Y1586575D03*
X1486968Y1590906D03*
X1495630Y1601930D03*
X1486968Y1606260D03*
X1495630Y1617284D03*
X1486968Y1621615D03*
X1512953Y1453504D03*
X1504291Y1457835D03*
X1512953Y1468859D03*
X1504291Y1473189D03*
X1512953Y1484213D03*
X1504291Y1488544D03*
X1512953Y1499567D03*
Y1514922D03*
X1504291Y1503898D03*
Y1519252D03*
X1512953Y1555867D03*
X1504291Y1560197D03*
X1512953Y1571221D03*
X1504291Y1575552D03*
X1512953Y1586575D03*
X1504291Y1590906D03*
X1512953Y1601930D03*
X1504291Y1606260D03*
X1512953Y1617284D03*
X1504291Y1621615D03*
X1530275Y1453504D03*
X1521614Y1457835D03*
X1530275Y1468859D03*
X1521614Y1473189D03*
X1530275Y1484213D03*
X1521614Y1488544D03*
X1530275Y1499567D03*
Y1514922D03*
X1521614Y1503898D03*
Y1519252D03*
X1530275Y1555867D03*
X1521614Y1560197D03*
X1530275Y1571221D03*
X1521614Y1575552D03*
X1530275Y1586575D03*
X1521614Y1590906D03*
X1530275Y1601930D03*
X1521614Y1606260D03*
X1530275Y1617284D03*
X1521614Y1621615D03*
X1547598Y1453504D03*
X1538937Y1457835D03*
X1547598Y1468859D03*
X1538937Y1473189D03*
X1547598Y1484213D03*
X1538937Y1488544D03*
X1547598Y1499567D03*
Y1514922D03*
X1538937Y1503898D03*
Y1519252D03*
X1547598Y1555867D03*
X1538937Y1560197D03*
X1547598Y1571221D03*
X1538937Y1575552D03*
X1547598Y1586575D03*
X1538937Y1590906D03*
X1547598Y1601930D03*
X1538937Y1606260D03*
X1547598Y1617284D03*
X1538937Y1621615D03*
X1556260Y1457835D03*
Y1473189D03*
Y1488544D03*
Y1503898D03*
Y1519252D03*
Y1560197D03*
Y1575552D03*
Y1590906D03*
Y1606260D03*
Y1621615D03*
X1651535Y1453504D03*
X1660196Y1457835D03*
X1651535Y1468859D03*
X1660196Y1473189D03*
X1651535Y1484213D03*
X1660196Y1488544D03*
X1651535Y1499567D03*
X1660196Y1503898D03*
X1651535Y1514922D03*
X1660196Y1519252D03*
X1651535Y1555867D03*
X1660196Y1560197D03*
X1651535Y1571221D03*
X1660196Y1575552D03*
X1651535Y1586575D03*
X1660196Y1590906D03*
X1651535Y1601930D03*
X1660196Y1606260D03*
X1651535Y1617284D03*
X1660196Y1621615D03*
X1668858Y1453504D03*
X1677519Y1457835D03*
X1668858Y1468859D03*
X1677519Y1473189D03*
X1668858Y1484213D03*
X1677519Y1488544D03*
X1668858Y1499567D03*
X1677519Y1503898D03*
X1668858Y1514922D03*
X1677519Y1519252D03*
X1668858Y1555867D03*
X1677519Y1560197D03*
X1668858Y1571221D03*
X1677519Y1575552D03*
X1668858Y1586575D03*
X1677519Y1590906D03*
X1668858Y1601930D03*
X1677519Y1606260D03*
X1668858Y1617284D03*
X1677519Y1621615D03*
X1686181Y1453504D03*
Y1468859D03*
Y1484213D03*
Y1499567D03*
Y1514922D03*
Y1555867D03*
Y1571221D03*
Y1586575D03*
Y1601930D03*
Y1617284D03*
X1703503Y1453504D03*
X1694842Y1457835D03*
X1703503Y1468859D03*
X1694842Y1473189D03*
X1703503Y1484213D03*
X1694842Y1488544D03*
X1703503Y1499567D03*
Y1514922D03*
X1694842Y1503898D03*
Y1519252D03*
X1703503Y1555867D03*
X1694842Y1560197D03*
X1703503Y1571221D03*
X1694842Y1575552D03*
X1703503Y1586575D03*
X1694842Y1590906D03*
X1703503Y1601930D03*
X1694842Y1606260D03*
X1703503Y1617284D03*
X1694842Y1621615D03*
X1720826Y1453504D03*
X1712165Y1457835D03*
X1720826Y1468859D03*
X1712165Y1473189D03*
X1720826Y1484213D03*
X1712165Y1488544D03*
X1720826Y1499567D03*
Y1514922D03*
X1712165Y1503898D03*
Y1519252D03*
X1720826Y1555867D03*
X1712165Y1560197D03*
X1720826Y1571221D03*
X1712165Y1575552D03*
X1720826Y1586575D03*
X1712165Y1590906D03*
X1720826Y1601930D03*
X1712165Y1606260D03*
X1720826Y1617284D03*
X1712165Y1621615D03*
X1729488Y1457835D03*
Y1473189D03*
Y1488544D03*
Y1503898D03*
Y1519252D03*
Y1560197D03*
Y1575552D03*
Y1590906D03*
Y1606260D03*
Y1621615D03*
G54D40*
X235433Y1606142D03*
X581890D03*
X1259055D03*
X1605512D03*
G54D16*
X15139Y198883D03*
Y201683D03*
X18564Y238589D03*
X6690Y1496782D03*
X34520Y213539D03*
X36201Y238714D03*
X21530Y236121D03*
X27966Y238689D03*
X27625Y663094D03*
X25818Y682139D03*
X28818D03*
X32079Y1517641D03*
X65189Y228961D03*
Y231461D03*
Y223661D03*
Y226461D03*
X54733Y231226D03*
Y228726D03*
Y223726D03*
Y226226D03*
X67622Y572842D03*
X64408Y572975D03*
X73110Y101701D03*
X78501Y110445D03*
Y115401D03*
Y129574D03*
Y124618D03*
X73158Y229286D03*
X76851Y222212D03*
Y224712D03*
X73158Y231786D03*
X75777Y585507D03*
X71184D03*
X71730Y579475D03*
X71228Y590145D03*
X75822Y590190D03*
X75684Y605443D03*
X83684D03*
X78129Y656900D03*
X72314Y680207D03*
Y683407D03*
X82714Y674707D03*
X71928Y873683D03*
X88903Y117557D03*
Y122513D03*
Y131731D03*
Y136687D03*
X94390Y293645D03*
Y290845D03*
Y288345D03*
X91890Y293645D03*
Y290845D03*
Y288345D03*
X93456Y649838D03*
X89432Y668293D03*
X92134D03*
X85614Y674707D03*
X87714Y684607D03*
X117501Y198883D03*
Y201683D03*
X111275Y1008262D03*
Y1011762D03*
X130328Y238689D03*
X123892Y236121D03*
X120926Y238589D03*
X136882Y213539D03*
X138563Y238714D03*
X143186Y402291D03*
Y397335D03*
X140786Y416465D03*
Y411509D03*
Y425682D03*
Y430638D03*
Y439855D03*
Y444811D03*
Y468609D03*
Y473565D03*
Y487738D03*
Y482782D03*
Y512743D03*
Y517699D03*
Y531872D03*
Y526916D03*
X157095Y228726D03*
Y231226D03*
X167551Y223661D03*
X157095Y226226D03*
Y223726D03*
X151188Y390223D03*
Y395179D03*
Y404396D03*
Y409352D03*
Y423525D03*
Y418569D03*
Y432743D03*
Y437699D03*
Y489895D03*
Y480677D03*
Y475721D03*
Y494851D03*
Y519855D03*
Y538984D03*
Y534028D03*
Y524811D03*
X175472Y101701D03*
X175520Y229286D03*
X179213Y224712D03*
Y222212D03*
X167551Y231461D03*
Y228961D03*
Y226461D03*
X175520Y231786D03*
X194189Y103621D03*
X196752Y293645D03*
Y290845D03*
Y288345D03*
X194252Y293645D03*
Y290845D03*
Y288345D03*
X203740Y567914D03*
Y565414D03*
Y570414D03*
Y575414D03*
Y572914D03*
X219863Y198883D03*
Y201683D03*
X226254Y236121D03*
X223288Y238589D03*
X239244Y213539D03*
X232690Y238689D03*
X240925Y238714D03*
X259457Y228726D03*
Y231226D03*
Y226226D03*
Y223726D03*
X251802Y824128D03*
X277834Y101701D03*
X269913Y228961D03*
Y226461D03*
Y223661D03*
X277882Y229286D03*
X269913Y231461D03*
X277882Y231786D03*
X286129Y36971D03*
X296551Y103621D03*
X281575Y224712D03*
Y222212D03*
X296614Y293645D03*
Y290845D03*
Y288345D03*
X309106Y37543D03*
X299114Y290845D03*
Y288345D03*
Y293645D03*
X302966Y324139D03*
X310013Y316731D03*
X301158Y380307D03*
X301308Y395346D03*
X301393Y400039D03*
X322225Y198883D03*
Y201683D03*
X325650Y238589D03*
X328616Y236121D03*
X321549Y445315D03*
Y448115D03*
X323489Y471484D03*
Y466528D03*
Y480701D03*
Y485657D03*
Y515617D03*
Y510661D03*
Y529791D03*
Y524835D03*
Y565657D03*
Y560701D03*
Y574874D03*
Y579830D03*
Y589047D03*
Y594003D03*
Y603221D03*
Y608177D03*
X330905Y11806D03*
Y23806D03*
Y31806D03*
X341606Y213539D03*
X335052Y238689D03*
X343287Y238714D03*
X345050Y458334D03*
X333891Y473640D03*
Y487813D03*
Y478596D03*
Y492769D03*
Y522730D03*
Y517774D03*
Y531947D03*
Y536903D03*
Y572769D03*
Y567813D03*
Y586943D03*
Y581987D03*
Y596160D03*
Y601116D03*
Y610333D03*
Y615289D03*
X347450Y447486D03*
X353670Y488618D03*
Y491118D03*
Y493618D03*
Y496118D03*
X372275Y226461D03*
X361819Y231226D03*
Y228726D03*
Y223726D03*
Y226226D03*
X372275Y228961D03*
Y231461D03*
Y223661D03*
X364954Y450091D03*
X367564Y452740D03*
X365332Y490070D03*
Y487570D03*
X361887Y493758D03*
Y496258D03*
X377020Y782535D03*
X368491Y815092D03*
X368273Y928100D03*
X380196Y101701D03*
X380244Y229286D03*
X383937Y222212D03*
Y224712D03*
X380244Y231786D03*
X393837Y466409D03*
X393823Y487382D03*
X398913Y103621D03*
X398976Y293645D03*
X401476D03*
Y288345D03*
Y290845D03*
X398976Y288345D03*
Y290845D03*
X406843Y399161D03*
Y401661D03*
Y396661D03*
X405603Y668060D03*
X408103D03*
X403103D03*
X400603D03*
Y678060D03*
X405603D03*
X408103D03*
X403103D03*
X406967Y878764D03*
X406415Y874840D03*
X399285Y1081599D03*
X398915Y1097278D03*
X396415D03*
X401711Y1419771D03*
X406667D03*
X400911Y1537902D03*
X407048D03*
X400911Y1544424D03*
X407048Y1549936D03*
X400911D03*
X420050Y33425D03*
X418876Y401661D03*
Y396661D03*
Y399161D03*
X411754Y474513D03*
X424731Y508152D03*
Y513452D03*
Y515952D03*
X414275Y508217D03*
Y510717D03*
Y515717D03*
Y513217D03*
X424731Y510952D03*
X410603Y668060D03*
Y678060D03*
X425759Y869921D03*
Y872721D03*
Y875521D03*
Y867121D03*
Y878321D03*
X411214Y892109D03*
X413012Y1537902D03*
Y1544098D03*
X426196Y1534087D03*
X413012Y1549936D03*
X421616Y1549885D03*
X442704Y506427D03*
X427693Y506520D03*
X438353Y508685D03*
X427693Y509020D03*
X432700Y516277D03*
X429210Y784833D03*
X428759Y869921D03*
Y867121D03*
Y872721D03*
Y875521D03*
Y878321D03*
X432332Y892049D03*
Y897649D03*
Y894849D03*
Y900449D03*
X453544Y461961D03*
X451144Y472809D03*
X447836Y711199D03*
X451889Y1301067D03*
X456832Y1299121D03*
X451889Y1306023D03*
X472226Y198883D03*
Y201683D03*
X473658Y467215D03*
X471048Y464566D03*
X469495Y1011303D03*
Y1023303D03*
Y1017303D03*
X491607Y213539D03*
X478617Y236121D03*
X475651Y238589D03*
X485053Y238689D03*
X481495Y1011303D03*
X475495D03*
X481495Y1023303D03*
Y1017303D03*
X475495Y1023303D03*
X484800Y1302000D03*
X493288Y238714D03*
X522276Y223661D03*
Y226461D03*
Y228961D03*
Y231461D03*
X511820Y231226D03*
Y228726D03*
Y223726D03*
Y226226D03*
X521494Y572975D03*
X524475Y952290D03*
X509471Y981608D03*
X517374Y1287222D03*
X514363Y1287370D03*
X520548Y1287181D03*
X530197Y101701D03*
X530245Y229286D03*
X533938Y222212D03*
Y224712D03*
X530245Y231786D03*
X524708Y572842D03*
X532863Y585507D03*
X528270D03*
X528816Y579475D03*
X532908Y590190D03*
X528314Y590145D03*
X532770Y605443D03*
X528868Y873683D03*
X548914Y103621D03*
X551477Y288345D03*
Y290845D03*
X548977Y288345D03*
Y290845D03*
Y293645D03*
X551477D03*
X540770Y605443D03*
X574588Y201683D03*
X568362Y1008262D03*
Y1011762D03*
X574588Y198883D03*
X587415Y238689D03*
X580979Y236121D03*
X578013Y238589D03*
X577249Y965445D03*
X593969Y213539D03*
X595650Y238714D03*
X600272Y397335D03*
Y402291D03*
X597872Y425682D03*
Y416465D03*
Y411509D03*
Y439855D03*
Y430638D03*
Y444811D03*
Y468609D03*
Y473565D03*
Y487738D03*
Y482782D03*
Y517699D03*
Y531872D03*
Y526916D03*
X606142Y965665D03*
X614182Y223726D03*
Y226226D03*
Y231226D03*
Y228726D03*
X608274Y390223D03*
Y395179D03*
Y404396D03*
Y409352D03*
Y418569D03*
Y423525D03*
Y432743D03*
Y437699D03*
Y489895D03*
Y480677D03*
Y475721D03*
Y494851D03*
Y519855D03*
Y538984D03*
Y534028D03*
Y524811D03*
X632559Y101701D03*
X624638Y231461D03*
X636300Y222212D03*
Y224712D03*
X632607Y229286D03*
X624638Y223661D03*
Y226461D03*
Y228961D03*
X632607Y231786D03*
X651276Y103621D03*
X651339Y290845D03*
Y293645D03*
X653839D03*
Y288345D03*
Y290845D03*
X651339Y288345D03*
X660826Y570414D03*
Y567914D03*
Y565414D03*
Y575414D03*
Y572914D03*
X676950Y201683D03*
X680375Y238589D03*
X683341Y236121D03*
X696331Y213539D03*
X698012Y238714D03*
X689777Y238689D03*
X716544Y228726D03*
Y231226D03*
Y226226D03*
Y223726D03*
X704446Y760611D03*
X713425Y786029D03*
X734921Y101701D03*
X727000Y228961D03*
Y226461D03*
Y223661D03*
X734969Y229286D03*
X727000Y231461D03*
X734969Y231786D03*
X721218Y742131D03*
X720271Y782481D03*
X738662Y224712D03*
Y222212D03*
X744069Y746617D03*
X735576Y861780D03*
X753638Y103621D03*
X760407Y324494D03*
X767099Y316731D03*
X767310Y1599164D03*
X756358Y1616917D03*
X779312Y198883D03*
Y201683D03*
X782737Y238589D03*
X780575Y471484D03*
Y466528D03*
Y480701D03*
Y485657D03*
Y510661D03*
Y515617D03*
Y524835D03*
Y529791D03*
Y560701D03*
Y565657D03*
Y579830D03*
Y574874D03*
Y589047D03*
Y594003D03*
Y603221D03*
Y608177D03*
X798693Y213539D03*
X792139Y238689D03*
X785703Y236121D03*
X790977Y473640D03*
Y487813D03*
Y478596D03*
Y492769D03*
Y517774D03*
Y522730D03*
Y531947D03*
Y536903D03*
Y567813D03*
Y572769D03*
Y581987D03*
Y586943D03*
Y601116D03*
Y596160D03*
Y615289D03*
Y610333D03*
X800374Y238714D03*
X804536Y441486D03*
X802136Y452334D03*
X810756Y491118D03*
Y488618D03*
Y483618D03*
Y486118D03*
X815492Y732917D03*
X829362Y231461D03*
Y228961D03*
Y226461D03*
Y223661D03*
X818906Y228726D03*
Y231226D03*
Y226226D03*
Y223726D03*
X829381Y348036D03*
X824650Y446740D03*
X822040Y444091D03*
X826262Y462326D03*
Y459326D03*
X818973Y491258D03*
Y488758D03*
X822418Y485070D03*
Y482570D03*
X823790Y713375D03*
X823843Y732109D03*
X819890Y736924D03*
X828423Y964731D03*
X837283Y101701D03*
X837331Y229286D03*
X841024Y224712D03*
Y222212D03*
X837331Y231786D03*
X839573Y325327D03*
X856000Y103621D03*
X858563Y293645D03*
Y290845D03*
X856063Y293645D03*
Y290845D03*
X858563Y288345D03*
X856063D03*
X854622Y359004D03*
X873885Y340892D03*
X873733Y357844D03*
X871382Y373971D03*
X875907Y486256D03*
X870137Y669461D03*
X875916Y808965D03*
X886026Y346584D03*
X896592Y362369D03*
Y366369D03*
Y370369D03*
X882907Y480350D03*
X892023Y570176D03*
X890959Y579788D03*
X890956Y588325D03*
X894015Y588253D03*
X895933Y618143D03*
X910076Y304843D03*
X905120D03*
X913206Y336489D03*
X910040Y353532D03*
X902169Y413002D03*
Y418002D03*
Y415502D03*
X913853Y561487D03*
X904393Y570176D03*
X908517D03*
X898815D03*
X898232Y588320D03*
X902635Y588305D03*
X906999Y588274D03*
X905313Y709259D03*
X905050Y720268D03*
X913716Y800815D03*
X899916D03*
X911053Y800510D03*
X901428Y1136426D03*
X904897Y1145169D03*
X902397D03*
X929978Y186854D03*
Y184054D03*
X917906Y321670D03*
X922629Y336609D03*
X922198Y342051D03*
X917858Y331453D03*
X927309Y357267D03*
X921389D03*
X915395D03*
Y363212D03*
X927309Y363239D03*
Y369210D03*
X921468D03*
X915395D03*
X927072Y386992D03*
X919072D03*
X923072D03*
X914202Y418002D03*
Y413002D03*
Y415502D03*
X916590Y800636D03*
X921790Y810965D03*
X926044Y1545370D03*
Y1542370D03*
X938125Y230891D03*
X942805Y223860D03*
X936369Y221292D03*
X940158Y245707D03*
X946064Y252998D03*
X941845Y278968D03*
X939606Y310521D03*
X939653Y317474D03*
X940924Y328959D03*
X936608Y326058D03*
X945120Y326441D03*
X930398Y342050D03*
X936453Y345336D03*
X945599Y345383D03*
X940972Y338238D03*
X943663Y355674D03*
X944900Y363700D03*
X938499Y362202D03*
X940600Y370600D03*
X939314Y707847D03*
X931244Y720471D03*
X936026Y730600D03*
X941916Y808965D03*
X949359Y198710D03*
X951040Y223885D03*
X956348Y356371D03*
X952170Y356131D03*
X958823Y362802D03*
X954888Y369513D03*
X948400Y370045D03*
X956035Y1545333D03*
X959035D03*
X953035D03*
X950035D03*
X959035Y1542333D03*
X956035D03*
X953035D03*
X950035D03*
X968906Y223726D03*
Y228726D03*
Y231226D03*
X979362Y223661D03*
X968906Y226226D03*
X973338Y345018D03*
X978581Y572975D03*
X971144Y908972D03*
X965405Y1136426D03*
X987283Y101701D03*
X987331Y229286D03*
X991024Y224712D03*
Y222212D03*
X979362Y231461D03*
Y228961D03*
Y226461D03*
X987331Y231786D03*
X992045Y366559D03*
X984045D03*
X988045D03*
X981795Y572842D03*
X985903Y579475D03*
X985357Y585507D03*
X989950D03*
X985401Y590145D03*
X989995Y590190D03*
X989857Y605443D03*
X983712Y722064D03*
X1006000Y103621D03*
X1008563Y293645D03*
X1006063D03*
Y290845D03*
Y288345D03*
X1008563Y290845D03*
Y288345D03*
X997857Y605443D03*
X1010606Y1547824D03*
X1010659Y1568771D03*
Y1565771D03*
X1010653Y1571669D03*
X1021451Y322879D03*
X1026032Y322906D03*
X1018238Y678647D03*
X1018155Y684132D03*
X1025116Y698332D03*
X1024932Y717856D03*
X1016320Y828481D03*
X1026340Y917761D03*
X1025448Y1008262D03*
Y1011762D03*
X1013606Y1547824D03*
X1016606D03*
X1019606D03*
X1013659Y1568771D03*
X1016659D03*
X1019659D03*
X1013659Y1565771D03*
X1016659D03*
X1019659D03*
X1013653Y1571669D03*
X1016653D03*
X1019653D03*
X1031674Y198883D03*
Y201683D03*
X1038065Y236121D03*
X1035099Y238589D03*
X1030184Y288709D03*
X1038068Y298789D03*
X1033112D03*
X1030753Y732213D03*
X1051055Y213539D03*
X1044501Y238689D03*
X1052736Y238714D03*
X1048695Y280161D03*
X1057359Y402291D03*
Y397335D03*
X1054959Y411509D03*
Y425682D03*
Y416465D03*
Y430638D03*
Y439855D03*
Y444811D03*
Y468609D03*
Y473565D03*
Y487738D03*
Y482782D03*
Y517699D03*
Y512743D03*
Y531872D03*
Y526916D03*
X1071268Y226226D03*
Y223726D03*
Y228726D03*
Y231226D03*
X1065361Y390223D03*
Y395179D03*
Y404396D03*
Y409352D03*
Y423525D03*
Y418569D03*
Y432743D03*
Y437699D03*
Y489895D03*
Y480677D03*
Y475721D03*
Y494851D03*
Y519855D03*
Y524811D03*
Y538984D03*
Y534028D03*
X1089645Y101701D03*
X1081724Y226461D03*
Y223661D03*
X1089693Y229286D03*
X1081724Y231461D03*
Y228961D03*
X1089693Y231786D03*
X1079863Y345660D03*
X1090747Y1617415D03*
X1108362Y103621D03*
X1093386Y224712D03*
Y222212D03*
X1108425Y293645D03*
Y290845D03*
Y288345D03*
X1096264Y1562285D03*
X1093713Y1585583D03*
X1110925Y293645D03*
Y290845D03*
Y288345D03*
X1117913Y565414D03*
Y567914D03*
Y570414D03*
Y572914D03*
Y575414D03*
X1122718Y598857D03*
X1121191Y612555D03*
X1120512Y617332D03*
X1121022Y607750D03*
X1134036Y198883D03*
Y201683D03*
X1137461Y238589D03*
X1140427Y236121D03*
X1138166Y534759D03*
X1153417Y213539D03*
X1146863Y238689D03*
X1155098Y238714D03*
X1149437Y728541D03*
X1152316Y746625D03*
X1173630Y226226D03*
Y223726D03*
Y228726D03*
Y231226D03*
X1161274Y550462D03*
X1170603Y715281D03*
X1163751Y719498D03*
X1168577Y733812D03*
X1169266Y800799D03*
X1184086Y231461D03*
Y228961D03*
Y226461D03*
Y223661D03*
X1176577Y885974D03*
X1188431Y936568D03*
X1192007Y101701D03*
X1192055Y229286D03*
X1195748Y224712D03*
Y222212D03*
X1192055Y231786D03*
X1192990Y914873D03*
X1195118Y936296D03*
X1210724Y103621D03*
X1213287Y293645D03*
Y290845D03*
Y288345D03*
X1210787Y293645D03*
Y290845D03*
Y288345D03*
X1217139Y324139D03*
X1222909Y-83456D03*
Y-78500D03*
Y-68500D03*
Y-73456D03*
X1228265Y-44406D03*
Y-39450D03*
Y-29450D03*
Y-34406D03*
X1236398Y198883D03*
Y201683D03*
X1224186Y316731D03*
X1237662Y466528D03*
Y471484D03*
Y480701D03*
Y485657D03*
Y515617D03*
Y510661D03*
Y524835D03*
Y529791D03*
Y565657D03*
Y560701D03*
Y589047D03*
Y574874D03*
Y579830D03*
Y603221D03*
Y594003D03*
Y608177D03*
X1239823Y238589D03*
X1242789Y236121D03*
X1248064Y473640D03*
Y487813D03*
Y478596D03*
Y492769D03*
Y517774D03*
Y522730D03*
Y531947D03*
Y536903D03*
X1255779Y213539D03*
X1257460Y238714D03*
X1264481Y300223D03*
X1261623Y447486D03*
X1259223Y458334D03*
X1267843Y488618D03*
Y491118D03*
Y493618D03*
X1275992Y223726D03*
Y226226D03*
Y231226D03*
Y228726D03*
X1286448Y223661D03*
Y226461D03*
Y228961D03*
Y231461D03*
X1279127Y450091D03*
X1281737Y452740D03*
X1279505Y487570D03*
Y490070D03*
X1276060Y496258D03*
Y493758D03*
X1294369Y101701D03*
X1294417Y229286D03*
X1298110Y222212D03*
Y224712D03*
X1294417Y231786D03*
X1313086Y103621D03*
X1313149Y288345D03*
Y290845D03*
Y293645D03*
X1315649Y288345D03*
Y290845D03*
Y293645D03*
X1308010Y466409D03*
X1307996Y487382D03*
X1313459Y1081599D03*
X1310589Y1097278D03*
X1313089D03*
X1334223Y33425D03*
X1333049Y399268D03*
Y401768D03*
Y396768D03*
X1321016Y399161D03*
Y401661D03*
Y396661D03*
X1325927Y474513D03*
X1386399Y201683D03*
X1383669Y1011303D03*
Y1017303D03*
Y1023303D03*
X1386399Y198883D03*
X1399226Y238689D03*
X1392790Y236121D03*
X1389824Y238589D03*
X1395669Y1011303D03*
X1389669D03*
X1395669Y1017303D03*
Y1023303D03*
X1389669D03*
X1405780Y213539D03*
X1407461Y238714D03*
X1425993Y231226D03*
Y228726D03*
Y226226D03*
Y223726D03*
X1444370Y101701D03*
X1436449Y228961D03*
X1444418Y229286D03*
X1436449Y226461D03*
Y223661D03*
X1448111Y222212D03*
Y224712D03*
X1436449Y231461D03*
X1444418Y231786D03*
X1438882Y572842D03*
X1447037Y585507D03*
X1442444D03*
X1442990Y579475D03*
X1435668Y572975D03*
X1442488Y590145D03*
X1447082Y590190D03*
X1446944Y605443D03*
X1443041Y873683D03*
X1463087Y103621D03*
X1465650Y293645D03*
Y288345D03*
Y290845D03*
X1463150Y288345D03*
Y290845D03*
Y293645D03*
X1454944Y605443D03*
X1479409Y-83456D03*
Y-78500D03*
Y-68500D03*
Y-73456D03*
X1476822Y40780D03*
X1498621Y15043D03*
Y35043D03*
Y27043D03*
X1488761Y198883D03*
Y201683D03*
X1492186Y238589D03*
X1495152Y236121D03*
X1483813Y368516D03*
X1482535Y1008262D03*
Y1002453D03*
Y1011762D03*
X1514765Y-44536D03*
Y-39580D03*
Y-29580D03*
Y-34536D03*
X1508142Y213539D03*
X1509823Y238714D03*
X1501588Y238689D03*
X1514446Y402291D03*
Y397335D03*
X1512046Y411509D03*
Y425682D03*
Y416465D03*
Y439855D03*
Y430638D03*
Y444811D03*
Y468609D03*
Y473565D03*
Y487738D03*
Y482782D03*
Y517699D03*
Y512743D03*
Y531872D03*
Y526916D03*
X1528355Y228726D03*
Y223726D03*
Y226226D03*
Y231226D03*
X1515779Y351594D03*
X1522448Y390223D03*
Y395179D03*
Y404396D03*
Y409352D03*
Y423525D03*
Y418569D03*
Y437699D03*
Y432743D03*
Y489895D03*
Y480677D03*
Y475721D03*
Y494851D03*
Y519855D03*
Y538984D03*
Y534028D03*
Y524811D03*
X1546732Y101701D03*
X1538811Y226461D03*
Y228961D03*
Y231461D03*
X1546780Y229286D03*
X1538811Y223661D03*
X1546780Y231786D03*
X1550473Y222212D03*
Y224712D03*
X1565449Y103621D03*
X1565512Y288345D03*
X1568012Y293645D03*
Y290845D03*
Y288345D03*
X1565512Y293645D03*
Y290845D03*
X1575000Y565414D03*
Y567914D03*
Y570414D03*
Y572914D03*
Y575414D03*
X1579753Y599100D03*
X1578679Y613047D03*
X1578114Y607563D03*
X1591123Y198883D03*
Y201683D03*
X1594548Y238589D03*
X1610504Y213539D03*
X1597514Y236121D03*
X1612185Y238714D03*
X1603950Y238689D03*
X1641173Y231461D03*
X1630717Y223726D03*
Y226226D03*
Y231226D03*
Y228726D03*
X1641173Y223661D03*
Y226461D03*
Y228961D03*
X1649094Y101701D03*
X1649142Y229286D03*
X1652835Y222212D03*
Y224712D03*
X1649142Y231786D03*
X1667811Y103621D03*
X1670374Y290845D03*
Y288345D03*
X1667874Y290845D03*
Y288345D03*
X1670374Y293645D03*
X1667874D03*
X1674226Y324139D03*
X1693485Y198883D03*
Y201683D03*
X1681273Y316731D03*
X1699876Y236121D03*
X1696910Y238589D03*
X1706312Y238689D03*
X1694749Y466528D03*
Y471484D03*
X1705151Y473640D03*
Y487813D03*
Y478596D03*
X1694749Y480701D03*
Y485657D03*
X1705151Y492769D03*
Y517774D03*
Y522730D03*
X1694749Y510661D03*
Y515617D03*
X1705151Y536903D03*
Y531947D03*
X1694749Y524835D03*
Y529791D03*
X1705151Y572769D03*
Y567813D03*
X1694749Y565657D03*
Y560701D03*
Y579830D03*
X1705151Y586943D03*
Y581987D03*
X1694749Y589047D03*
Y574874D03*
Y603221D03*
X1705151Y601116D03*
Y596160D03*
X1694749Y594003D03*
X1705151Y615289D03*
X1694749Y608177D03*
X1705151Y610333D03*
X1712866Y213539D03*
X1714547Y238714D03*
X1718710Y447486D03*
X1716310Y458334D03*
X1724930Y491118D03*
Y488618D03*
Y493618D03*
Y496118D03*
X1733909Y-83456D03*
Y-78500D03*
Y-68500D03*
Y-73456D03*
X1733079Y223726D03*
Y226226D03*
Y231226D03*
Y228726D03*
X1743535Y223661D03*
X1738824Y452740D03*
X1736214Y450091D03*
X1736592Y487570D03*
Y490070D03*
X1733147Y493758D03*
Y496258D03*
X1751456Y101701D03*
X1743535Y226461D03*
X1755197Y224712D03*
X1743535Y228961D03*
Y231461D03*
X1751504Y229286D03*
X1755197Y222212D03*
X1751504Y231786D03*
X1770173Y103621D03*
X1772736Y293645D03*
X1770236D03*
Y290845D03*
Y288345D03*
X1772736Y290845D03*
Y288345D03*
X1765097Y466409D03*
X1765083Y487382D03*
X1772768Y818696D03*
X1790136Y399161D03*
Y401661D03*
Y396661D03*
X1778103Y399161D03*
Y401661D03*
Y396661D03*
X1783014Y474513D03*
X1778801Y836469D03*
X1786256Y927626D03*
X1784306Y924601D03*
X1786256Y930626D03*
X1799265Y-44666D03*
Y-39710D03*
Y-29710D03*
Y-34666D03*
X1791302Y829031D03*
X1816385Y1136912D03*
X1813885D03*
Y1144912D03*
X1816385D03*
G54D20*
X51043Y60709D03*
Y150197D03*
X153405Y60709D03*
Y150197D03*
X255767Y60709D03*
Y150197D03*
X279360Y368760D03*
Y421555D03*
Y501752D03*
Y550020D03*
Y636752D03*
X358129Y60709D03*
Y150197D03*
X508130Y60709D03*
Y150197D03*
X610492Y60709D03*
Y150197D03*
X712854Y60709D03*
Y150197D03*
X736446Y368760D03*
Y421555D03*
Y501752D03*
Y550020D03*
Y636752D03*
X815216Y60709D03*
Y150197D03*
X965216Y60709D03*
Y150197D03*
X1067578Y60709D03*
Y150197D03*
X1169940Y60709D03*
Y150197D03*
X1193533Y368760D03*
Y421555D03*
Y501752D03*
Y550020D03*
Y636752D03*
X1272302Y60709D03*
Y150197D03*
X1422303Y60709D03*
Y150197D03*
X1524665Y60709D03*
Y150197D03*
X1627027Y60709D03*
Y150197D03*
X1650620Y368760D03*
Y421555D03*
Y501752D03*
Y550020D03*
Y636752D03*
X1729389Y60709D03*
Y150197D03*
G54D49*
X843012Y1592787D03*
Y1602787D03*
Y1612787D03*
Y1622787D03*
X853012Y1592787D03*
Y1602787D03*
Y1612787D03*
Y1622787D03*
X878012Y1592787D03*
Y1602787D03*
Y1612787D03*
Y1622787D03*
X888012Y1592787D03*
Y1602787D03*
Y1612787D03*
Y1622787D03*
X913012Y1592787D03*
Y1602787D03*
Y1612787D03*
Y1622787D03*
X923012Y1592787D03*
Y1602787D03*
Y1612787D03*
Y1622787D03*
X948012Y1592787D03*
Y1602787D03*
Y1612787D03*
Y1622787D03*
X958012Y1592787D03*
Y1602787D03*
Y1612787D03*
Y1622787D03*
X983012Y1592787D03*
X993012D03*
X983012Y1602787D03*
Y1612787D03*
X993012Y1602787D03*
Y1612787D03*
X983012Y1622787D03*
X993012D03*
X1018012Y1592787D03*
X1028012D03*
X1018012Y1602787D03*
Y1612787D03*
X1028012Y1602787D03*
Y1612787D03*
X1018012Y1622787D03*
X1028012D03*
G54D12*
X3035Y1578036D03*
X3017Y1639466D03*
X14751Y62381D03*
X12601Y92110D03*
X9364Y107501D03*
X16728Y107910D03*
X12652Y116894D03*
X13615Y153263D03*
X10966Y155873D03*
Y152873D03*
X12709Y175777D03*
X9745Y245784D03*
X19075Y278429D03*
X7036Y268371D03*
X14252Y1121333D03*
X11552D03*
X16752D03*
X8952D03*
X14152Y1111633D03*
X11452D03*
X8852D03*
X16652D03*
X14252Y1130333D03*
X16752D03*
X14306Y1138705D03*
X16806D03*
X20079Y1429347D03*
X12327Y1519202D03*
X11995Y1535134D03*
X6567Y1554215D03*
X14375Y1553121D03*
X18409Y1554202D03*
X12000Y1644980D03*
X33288Y109410D03*
Y116497D03*
X30788D03*
X25988D03*
X22439Y106495D03*
X30788Y123584D03*
X33288Y123583D03*
X25988Y123584D03*
X33288Y130670D03*
X30788D03*
X25988D03*
X30788Y137757D03*
X25988D03*
X29201Y151651D03*
X26201D03*
X20709Y175777D03*
X28740Y247292D03*
X21449Y253198D03*
X28740Y267292D03*
X21386Y273198D03*
X23479Y295619D03*
X32452Y581222D03*
X29652D03*
X35252D03*
Y591215D03*
X29652D03*
X32452D03*
X34254Y611091D03*
X29451Y633560D03*
X30369Y663048D03*
X27854Y671553D03*
X30414Y671508D03*
X26596Y874520D03*
X26844Y920354D03*
X24132Y958151D03*
X25371Y980696D03*
X34314Y1215403D03*
X22284Y1464612D03*
X32079Y1525641D03*
X35237Y1532096D03*
X35850Y1556096D03*
X32000Y1644980D03*
X46450Y82984D03*
Y77784D03*
Y75184D03*
Y80384D03*
X48364Y92473D03*
X46450Y85584D03*
X37988Y109410D03*
Y102323D03*
Y116496D03*
Y130670D03*
Y123583D03*
X52437Y137756D03*
X37988D03*
X45984Y163264D03*
X37284Y285272D03*
X42690Y451466D03*
X48596Y458466D03*
X39643Y555194D03*
X36843D03*
X39643Y563194D03*
X36843D03*
X39643Y571194D03*
X36843D03*
X49265Y886660D03*
X52922Y900295D03*
X47916Y947622D03*
X50366Y1086981D03*
Y1082388D03*
X38200Y1089721D03*
X44365Y1086404D03*
X38216Y1093757D03*
X49500Y1199066D03*
X51197Y1218206D03*
X39452Y1250932D03*
X48195Y1511279D03*
X48079Y1525641D03*
Y1529641D03*
Y1521641D03*
X52048Y1556062D03*
X52000Y1644980D03*
X56098Y109410D03*
Y116496D03*
X55964Y103037D03*
X56098Y123583D03*
Y130670D03*
X68896Y226141D03*
X58279Y293796D03*
X66293Y285690D03*
X68793D03*
X66293Y288190D03*
X68793D03*
X60779Y293796D03*
X65759Y437508D03*
X61759D03*
X57759D03*
X54936Y449352D03*
X59522Y448874D03*
X68619Y447269D03*
X68497Y450201D03*
X64550Y504699D03*
X62050D03*
X59550D03*
X68236Y519458D03*
X61752Y516979D03*
X64252D03*
X59252D03*
X55318Y629362D03*
X53129Y627948D03*
X55307Y688473D03*
X66342Y880067D03*
X67316Y865869D03*
X64175Y897500D03*
X67461Y912983D03*
X63303Y912835D03*
X57178Y981386D03*
X69263Y1053152D03*
X55049Y1082343D03*
X55004Y1086937D03*
X58981Y1105100D03*
X56381D03*
X61581D03*
X64281D03*
X61681Y1114800D03*
X56481D03*
X59081D03*
X64381D03*
X57218Y1123867D03*
X55397Y1133688D03*
X57897D03*
X58250Y1220896D03*
X65940Y1209382D03*
X58250Y1227796D03*
Y1230296D03*
Y1237196D03*
Y1234696D03*
Y1223396D03*
X57185Y1480808D03*
X57144Y1491047D03*
X56114Y1556061D03*
X68743Y1583498D03*
X73381Y94017D03*
X69381D03*
X71422Y151540D03*
X75072Y191941D03*
X81572Y184619D03*
X74939Y188727D03*
X83552Y206760D03*
X71696Y226141D03*
X76766Y256535D03*
X84766D03*
X71593Y285690D03*
Y288190D03*
X75819Y290755D03*
X79819D03*
X83819D03*
X71826Y480705D03*
X75736Y519458D03*
X73236D03*
X70736D03*
X81740Y636250D03*
X69670Y633205D03*
Y636005D03*
X81740Y633450D03*
X69670Y638805D03*
X81740Y639050D03*
X74414Y681907D03*
X76991Y946134D03*
X84679Y1018368D03*
X70059Y1071656D03*
X69373Y1063389D03*
X70059Y1079656D03*
X80290Y1345691D03*
Y1350683D03*
X75334Y1345691D03*
Y1350683D03*
X80290Y1357603D03*
Y1362595D03*
X75334Y1357603D03*
Y1362595D03*
X80290Y1381801D03*
Y1369889D03*
Y1374881D03*
X75334Y1381801D03*
Y1374881D03*
Y1369889D03*
X80290Y1386793D03*
X75334D03*
X87000Y1597855D03*
X76005Y1580680D03*
X82433Y1580590D03*
X72000Y1644980D03*
X88080Y103603D03*
X87002Y146461D03*
X85904Y152367D03*
X87604Y180572D03*
X92287Y180527D03*
X96010Y192421D03*
X92242Y185121D03*
X87604Y185165D03*
X85796Y279208D03*
X89900Y281307D03*
X90257Y445506D03*
X88875Y840940D03*
X91581Y877859D03*
Y874859D03*
X87853Y899220D03*
X91128Y1006487D03*
X99836Y997860D03*
X95836D03*
X100594Y1035088D03*
X97247Y1030568D03*
X103124Y1165091D03*
X87574Y1345691D03*
Y1350683D03*
X99814D03*
Y1345691D03*
X92530D03*
Y1350683D03*
X87574Y1362595D03*
Y1357603D03*
X99814Y1362595D03*
Y1357603D03*
X92530Y1362595D03*
Y1357603D03*
X87574Y1374881D03*
Y1369795D03*
Y1381801D03*
X99814D03*
Y1374881D03*
Y1369889D03*
X92530Y1374881D03*
Y1369795D03*
Y1381801D03*
X87574Y1399079D03*
Y1393993D03*
Y1386793D03*
X99814Y1399079D03*
Y1394087D03*
Y1386793D03*
X92530Y1393993D03*
Y1399079D03*
Y1386793D03*
X87574Y1410991D03*
Y1405999D03*
X99814Y1410991D03*
Y1405999D03*
X92530Y1410991D03*
Y1405999D03*
X92000Y1644980D03*
X107364Y113394D03*
Y110394D03*
X110013Y110784D03*
X110152Y130898D03*
X117607Y133298D03*
X111754Y134579D03*
X107540Y172665D03*
Y180665D03*
X107572Y200864D03*
Y212864D03*
Y216864D03*
Y221864D03*
X109329Y252371D03*
X112474Y716315D03*
X114397Y727974D03*
X113601Y881266D03*
X107641Y865224D03*
X103836Y997860D03*
X111836D03*
X114770Y1009354D03*
X107836Y997860D03*
X115836D03*
X108933Y1102091D03*
X112433D03*
X103124D03*
X112433Y1114691D03*
X103124D03*
X108933D03*
Y1127291D03*
X112433D03*
X103124D03*
X112433Y1139891D03*
X103124Y1152491D03*
X108933D03*
X112433D03*
X108933Y1165091D03*
X112433D03*
X103184Y1177691D03*
X108933D03*
X112433D03*
X109415Y1202103D03*
X112795Y1223749D03*
X104770Y1350683D03*
Y1345691D03*
X112054D03*
Y1350683D03*
X117010Y1345691D03*
Y1350683D03*
X104770Y1362595D03*
Y1357603D03*
X112054Y1362595D03*
Y1357603D03*
X117010Y1362595D03*
Y1357603D03*
Y1369889D03*
Y1374881D03*
Y1381801D03*
X104770D03*
Y1374881D03*
Y1369889D03*
X112054D03*
Y1374881D03*
Y1381801D03*
X104770Y1399079D03*
Y1394087D03*
Y1386793D03*
X112054Y1399079D03*
Y1394087D03*
Y1386793D03*
X117010Y1394087D03*
Y1399079D03*
Y1386793D03*
X104770Y1410991D03*
Y1405999D03*
X112054Y1410991D03*
Y1405999D03*
X117010Y1410991D03*
Y1405999D03*
X107669Y1456451D03*
Y1465913D03*
X116330Y1465513D03*
X107669Y1461182D03*
X116330Y1460782D03*
X107669Y1481267D03*
X116330Y1480867D03*
X107669Y1476536D03*
X116330Y1476136D03*
Y1470244D03*
X107669Y1471805D03*
X116330Y1491490D03*
Y1485598D03*
X107669Y1487159D03*
Y1496621D03*
X116330Y1496221D03*
X107669Y1491890D03*
X116330Y1506845D03*
Y1500952D03*
X107669Y1502514D03*
X116330Y1511576D03*
X107669Y1511976D03*
Y1507245D03*
X116330Y1516307D03*
X107669Y1563544D03*
X116330Y1563144D03*
X107669Y1558813D03*
Y1568275D03*
X116330Y1567875D03*
X107669Y1578898D03*
X116330Y1578498D03*
Y1572606D03*
X107669Y1574167D03*
Y1583629D03*
X116330Y1583229D03*
X107669Y1594253D03*
X116330Y1593853D03*
Y1587960D03*
X107669Y1589522D03*
Y1609607D03*
X116330Y1609207D03*
X107669Y1598984D03*
X116330Y1598584D03*
Y1603315D03*
X107669Y1604876D03*
X116330Y1613938D03*
Y1618669D03*
X107669Y1614338D03*
X112000Y1644980D03*
X128350Y116497D03*
X133150D03*
X124606Y106495D03*
X125599Y109172D03*
X122599D03*
X133150Y123584D03*
X128350D03*
X133150Y130670D03*
X128350D03*
Y137757D03*
X133150D03*
X126246Y141228D03*
X124340Y146012D03*
X129134Y150847D03*
X131102Y247292D03*
X123811Y253198D03*
X125125Y362403D03*
X118122Y747565D03*
X122887Y884000D03*
X127067Y891495D03*
X124079Y1009354D03*
X119836Y997860D03*
X131836D03*
X127836D03*
X123836D03*
X120579Y1009354D03*
Y1021954D03*
X124079D03*
X133870Y1105091D03*
Y1117691D03*
Y1130291D03*
Y1142891D03*
Y1155491D03*
Y1168091D03*
X121211Y1215195D03*
X126937Y1209607D03*
X124294Y1350683D03*
Y1345691D03*
X129250Y1350683D03*
Y1345691D03*
X124294Y1362595D03*
Y1357603D03*
X129250D03*
Y1362595D03*
X124294Y1374881D03*
Y1369889D03*
Y1381801D03*
X129250Y1374881D03*
Y1369889D03*
Y1381801D03*
X124294Y1394087D03*
Y1399079D03*
Y1386793D03*
X129250Y1394087D03*
Y1399079D03*
Y1386793D03*
X124294Y1405999D03*
Y1410991D03*
X129250Y1405999D03*
Y1410991D03*
X124992Y1465913D03*
Y1456451D03*
Y1461182D03*
X133653Y1465513D03*
Y1460782D03*
X124992Y1471805D03*
Y1476536D03*
Y1481267D03*
X133653Y1476136D03*
Y1470244D03*
Y1480867D03*
Y1496221D03*
X124992Y1487159D03*
Y1491890D03*
Y1496621D03*
X133653Y1491490D03*
Y1485598D03*
Y1506845D03*
Y1500952D03*
Y1511576D03*
X124992Y1511976D03*
Y1507245D03*
Y1502514D03*
X133653Y1516307D03*
X124992Y1558813D03*
Y1563544D03*
X133653Y1563144D03*
Y1567875D03*
X124992Y1574167D03*
Y1578898D03*
X133653Y1578498D03*
Y1572606D03*
X124992Y1568275D03*
Y1589522D03*
Y1594253D03*
X133653Y1593853D03*
Y1587960D03*
X124992Y1583629D03*
X133653Y1583229D03*
X124992Y1609607D03*
Y1604876D03*
Y1598984D03*
X133653Y1609207D03*
Y1598584D03*
Y1603315D03*
X124992Y1614338D03*
X133653Y1613938D03*
Y1618669D03*
X132000Y1644980D03*
X148812Y80384D03*
Y82984D03*
Y75184D03*
Y77784D03*
Y85584D03*
X135650Y109410D03*
X140350Y116496D03*
Y109410D03*
Y102323D03*
X135650Y116497D03*
Y123583D03*
Y130670D03*
X140350D03*
Y123583D03*
Y137756D03*
X136604Y450750D03*
X140703Y536382D03*
X145670Y597580D03*
X147893Y599588D03*
X147155Y589556D03*
X147094Y592354D03*
X145609Y594668D03*
X147896Y596095D03*
X147925Y615600D03*
X147893Y607588D03*
X139836Y997860D03*
X147836D03*
X143836D03*
X135836D03*
X145516Y1024954D03*
Y1012354D03*
X148534Y1046476D03*
X134457Y1180654D03*
X141490Y1345691D03*
Y1350683D03*
X136534D03*
Y1345691D03*
X148774Y1350683D03*
Y1345691D03*
X141490Y1357603D03*
Y1362595D03*
X136534D03*
Y1357603D03*
X148774D03*
Y1362595D03*
X141490Y1369889D03*
Y1374881D03*
Y1381801D03*
X136534Y1369889D03*
Y1381801D03*
Y1374881D03*
X148774Y1369889D03*
Y1381801D03*
Y1374881D03*
X141490Y1386793D03*
Y1394087D03*
Y1399079D03*
X136534D03*
Y1394087D03*
Y1386793D03*
X148774Y1394087D03*
Y1399079D03*
Y1386793D03*
X141490Y1405999D03*
Y1410991D03*
X136534D03*
Y1405999D03*
X148774D03*
Y1410991D03*
X142315Y1456451D03*
Y1461182D03*
Y1465913D03*
Y1471805D03*
Y1476536D03*
Y1481267D03*
Y1487159D03*
Y1491890D03*
Y1496621D03*
Y1507245D03*
Y1502514D03*
Y1511976D03*
Y1558813D03*
Y1563544D03*
Y1574167D03*
Y1578898D03*
Y1568275D03*
Y1589522D03*
Y1594253D03*
Y1583629D03*
Y1609607D03*
Y1604876D03*
Y1598984D03*
Y1614338D03*
X151366Y92849D03*
X158460Y116496D03*
X158326Y103037D03*
X158460Y109410D03*
Y130670D03*
Y123583D03*
X155051Y137756D03*
X163141Y293796D03*
X160641D03*
X166528Y312392D03*
X157375Y555234D03*
X157090Y562003D03*
X152386Y634946D03*
X151836Y997860D03*
X159836D03*
X164028Y1041468D03*
X155513Y1065148D03*
X161014Y1345691D03*
Y1350683D03*
X153730Y1345691D03*
Y1350683D03*
X165970Y1345691D03*
Y1350683D03*
X161014Y1362595D03*
Y1357603D03*
X153730Y1362595D03*
Y1357603D03*
X165970Y1362595D03*
Y1357603D03*
X161014Y1381801D03*
Y1369889D03*
Y1374881D03*
X153730Y1369889D03*
Y1381801D03*
Y1374881D03*
X165970D03*
Y1381801D03*
Y1369889D03*
X161014Y1394087D03*
Y1386793D03*
X153730Y1394087D03*
Y1386793D03*
X165970Y1394087D03*
Y1386793D03*
X161014Y1399079D03*
X153730D03*
X165970D03*
X161014Y1410991D03*
Y1405999D03*
X153730D03*
Y1410991D03*
X165970D03*
Y1405999D03*
X159637Y1461182D03*
X150976Y1465513D03*
Y1460782D03*
X159637Y1465913D03*
Y1456451D03*
X150976Y1476136D03*
Y1470244D03*
Y1480867D03*
X159637Y1471805D03*
Y1476536D03*
Y1481267D03*
Y1496621D03*
X150976Y1491490D03*
Y1485598D03*
Y1496221D03*
X159637Y1487159D03*
Y1491890D03*
X150976Y1500952D03*
Y1511576D03*
X159637Y1507245D03*
Y1502514D03*
Y1511976D03*
X150976Y1506845D03*
Y1516307D03*
X159637Y1558813D03*
Y1563544D03*
X150976Y1563144D03*
X159637Y1578898D03*
X150976Y1567875D03*
Y1578498D03*
Y1572606D03*
X159637Y1568275D03*
Y1574167D03*
X150976Y1583229D03*
Y1593853D03*
Y1587960D03*
X159637Y1583629D03*
Y1589522D03*
Y1594253D03*
X150976Y1609207D03*
Y1598584D03*
Y1603315D03*
X159637Y1609607D03*
Y1604876D03*
Y1598984D03*
X150976Y1613938D03*
Y1618669D03*
X159637Y1614338D03*
X152000Y1644980D03*
X179743Y94017D03*
X175743D03*
X171743D03*
X175871Y110445D03*
X180863Y115401D03*
Y110445D03*
X175871Y115401D03*
X180863Y129574D03*
Y124618D03*
X175871Y129574D03*
Y124618D03*
X173784Y151540D03*
X177434Y191941D03*
X177301Y188727D03*
X171258Y226141D03*
X174058D03*
X179128Y256535D03*
X173955Y285690D03*
Y288190D03*
X171155Y285690D03*
X168655Y288190D03*
X171155D03*
X168655Y285690D03*
X182181Y290755D03*
X178181D03*
X177369Y389154D03*
Y396240D03*
Y403327D03*
Y410413D03*
Y417500D03*
Y424587D03*
Y431673D03*
Y438760D03*
Y445847D03*
Y467539D03*
Y474626D03*
Y488799D03*
Y481713D03*
Y495886D03*
Y511673D03*
Y518760D03*
Y525847D03*
Y532933D03*
Y540020D03*
Y547106D03*
X176650Y602197D03*
X177114Y595108D03*
X173254Y1345691D03*
Y1350683D03*
X178210Y1345691D03*
Y1350683D03*
X173254Y1362595D03*
Y1357603D03*
X178210D03*
Y1362595D03*
X173254Y1374881D03*
Y1369889D03*
Y1381801D03*
X178210Y1374881D03*
Y1369889D03*
Y1381801D03*
X173254Y1394087D03*
Y1386793D03*
X178210Y1394087D03*
Y1386793D03*
X173254Y1399079D03*
X178210D03*
X173254Y1405999D03*
Y1410991D03*
X178210Y1405999D03*
Y1410991D03*
X168299Y1465513D03*
Y1460782D03*
X176960Y1465914D03*
Y1456452D03*
Y1461183D03*
X168299Y1476136D03*
Y1470244D03*
Y1480867D03*
X176960Y1476537D03*
Y1471806D03*
Y1481268D03*
X168299Y1491490D03*
Y1485598D03*
Y1496221D03*
X176960Y1491891D03*
Y1487160D03*
Y1496622D03*
Y1507246D03*
Y1502515D03*
X168299Y1506845D03*
Y1500952D03*
Y1511576D03*
X176960Y1511977D03*
X168299Y1516307D03*
Y1563144D03*
X176960Y1563544D03*
Y1558813D03*
Y1568275D03*
X168299Y1578498D03*
Y1572606D03*
Y1567875D03*
Y1583229D03*
X176960Y1583629D03*
X168299Y1593853D03*
Y1587960D03*
X176960Y1594253D03*
Y1589522D03*
X168299Y1609207D03*
Y1598584D03*
Y1603315D03*
X176960Y1609607D03*
Y1598984D03*
Y1604876D03*
X168299Y1613938D03*
Y1618669D03*
X176960Y1614338D03*
X172000Y1644980D03*
X188820Y80140D03*
Y84140D03*
Y76140D03*
X183752Y94017D03*
X186273Y117557D03*
X191265D03*
X186273Y131731D03*
Y122513D03*
X191265D03*
Y131731D03*
X189364Y146461D03*
X186273Y136687D03*
X191265D03*
X188266Y152367D03*
X194649Y180527D03*
X189966Y180572D03*
X198372Y192421D03*
X189966Y185165D03*
X194604Y185121D03*
X183934Y184619D03*
X185914Y206760D03*
X187128Y256535D03*
X188158Y279208D03*
X192262Y281307D03*
X186181Y290755D03*
X191988Y389154D03*
X190518Y396240D03*
X194603Y422864D03*
X195295Y414823D03*
X194673Y429832D03*
X194278Y436447D03*
X196313Y447953D03*
X195480Y467539D03*
X194222Y472772D03*
X194956Y487711D03*
X195069Y479104D03*
X195480Y495886D03*
X190829Y516841D03*
X194080Y510565D03*
X185654Y552872D03*
X185776Y550123D03*
X185099Y562443D03*
X186867Y560675D03*
X187408Y572334D03*
X185640Y574102D03*
X193723Y656942D03*
X185494Y1345597D03*
Y1350683D03*
X190450Y1345597D03*
Y1350683D03*
X197734Y1345691D03*
Y1350683D03*
X185494Y1362595D03*
Y1357603D03*
X197734Y1362595D03*
Y1357603D03*
X190450Y1362595D03*
Y1357603D03*
X185494Y1374881D03*
Y1381801D03*
Y1369889D03*
X197734D03*
Y1381801D03*
Y1374881D03*
X190450Y1369889D03*
Y1374881D03*
Y1381801D03*
X185494Y1393993D03*
Y1386793D03*
X190450Y1393993D03*
Y1386793D03*
X197734Y1394087D03*
Y1386793D03*
X185494Y1399079D03*
X190450D03*
X197734D03*
X185494Y1410991D03*
Y1405999D03*
X190450Y1410991D03*
Y1405999D03*
X197734D03*
Y1410991D03*
X185622Y1465513D03*
Y1460782D03*
Y1480868D03*
Y1476137D03*
Y1470244D03*
Y1485599D03*
X192000Y1644980D03*
X211262Y60922D03*
X206398Y55513D03*
X208463Y96472D03*
X202195Y117261D03*
X209726Y113394D03*
Y110394D03*
X212375Y110784D03*
X211969Y133298D03*
X214116Y134579D03*
X209902Y172665D03*
Y180665D03*
X209934Y200864D03*
Y212864D03*
Y216864D03*
Y221864D03*
X211691Y252371D03*
X215380Y389153D03*
X210580D03*
X215380Y396240D03*
X208080Y403327D03*
X215380Y403326D03*
X210580D03*
X208080Y410413D03*
X210580D03*
X215380D03*
X208080Y396240D03*
X210580D03*
X208080Y417500D03*
X215380Y417499D03*
X210580D03*
X208080Y424586D03*
X210580D03*
X215380D03*
X208080Y431673D03*
Y438760D03*
X210580D03*
X215380D03*
Y431673D03*
X210580D03*
X208080Y445847D03*
X215380Y467539D03*
X210580D03*
X208080Y474626D03*
X210580D03*
X215380D03*
Y488799D03*
X208080D03*
X210580D03*
Y481712D03*
X208080D03*
X215380D03*
X208080Y495886D03*
X215380Y518760D03*
X210580D03*
X208080D03*
X210580Y511673D03*
X215380D03*
X210580Y532933D03*
X208080D03*
Y540020D03*
Y525846D03*
X210580D03*
X215380D03*
Y532933D03*
X212460Y560500D03*
X209429Y625300D03*
X202690Y1345597D03*
Y1350683D03*
Y1362595D03*
Y1357603D03*
Y1369889D03*
Y1381801D03*
Y1374881D03*
Y1394087D03*
Y1386793D03*
Y1399079D03*
Y1405999D03*
Y1410991D03*
X211473Y1446675D03*
X213296Y1438215D03*
X211473Y1451631D03*
Y1462631D03*
Y1457675D03*
X224961Y109172D03*
X226968Y106495D03*
X230712Y116497D03*
X227961Y109172D03*
X230712Y123584D03*
Y130670D03*
X219969Y133298D03*
X228608Y141228D03*
X230712Y137757D03*
X226702Y146012D03*
X231496Y150847D03*
X226173Y253198D03*
X228760Y316122D03*
X223925Y543925D03*
X224500Y555000D03*
X222646Y607542D03*
X217945Y1423924D03*
X217799Y1433684D03*
X216465Y1446675D03*
X222253Y1438483D03*
X216465Y1451631D03*
Y1462631D03*
Y1457675D03*
X229260Y1469587D03*
X218171Y1474460D03*
X224176Y1492816D03*
X223235Y1506770D03*
X222908Y1502028D03*
X226957Y1510442D03*
X216342Y1515642D03*
X217519Y1537172D03*
X242712Y116496D03*
Y109410D03*
Y102323D03*
X238012Y116497D03*
X235512D03*
X238012Y109410D03*
Y123583D03*
Y130670D03*
X235512D03*
X242712D03*
Y123583D03*
X235512Y123584D03*
Y137757D03*
X242712Y137756D03*
X233464Y247292D03*
X236349Y339428D03*
X247333Y599506D03*
X241967Y616063D03*
X243078Y636486D03*
X240249Y628328D03*
X241084Y638243D03*
X246583Y665140D03*
X241850Y678462D03*
X247600Y848500D03*
X240845Y1345691D03*
Y1350683D03*
X245801Y1345691D03*
Y1350683D03*
X240845Y1357603D03*
Y1362595D03*
X245801Y1357603D03*
Y1362595D03*
X240845Y1381801D03*
Y1374881D03*
Y1369889D03*
X245801Y1381801D03*
Y1374881D03*
Y1369889D03*
X240845Y1386793D03*
X245801D03*
X232675Y1466801D03*
X240466Y1503857D03*
X243268Y1501903D03*
X237700Y1531600D03*
X251174Y77784D03*
Y80384D03*
Y82984D03*
Y75184D03*
Y85584D03*
X253728Y92849D03*
X260688Y103037D03*
X260822Y116496D03*
Y109410D03*
Y130670D03*
Y123583D03*
X257413Y137756D03*
X263003Y293796D03*
X257226Y312081D03*
X265011Y403307D03*
X255000Y427017D03*
X254692Y431029D03*
X253758Y435029D03*
X254678Y449873D03*
X261605Y465492D03*
Y472579D03*
X259105D03*
X254305D03*
X261605Y486752D03*
X254305D03*
X259105Y479666D03*
X261605D03*
X254305D03*
X259105Y486752D03*
X254305Y493839D03*
X259105D03*
X261605Y516713D03*
X259105D03*
Y523800D03*
X261605D03*
X254305D03*
Y516713D03*
X261605Y509626D03*
Y530886D03*
X259105D03*
Y537973D03*
X254305Y530886D03*
Y537973D03*
Y566752D03*
X261605Y559665D03*
Y566752D03*
X259105D03*
X261605Y588012D03*
X259105Y588013D03*
X254305Y573839D03*
X261605D03*
X259105D03*
X261605Y580926D03*
X259105D03*
X254305D03*
Y588013D03*
X259105Y602186D03*
X254305D03*
Y595099D03*
X259105D03*
X261605D03*
Y602185D03*
X254305Y609272D03*
X259105D03*
X261605D03*
X259105Y616359D03*
X254305D03*
X248984Y638125D03*
X258867Y680499D03*
X258041Y1350683D03*
Y1345691D03*
X253085Y1350683D03*
Y1345691D03*
X258041Y1362595D03*
X253085D03*
X258041Y1357603D03*
X253085D03*
X258041Y1381801D03*
Y1369795D03*
Y1374881D03*
X253085Y1381801D03*
Y1369795D03*
Y1374881D03*
Y1393993D03*
Y1399079D03*
X258041Y1386793D03*
Y1399079D03*
Y1393993D03*
X253085Y1386793D03*
X258041Y1405999D03*
Y1410991D03*
X253085Y1405999D03*
Y1410991D03*
X248042Y1532900D03*
X274105Y94017D03*
X278105D03*
X278233Y115401D03*
Y110445D03*
Y129574D03*
Y124618D03*
X276146Y151540D03*
X279796Y191941D03*
X279663Y188727D03*
X276420Y226141D03*
X273620D03*
X276317Y288190D03*
X273517Y285690D03*
X271017Y288190D03*
X273517D03*
X271017Y285690D03*
X265503Y293796D03*
X276317Y285690D03*
X274425Y390500D03*
X265011Y410394D03*
X266405Y451319D03*
Y458406D03*
Y465492D03*
X266229Y462264D03*
X266405Y472579D03*
Y479665D03*
Y486752D03*
Y493839D03*
Y523799D03*
Y516713D03*
Y509626D03*
Y530886D03*
Y537973D03*
Y566752D03*
Y559665D03*
Y580926D03*
Y588012D03*
Y573839D03*
Y602185D03*
Y595099D03*
Y609272D03*
Y616358D03*
X269700Y884600D03*
X269900Y914200D03*
X270100Y946500D03*
X277565Y1350683D03*
Y1345691D03*
X265325D03*
Y1350683D03*
X270281Y1345691D03*
Y1350683D03*
X277565Y1362595D03*
X265325D03*
X270281D03*
X277565Y1357603D03*
X265325D03*
X270281D03*
X277565Y1381801D03*
Y1374881D03*
Y1369889D03*
X265325D03*
Y1374881D03*
Y1381801D03*
X270281Y1369889D03*
Y1374881D03*
Y1381801D03*
X277565Y1386793D03*
Y1394087D03*
Y1399079D03*
X265325Y1394087D03*
Y1399079D03*
Y1386793D03*
X270281Y1399079D03*
Y1394087D03*
Y1386793D03*
X265325Y1405999D03*
Y1410991D03*
X270281Y1405999D03*
Y1410991D03*
X277565Y1405999D03*
Y1410991D03*
X272000Y1644980D03*
X291182Y84140D03*
Y80140D03*
Y76140D03*
X282105Y94017D03*
X286114D03*
X288635Y117557D03*
X283225Y115401D03*
Y110445D03*
X293627Y117557D03*
X288635Y131731D03*
Y122513D03*
X283225Y129574D03*
Y124618D03*
X293627Y122513D03*
Y131731D03*
X291726Y146461D03*
X293627Y136687D03*
X288635D03*
X290628Y152367D03*
X292328Y180572D03*
Y185165D03*
X286296Y184619D03*
X288276Y206760D03*
X281490Y256535D03*
X289490D03*
X290520Y279208D03*
X294624Y281307D03*
X284543Y290755D03*
X280543D03*
X288543D03*
X284075Y381500D03*
X284482Y460250D03*
X284516Y465492D03*
X282247Y470136D03*
X284516Y472579D03*
Y479665D03*
Y486752D03*
Y493839D03*
Y516713D03*
Y509626D03*
X283377Y532756D03*
X283456Y525483D03*
X280976Y537973D03*
X284516Y559665D03*
Y566752D03*
X284366Y579978D03*
X284516Y573839D03*
X284580Y608117D03*
X282521Y1345691D03*
X289805Y1350683D03*
Y1345691D03*
X294761Y1350683D03*
Y1345691D03*
X282521Y1350683D03*
X289805Y1362595D03*
X294761D03*
X282521D03*
X289805Y1357603D03*
X294761D03*
X282521D03*
X289805Y1374881D03*
Y1369889D03*
Y1381801D03*
X294761Y1374881D03*
Y1369889D03*
Y1381801D03*
X282521D03*
Y1374881D03*
Y1369889D03*
X289805Y1394087D03*
Y1399079D03*
Y1386793D03*
X294761Y1394087D03*
Y1399079D03*
Y1386793D03*
X282521D03*
Y1399079D03*
Y1394087D03*
X289805Y1405999D03*
Y1410991D03*
X294761Y1405999D03*
Y1410991D03*
X282521Y1405999D03*
Y1410991D03*
X280897Y1465913D03*
X289558Y1465513D03*
X280897Y1461182D03*
X289558Y1460782D03*
X280897Y1456451D03*
X289558Y1480867D03*
X280897Y1476536D03*
X289558Y1476136D03*
Y1470244D03*
X280897Y1471805D03*
Y1481267D03*
Y1491890D03*
X289558Y1491490D03*
Y1485598D03*
X280897Y1487159D03*
Y1496621D03*
X289558Y1496221D03*
X280897Y1507245D03*
X289558Y1506845D03*
Y1500952D03*
X280897Y1502514D03*
X289558Y1511576D03*
X280897Y1511976D03*
X289558Y1516307D03*
X280897Y1563544D03*
X289558Y1563144D03*
X280897Y1558813D03*
Y1574167D03*
Y1568275D03*
X289558Y1567875D03*
X280897Y1578898D03*
X289558Y1578498D03*
Y1572606D03*
Y1593853D03*
Y1587960D03*
X280897Y1589522D03*
Y1583629D03*
X289558Y1583229D03*
X280897Y1594253D03*
Y1609607D03*
X289558Y1609207D03*
X280897Y1598984D03*
X289558Y1598584D03*
Y1603315D03*
X280897Y1604876D03*
Y1614338D03*
X289558Y1613938D03*
Y1618669D03*
X292000Y1644980D03*
X308760Y55513D03*
X310882Y96613D03*
X305953Y91951D03*
X312088Y113394D03*
X304557Y117261D03*
X297011Y180527D03*
X312264Y172665D03*
Y180665D03*
X299759Y190285D03*
X296966Y185121D03*
X312296Y212864D03*
Y200864D03*
Y221864D03*
Y216864D03*
X306812Y342319D03*
X309258Y389912D03*
Y393924D03*
Y385912D03*
Y409924D03*
Y405924D03*
Y401924D03*
X306673Y418838D03*
X298507Y445908D03*
X302457Y445787D03*
X302045Y1345691D03*
Y1350683D03*
X307001D03*
Y1345691D03*
X302045Y1362595D03*
X307001D03*
X302045Y1357603D03*
X307001D03*
X302045Y1374881D03*
Y1381801D03*
Y1369889D03*
X307001Y1374881D03*
Y1369889D03*
Y1381801D03*
X302045Y1386793D03*
Y1394087D03*
Y1399079D03*
X307001Y1386793D03*
Y1399079D03*
Y1394087D03*
X302045Y1405999D03*
Y1410991D03*
X307001Y1405999D03*
Y1410991D03*
X298220Y1465913D03*
Y1456451D03*
Y1461182D03*
X306881Y1465513D03*
Y1460782D03*
Y1470244D03*
Y1480867D03*
X298220Y1471805D03*
Y1476536D03*
Y1481267D03*
X306881Y1476136D03*
X298220Y1487159D03*
Y1491890D03*
Y1496621D03*
X306881Y1491490D03*
Y1485598D03*
Y1496221D03*
X298220Y1507245D03*
Y1502514D03*
X306881Y1506845D03*
Y1500952D03*
Y1511576D03*
X298220Y1511976D03*
X306881Y1516307D03*
X298220Y1558813D03*
Y1563544D03*
X306881Y1563144D03*
X298220Y1568275D03*
X306881Y1567875D03*
X298220Y1574167D03*
Y1578898D03*
X306881Y1578498D03*
Y1572606D03*
X298220Y1583629D03*
X306881Y1583229D03*
X298220Y1589522D03*
Y1594253D03*
X306881Y1593853D03*
Y1587960D03*
Y1598584D03*
Y1603315D03*
X298220Y1609607D03*
Y1604876D03*
Y1598984D03*
X306881Y1609207D03*
X298220Y1614338D03*
X306881Y1613938D03*
Y1618669D03*
X312000Y1644980D03*
X313624Y60922D03*
X327323Y109172D03*
X314737Y110784D03*
X314854Y130898D03*
X322331Y133298D03*
X329064Y146012D03*
X316478Y134579D03*
X328535Y253198D03*
X314053Y252371D03*
X323882Y303839D03*
X315904Y336324D03*
X320483Y353506D03*
X319241Y1350683D03*
Y1345691D03*
X314285D03*
Y1350683D03*
X326525Y1345691D03*
Y1350683D03*
X319241Y1362595D03*
X314285D03*
X326525D03*
X319241Y1357603D03*
X314285D03*
X326525D03*
X319241Y1374881D03*
Y1381801D03*
Y1369889D03*
X314285Y1374881D03*
Y1381801D03*
Y1369889D03*
X326525Y1381801D03*
Y1369889D03*
Y1374881D03*
X319241Y1386793D03*
Y1399079D03*
Y1394087D03*
X314285Y1386793D03*
Y1399079D03*
Y1394087D03*
X326525Y1399079D03*
Y1394087D03*
Y1386793D03*
X319241Y1410991D03*
Y1405999D03*
X314285Y1410991D03*
Y1405999D03*
X326525Y1410991D03*
Y1405999D03*
X315543Y1465913D03*
Y1456451D03*
Y1461182D03*
X324204Y1465513D03*
Y1460782D03*
Y1480867D03*
X315543Y1471805D03*
Y1476536D03*
Y1481267D03*
X324204Y1476136D03*
Y1470244D03*
X315543Y1487159D03*
Y1491890D03*
Y1496621D03*
X324204Y1491490D03*
Y1485598D03*
Y1496221D03*
Y1500952D03*
Y1511576D03*
X315543Y1507245D03*
Y1502514D03*
Y1511976D03*
X324204Y1506845D03*
Y1516307D03*
X315543Y1558813D03*
Y1563544D03*
X324204Y1563144D03*
X315543Y1574167D03*
Y1578898D03*
X324204Y1567875D03*
Y1578498D03*
Y1572606D03*
X315543Y1568275D03*
Y1583629D03*
Y1589522D03*
Y1594253D03*
X324204Y1583229D03*
Y1593853D03*
Y1587960D03*
X315543Y1609607D03*
Y1604876D03*
Y1598984D03*
X324204Y1609207D03*
Y1598584D03*
Y1603315D03*
X315543Y1614338D03*
X324204Y1613938D03*
Y1618669D03*
X329330Y106495D03*
X345074Y116496D03*
X337874Y116497D03*
X340374D03*
X345074Y109410D03*
Y102323D03*
X340374Y109410D03*
X333074Y116497D03*
X330323Y109172D03*
X337874Y130670D03*
X345074D03*
Y123583D03*
X340374D03*
X337874Y123584D03*
X333074D03*
Y130670D03*
X340374D03*
X333074Y137757D03*
X337874D03*
X330970Y141228D03*
X345074Y137756D03*
X333858Y150847D03*
X335826Y247292D03*
X338358Y554861D03*
X337564Y1018294D03*
X337629Y1186071D03*
X336901Y1196407D03*
X338765Y1350683D03*
Y1345691D03*
X331481D03*
Y1350683D03*
X343721Y1345691D03*
Y1350683D03*
X331481Y1362595D03*
X343721D03*
X338765D03*
X331481Y1357603D03*
X343721D03*
X338765D03*
X331481Y1374881D03*
Y1381801D03*
Y1369889D03*
X343721Y1381801D03*
Y1369889D03*
Y1374881D03*
X338765Y1381801D03*
Y1369889D03*
Y1374881D03*
X331481Y1399079D03*
Y1394087D03*
Y1386793D03*
X343721D03*
Y1394087D03*
Y1399079D03*
X338765Y1386793D03*
Y1394087D03*
Y1399079D03*
X331481Y1410991D03*
Y1405999D03*
X343721Y1410991D03*
Y1405999D03*
X338765Y1410991D03*
Y1405999D03*
X341527Y1460782D03*
X332865Y1465913D03*
Y1456451D03*
Y1461182D03*
X341527Y1465513D03*
Y1476136D03*
Y1470244D03*
Y1480867D03*
X332865Y1471805D03*
Y1476536D03*
Y1481267D03*
X341527Y1491490D03*
Y1485598D03*
Y1496221D03*
X332865Y1487159D03*
Y1491890D03*
Y1496621D03*
Y1511976D03*
X341527Y1506845D03*
Y1500952D03*
Y1511576D03*
X332865Y1507245D03*
Y1502514D03*
X341527Y1516307D03*
X332865Y1558813D03*
Y1563544D03*
X341527Y1563144D03*
X332865Y1578898D03*
X341527Y1567875D03*
Y1578498D03*
Y1572606D03*
X332865Y1568275D03*
Y1574167D03*
Y1583629D03*
Y1589522D03*
Y1594253D03*
X341527Y1583229D03*
Y1593853D03*
Y1587960D03*
X332865Y1598984D03*
X341527Y1609207D03*
Y1598584D03*
Y1603315D03*
X332865Y1609607D03*
Y1604876D03*
X341527Y1613938D03*
Y1618669D03*
X332865Y1614338D03*
X332000Y1644980D03*
X353536Y82984D03*
Y80384D03*
Y77784D03*
Y75184D03*
X356090Y92849D03*
X353536Y85584D03*
X359525Y137756D03*
X356423Y301288D03*
X348375Y322284D03*
X348968Y333138D03*
X359278Y491870D03*
X356778D03*
X358096Y867459D03*
X358086Y884616D03*
X357962Y898800D03*
X358024Y912085D03*
X358085Y923327D03*
X355929Y1132042D03*
X351563Y1132410D03*
X349700Y1148000D03*
X357947Y1159455D03*
X352536Y1160168D03*
X357297Y1192709D03*
X360659Y1209789D03*
X355961Y1350683D03*
X351005Y1345597D03*
Y1350683D03*
X355961Y1345597D03*
X351005Y1362595D03*
X355961D03*
X351005Y1357603D03*
X355961D03*
X351005Y1374881D03*
Y1381801D03*
Y1369889D03*
X355961Y1381801D03*
Y1374881D03*
Y1369889D03*
X351005Y1399079D03*
Y1393993D03*
Y1386793D03*
X355961D03*
Y1399079D03*
Y1393993D03*
X351005Y1410991D03*
Y1405999D03*
X355961D03*
Y1410991D03*
X350188Y1491891D03*
Y1487160D03*
Y1496622D03*
Y1507246D03*
Y1502515D03*
Y1511977D03*
X358850Y1511576D03*
Y1506845D03*
Y1516307D03*
X350188Y1563544D03*
Y1558813D03*
Y1568275D03*
Y1578898D03*
Y1574167D03*
Y1583629D03*
Y1594253D03*
Y1589522D03*
Y1604876D03*
Y1609607D03*
Y1598984D03*
Y1614338D03*
X352000Y1644980D03*
X376467Y94017D03*
X363050Y103037D03*
X363184Y116496D03*
Y109410D03*
Y130670D03*
Y123583D03*
X375982Y226141D03*
X378782D03*
X365365Y293796D03*
X367865D03*
X373379Y288190D03*
X375879Y285690D03*
X373379D03*
X375879Y288190D03*
X368057Y354184D03*
X364933Y374232D03*
X373264Y370010D03*
X366443Y472189D03*
X373504Y517954D03*
X375040Y932959D03*
X371424Y937185D03*
X367944Y946082D03*
X368657Y1146937D03*
X366133Y1162817D03*
X368661Y1182649D03*
X368917Y1195419D03*
X365029Y1214158D03*
X362735Y1211864D03*
X369839Y1218940D03*
X363245Y1345691D03*
Y1350683D03*
X368201Y1345691D03*
Y1350683D03*
X363245Y1362595D03*
X368201D03*
X363245Y1357603D03*
X368201D03*
X363245Y1369889D03*
Y1381801D03*
Y1374881D03*
X368201D03*
Y1381801D03*
Y1369889D03*
X363245Y1399079D03*
Y1394087D03*
Y1386793D03*
X368201D03*
Y1394087D03*
Y1399079D03*
X363245Y1405999D03*
Y1410991D03*
X368201D03*
Y1405999D03*
X372000Y1644980D03*
X393544Y76140D03*
Y84140D03*
Y80140D03*
X384467Y94017D03*
X388476D03*
X380467D03*
X390997Y117557D03*
X385587Y115401D03*
X380595D03*
X385587Y110445D03*
X380595D03*
X390997Y131731D03*
Y122513D03*
X385587Y129574D03*
X380595D03*
X385587Y124618D03*
X380595D03*
X390997Y136687D03*
X382158Y191941D03*
X388658Y184619D03*
X382025Y188727D03*
X390638Y206760D03*
X391852Y256535D03*
X383852D03*
X392882Y279208D03*
X378679Y285690D03*
Y288190D03*
X386905Y290755D03*
X382905D03*
X390905D03*
X392387Y337599D03*
Y342555D03*
X392444Y401949D03*
X393893Y413611D03*
X393833Y423944D03*
X393652Y482382D03*
X393746Y478382D03*
X388593Y664232D03*
X386350Y693559D03*
X391478Y690675D03*
X391614Y938651D03*
X381377Y1003008D03*
X381045Y1009444D03*
X391284Y1307238D03*
X394000Y1508100D03*
X382017Y1555700D03*
Y1547700D03*
Y1551700D03*
X392000Y1644980D03*
X408493Y117577D03*
X395989Y117557D03*
Y131731D03*
Y122513D03*
Y136687D03*
X399373Y180527D03*
X394690Y180572D03*
X403096Y192421D03*
X394690Y185165D03*
X399328Y185121D03*
X396986Y281307D03*
X409484Y314921D03*
X398951Y333711D03*
X397374Y344439D03*
X407493Y354142D03*
X394237Y370899D03*
X394944Y398949D03*
X399518Y402642D03*
X402018D03*
X396633Y423944D03*
X396693Y413611D03*
X399193D03*
X401693D03*
X401633Y423944D03*
X399133D03*
X409284Y741316D03*
X401121Y936686D03*
X409121Y939186D03*
X401121D03*
X409121Y936686D03*
X409231Y1123101D03*
X406105Y1139435D03*
X410131Y1129301D03*
X407631D03*
X409231Y1125801D03*
X406105Y1131935D03*
Y1134435D03*
Y1136935D03*
Y1141935D03*
Y1146935D03*
Y1144435D03*
X403263Y1152684D03*
X406319Y1204405D03*
Y1206905D03*
Y1211905D03*
Y1209405D03*
X397695Y1287071D03*
X399716Y1295198D03*
X408523Y1332967D03*
X404657D03*
X408937Y1351568D03*
X403981D03*
X401990Y1446807D03*
X399731Y1442755D03*
X397245Y1511640D03*
X404053Y1513673D03*
X397220Y1521207D03*
X409461Y1569560D03*
X405461D03*
X426147Y151540D03*
X414626Y180665D03*
Y172665D03*
X414658Y212864D03*
Y200864D03*
Y216864D03*
Y221864D03*
X422873Y309966D03*
X419955Y306966D03*
X414999D03*
X411984Y314921D03*
X421231Y338523D03*
Y331255D03*
Y345776D03*
X413432Y346797D03*
X416318Y367903D03*
X424479Y367859D03*
X418754Y468607D03*
X418226Y653288D03*
Y646480D03*
Y648980D03*
Y655788D03*
X425121Y936686D03*
Y939186D03*
X417121Y936686D03*
Y939186D03*
X417677Y1052215D03*
X425175Y1098767D03*
X417171Y1098887D03*
X419987Y1098518D03*
X419731Y1123101D03*
X417231D03*
X422631Y1125801D03*
X425131Y1129301D03*
X422631D03*
X420131D03*
X417631D03*
X415131D03*
X412631D03*
X420131Y1125801D03*
X417631D03*
X425131D03*
X422495Y1152713D03*
Y1155213D03*
X412095Y1152713D03*
Y1155213D03*
X422934Y1200821D03*
Y1198321D03*
X420619Y1204617D03*
Y1207117D03*
Y1209617D03*
Y1212117D03*
X411174Y1282776D03*
X418537Y1300197D03*
X423741Y1300115D03*
X413354Y1300197D03*
X425582Y1291743D03*
X423762Y1305298D03*
X413374D03*
X418558Y1310523D03*
X413395Y1310481D03*
X423721Y1310523D03*
X425283Y1373958D03*
X411147Y1474993D03*
X419818Y1474945D03*
X415241Y1492990D03*
X415095Y1502750D03*
X411353Y1519440D03*
X419467Y1519706D03*
X420279Y1525978D03*
X410626Y1525991D03*
X413461Y1569560D03*
X412000Y1644980D03*
X441727Y146461D03*
X440629Y152367D03*
X435703Y306966D03*
X430747D03*
X427829Y309966D03*
X428459Y331255D03*
X435793D03*
X428500Y345776D03*
X435793Y345738D03*
X430439Y358115D03*
X435702Y367813D03*
X430746D03*
X427782Y464026D03*
X438396Y511493D03*
X435834Y509580D03*
X431804Y536682D03*
Y539182D03*
X441832Y626193D03*
X433206Y1055498D03*
X430706D03*
Y1057998D03*
X433206D03*
Y1060498D03*
Y1062998D03*
X430706D03*
Y1060498D03*
X441359Y1123101D03*
X438233Y1139435D03*
X441359Y1125801D03*
X439759Y1129301D03*
X442259D03*
X429331Y1136935D03*
Y1134435D03*
Y1139435D03*
Y1131935D03*
X435733D03*
Y1134435D03*
Y1136935D03*
Y1139435D03*
X438233Y1131935D03*
Y1134435D03*
Y1136935D03*
X429331Y1141935D03*
X435733D03*
Y1146935D03*
Y1144435D03*
X438233Y1141935D03*
Y1146935D03*
Y1144435D03*
X437231Y1154902D03*
Y1152402D03*
X429331Y1146935D03*
Y1144435D03*
X433249Y1204405D03*
Y1209405D03*
Y1211905D03*
Y1206905D03*
X437991Y1286544D03*
X440896Y1311366D03*
X432485Y1325784D03*
X439624Y1345691D03*
Y1350683D03*
Y1357603D03*
Y1362595D03*
Y1381801D03*
Y1369889D03*
Y1374881D03*
X436002Y1382252D03*
X439624Y1386793D03*
X437675Y1550158D03*
X429784Y1548222D03*
X432000Y1644980D03*
X458454Y328963D03*
Y324007D03*
Y339755D03*
Y344711D03*
X453463Y370694D03*
X448092Y375770D03*
X443094Y491251D03*
X455104Y536582D03*
Y539082D03*
X447279Y633881D03*
X454815Y974622D03*
X448999Y994483D03*
X456210Y1004680D03*
X452319Y1000828D03*
X449731Y1000855D03*
X453710Y1018825D03*
X443091Y1022766D03*
Y1030266D03*
X450063Y1043140D03*
X449767Y1047047D03*
X457303Y1098767D03*
X452115Y1098518D03*
X446863Y1098428D03*
X449359Y1123101D03*
X451859D03*
X457259Y1129301D03*
X449759Y1125801D03*
X452259D03*
X444759Y1129301D03*
X447259D03*
X449759D03*
X452259D03*
X454759Y1125801D03*
X457259D03*
X454759Y1129301D03*
X443223Y1155213D03*
Y1152713D03*
X452623D03*
Y1155213D03*
X447549Y1204617D03*
X449864Y1198321D03*
Y1200821D03*
X447549Y1209617D03*
Y1207117D03*
Y1212117D03*
X454120Y1269498D03*
X456213Y1286776D03*
X451304Y1293045D03*
X456820Y1345691D03*
X451864D03*
Y1350683D03*
X456820D03*
X444580Y1345691D03*
Y1350683D03*
X456820Y1362595D03*
Y1357603D03*
X451864Y1362595D03*
Y1357603D03*
X444580D03*
Y1362595D03*
X456820Y1374881D03*
X451864D03*
X444580Y1369889D03*
X456820Y1369795D03*
X451864D03*
X444580Y1374881D03*
Y1381801D03*
X456820D03*
X451864D03*
X456820Y1399079D03*
X451864Y1393993D03*
Y1399079D03*
X456820Y1393993D03*
Y1386793D03*
X451864D03*
X444580D03*
X456820Y1405999D03*
X451864D03*
Y1410991D03*
X456820D03*
X454125Y1461182D03*
Y1465913D03*
Y1471805D03*
Y1481267D03*
Y1476536D03*
Y1491890D03*
Y1487159D03*
Y1496621D03*
Y1511976D03*
Y1507245D03*
Y1502514D03*
Y1558813D03*
Y1578898D03*
Y1568275D03*
Y1563544D03*
Y1574167D03*
Y1583629D03*
Y1589522D03*
Y1594253D03*
Y1609607D03*
Y1598984D03*
Y1604876D03*
Y1614338D03*
X452000Y1644980D03*
X464738Y110784D03*
X462089Y113394D03*
X472332Y133298D03*
X464332D03*
X466479Y134579D03*
X464054Y252371D03*
X461454Y336837D03*
Y331881D03*
Y347629D03*
Y352585D03*
X466375Y366365D03*
X470389Y389553D03*
X468558Y491669D03*
Y503669D03*
Y507669D03*
Y512669D03*
X462242Y809792D03*
X475032Y843252D03*
X474678Y857919D03*
X463134Y859203D03*
X460455Y867050D03*
X475046Y885952D03*
X467494Y924532D03*
X462427Y1030218D03*
X460277Y1090268D03*
Y1093068D03*
X474818Y1123101D03*
X469192Y1131935D03*
X474818Y1125801D03*
X473218Y1129301D03*
X461459Y1136935D03*
Y1134435D03*
Y1139435D03*
Y1131935D03*
X471692Y1139435D03*
Y1136935D03*
Y1134435D03*
Y1131935D03*
X469192Y1139435D03*
Y1136935D03*
Y1134435D03*
X471692Y1146935D03*
Y1141935D03*
X469192Y1144435D03*
Y1146935D03*
Y1141935D03*
X471692Y1144435D03*
X461459D03*
X462687Y1152684D03*
X468850D03*
X461459Y1141935D03*
Y1146935D03*
X463216Y1254164D03*
Y1250760D03*
Y1244055D03*
X461613Y1286776D03*
X469060Y1345691D03*
Y1350683D03*
X464104Y1345691D03*
Y1350683D03*
X469060Y1357603D03*
Y1362595D03*
X464104D03*
Y1357603D03*
Y1381801D03*
X469060D03*
X464104Y1369889D03*
X469060D03*
X464104Y1374881D03*
X469060D03*
Y1386793D03*
X464104D03*
X469060Y1399079D03*
X464104Y1394087D03*
X469060D03*
X464104Y1399079D03*
Y1405999D03*
X469060D03*
X464104Y1410991D03*
X469060D03*
X471448Y1461182D03*
X462786Y1460782D03*
X471448Y1465913D03*
X462786Y1465513D03*
X471448Y1481267D03*
X462786Y1480867D03*
X471448Y1471805D03*
Y1476536D03*
X462786Y1476136D03*
Y1470244D03*
X471448Y1496621D03*
X462786Y1496221D03*
X471448Y1491890D03*
X462786Y1491490D03*
Y1485598D03*
X471448Y1487159D03*
Y1511976D03*
Y1502514D03*
Y1507245D03*
X462786Y1511576D03*
Y1506845D03*
Y1500952D03*
Y1516307D03*
Y1563144D03*
X471448Y1558813D03*
X462786Y1578498D03*
X471448Y1574167D03*
Y1568275D03*
Y1563544D03*
X462786Y1567875D03*
Y1572606D03*
X471448Y1578898D03*
Y1594253D03*
X462786Y1593853D03*
X471448Y1589522D03*
Y1583629D03*
X462786Y1583229D03*
Y1587960D03*
X471448Y1598984D03*
X462786Y1609207D03*
Y1598584D03*
Y1603315D03*
X471448Y1609607D03*
Y1604876D03*
Y1614338D03*
X462786Y1613938D03*
Y1618669D03*
X472000Y1644980D03*
X480324Y109172D03*
X477324D03*
X479331Y106495D03*
X483075Y116497D03*
X487875D03*
X490375Y109410D03*
Y116497D03*
X483075Y130670D03*
X487875Y123584D03*
Y130670D03*
X490375Y123583D03*
Y130670D03*
X483075Y123584D03*
X479065Y146012D03*
X480971Y141228D03*
X483075Y137757D03*
X487875D03*
X483859Y150847D03*
X485827Y247292D03*
X478536Y253198D03*
X483242Y366481D03*
X483584Y375840D03*
X483736Y371266D03*
X483541Y380306D03*
X481724Y391589D03*
Y387089D03*
X488438Y425464D03*
X482532Y418464D03*
X482484Y444517D03*
X486738Y581222D03*
X489538D03*
Y591215D03*
X486738D03*
X491340Y611091D03*
X485005Y659771D03*
X491324Y667293D03*
X485303Y681841D03*
X486246Y804497D03*
X485824Y819787D03*
X481593Y826387D03*
X491453Y834546D03*
X491527Y843206D03*
X488469Y857013D03*
X481943Y924633D03*
X488388Y938903D03*
X483636Y952152D03*
X490143Y989521D03*
X476148Y1057998D03*
Y1055498D03*
X478648D03*
Y1057998D03*
X476148Y1060498D03*
Y1062998D03*
X478648D03*
Y1060498D03*
X490762Y1098767D03*
X485574Y1098518D03*
X480322Y1098428D03*
X485318Y1123101D03*
X482818D03*
X490718Y1129301D03*
X483218Y1125801D03*
X485718D03*
X475718Y1129301D03*
X478218D03*
X480718D03*
X483218D03*
X485718D03*
X488218Y1125801D03*
X490718D03*
X488218Y1129301D03*
X477682Y1152713D03*
Y1155213D03*
X488082D03*
Y1152713D03*
X479521Y1204405D03*
Y1206905D03*
Y1211905D03*
Y1209405D03*
X488584Y1345691D03*
Y1350683D03*
X481300Y1345691D03*
X476344D03*
X481300Y1350683D03*
X476344D03*
X488584Y1357603D03*
Y1362595D03*
X481300D03*
Y1357603D03*
X476344Y1362595D03*
Y1357603D03*
X488584Y1381801D03*
X481300D03*
X488584Y1374881D03*
Y1369889D03*
X481300D03*
Y1374881D03*
X476344Y1381801D03*
Y1369889D03*
Y1374881D03*
X488584Y1386793D03*
X481300D03*
Y1399079D03*
X476344Y1394087D03*
Y1399079D03*
X488584Y1394087D03*
X481300D03*
X488584Y1399079D03*
X476344Y1386793D03*
Y1410991D03*
X481300Y1405999D03*
X476344D03*
X488584D03*
Y1410991D03*
X481300D03*
X480109Y1460782D03*
Y1465513D03*
X488771Y1465913D03*
Y1461182D03*
X480109Y1476136D03*
Y1470244D03*
X488771Y1471805D03*
Y1476536D03*
Y1481267D03*
X480109Y1480867D03*
Y1496221D03*
X488771Y1487159D03*
Y1491890D03*
X480109Y1491490D03*
Y1485598D03*
X488771Y1496621D03*
Y1511976D03*
X480109Y1511576D03*
Y1506845D03*
Y1500952D03*
X488771Y1502514D03*
Y1507245D03*
X480109Y1516307D03*
X488771Y1558813D03*
X480109Y1563144D03*
X488771Y1578898D03*
X480109Y1578498D03*
X488771Y1574167D03*
Y1568275D03*
Y1563544D03*
X480109Y1567875D03*
Y1572606D03*
X488771Y1589522D03*
Y1583629D03*
X480109Y1583229D03*
Y1587960D03*
X488771Y1594253D03*
X480109Y1593853D03*
X488771Y1609607D03*
Y1604876D03*
Y1598984D03*
X480109Y1609207D03*
Y1598584D03*
Y1603315D03*
X488771Y1614338D03*
X480109Y1613938D03*
Y1618669D03*
X503537Y77784D03*
Y75184D03*
Y80384D03*
Y82984D03*
X506091Y92849D03*
X503537Y85584D03*
X495075Y116496D03*
Y102323D03*
Y109410D03*
Y130670D03*
Y123583D03*
Y137756D03*
X497424Y354559D03*
X492317Y376252D03*
X503682Y455466D03*
X497776Y448466D03*
X493929Y555194D03*
X496729D03*
X493929Y563194D03*
X496729D03*
X493929Y571194D03*
X496729D03*
X492338Y581222D03*
Y591215D03*
X494632Y654622D03*
X501618Y698355D03*
X499012Y699819D03*
X503311Y715652D03*
X500705Y705524D03*
X507546Y738539D03*
X505673Y767961D03*
X500717D03*
X504341Y812040D03*
X491655Y829173D03*
X506246Y824689D03*
X492799Y846488D03*
X503741Y846830D03*
X497467Y833027D03*
X499640Y861538D03*
X499595Y963963D03*
X493050Y976078D03*
X506566Y1000766D03*
Y1004766D03*
Y1016266D03*
Y1030766D03*
X505981Y1052487D03*
X506946Y1123101D03*
Y1125801D03*
X505346Y1129301D03*
X507846D03*
X503820Y1139435D03*
Y1136935D03*
Y1134435D03*
Y1131935D03*
X501320Y1139435D03*
Y1136935D03*
Y1134435D03*
Y1131935D03*
X494918Y1136935D03*
Y1134435D03*
Y1139435D03*
Y1131935D03*
X503820Y1144435D03*
Y1146935D03*
Y1141935D03*
X501320Y1144435D03*
Y1146935D03*
Y1141935D03*
X494918Y1146935D03*
Y1144435D03*
Y1141935D03*
X502562Y1152713D03*
Y1155213D03*
X506451Y1204405D03*
X493821Y1204617D03*
X496136Y1200821D03*
Y1198321D03*
X506451Y1206905D03*
Y1211905D03*
Y1209405D03*
X493821Y1207117D03*
Y1209617D03*
Y1212117D03*
X500824Y1350683D03*
Y1345691D03*
X505780Y1350683D03*
Y1345691D03*
X493540D03*
Y1350683D03*
X505780Y1362595D03*
Y1357603D03*
X500824Y1362595D03*
Y1357603D03*
X493540Y1362595D03*
Y1357603D03*
Y1381801D03*
Y1374881D03*
Y1369889D03*
X505780Y1381801D03*
Y1374881D03*
Y1369889D03*
X500824D03*
Y1381801D03*
Y1374881D03*
Y1394087D03*
X505780Y1399079D03*
X500824D03*
X505780Y1394087D03*
X493540Y1386793D03*
Y1394087D03*
Y1399079D03*
X505780Y1386793D03*
X500824D03*
X505780Y1410991D03*
X500824D03*
X505780Y1405999D03*
X500824D03*
X493540D03*
Y1410991D03*
X497432Y1465513D03*
X506093Y1465913D03*
X497432Y1460782D03*
X506093Y1461182D03*
X497432Y1480867D03*
X506093Y1481267D03*
X497432Y1476136D03*
Y1470244D03*
X506093Y1471805D03*
Y1476536D03*
X497432Y1496221D03*
Y1491490D03*
Y1485598D03*
X506093Y1487159D03*
Y1491890D03*
Y1496621D03*
Y1511976D03*
X497432Y1506845D03*
Y1500952D03*
X506093Y1502514D03*
Y1507245D03*
X497432Y1511576D03*
Y1516307D03*
Y1563144D03*
X506093Y1558813D03*
X497432Y1578498D03*
X506093Y1578898D03*
X497432Y1567875D03*
Y1572606D03*
X506093Y1574167D03*
Y1568275D03*
Y1563544D03*
X497432Y1587960D03*
X506093Y1589522D03*
Y1583629D03*
X497432Y1593853D03*
X506093Y1594253D03*
X497432Y1583229D03*
X506093Y1604876D03*
Y1598984D03*
X497432Y1609207D03*
X506093Y1609607D03*
X497432Y1598584D03*
Y1603315D03*
Y1613938D03*
Y1618669D03*
X506093Y1614338D03*
X492000Y1644980D03*
X513051Y103037D03*
X513185Y116496D03*
Y109410D03*
Y130670D03*
Y123583D03*
X509251Y137756D03*
X517866Y293796D03*
X515366D03*
X523380Y285690D03*
Y288190D03*
X511342Y311124D03*
X520845Y434508D03*
X516845D03*
X512845D03*
X514608Y445874D03*
X510022Y446352D03*
X523705Y444269D03*
X523583Y447201D03*
X521636Y504699D03*
X516636D03*
X519136D03*
X516338Y516979D03*
X521338D03*
X518838D03*
X512404Y629362D03*
X510215Y627948D03*
X511990Y686365D03*
X518001Y694940D03*
X522410Y694881D03*
X518067Y699378D03*
X518530Y703584D03*
X522628Y703884D03*
X508237Y723585D03*
X512502Y738539D03*
X516953Y738575D03*
X521909D03*
X520159Y758832D03*
X509063Y782867D03*
X517194Y773232D03*
X522316Y793574D03*
X509316Y793224D03*
X508130Y787488D03*
X521178Y814001D03*
X521565Y820931D03*
X520720Y846133D03*
X517832Y834558D03*
X508049Y877789D03*
X523272Y880067D03*
X509428Y888390D03*
X521115Y897500D03*
X511025Y911443D03*
X509673Y900295D03*
X516256Y939157D03*
X514886Y952189D03*
X519792Y1031271D03*
X517702Y1098518D03*
X512450Y1098428D03*
X522890Y1098767D03*
X514946Y1123101D03*
X517446D03*
X522846Y1129301D03*
X515346Y1125801D03*
X517846D03*
X510346Y1129301D03*
X512846D03*
X515346D03*
X517846D03*
X520346Y1125801D03*
X522846D03*
X520346Y1129301D03*
X518210Y1155213D03*
Y1152713D03*
X508810D03*
Y1155213D03*
X520751Y1204617D03*
X523066Y1200821D03*
Y1198321D03*
X520751Y1207117D03*
Y1209617D03*
Y1212117D03*
X513064Y1345691D03*
X518020Y1350683D03*
X513064D03*
X518020Y1345691D03*
Y1357603D03*
X513064Y1362595D03*
Y1357603D03*
X518020Y1362595D03*
X513064Y1369889D03*
Y1381801D03*
Y1374881D03*
X518020Y1369889D03*
Y1381801D03*
Y1374881D03*
Y1394087D03*
Y1399079D03*
X513064Y1394087D03*
Y1399079D03*
Y1386793D03*
X518020D03*
Y1405999D03*
Y1410991D03*
X513064D03*
Y1405999D03*
X514755Y1460782D03*
Y1465513D03*
Y1480867D03*
Y1476136D03*
Y1470244D03*
Y1491490D03*
Y1485598D03*
Y1496221D03*
Y1511576D03*
Y1506845D03*
Y1500952D03*
Y1516307D03*
Y1563144D03*
Y1567875D03*
Y1572606D03*
Y1578498D03*
Y1593853D03*
Y1583229D03*
Y1587960D03*
Y1603315D03*
Y1609207D03*
Y1598584D03*
Y1613938D03*
Y1618669D03*
X512000Y1644980D03*
X526468Y94017D03*
X534468D03*
X538477D03*
X530468D03*
X530596Y115401D03*
X535588Y110445D03*
Y115401D03*
X530596Y110445D03*
Y124618D03*
Y129574D03*
X535588Y124618D03*
Y129574D03*
X528509Y151540D03*
X538659Y184619D03*
X532159Y191941D03*
X532026Y188727D03*
X528783Y226141D03*
X525983D03*
X533853Y256535D03*
X525880Y285690D03*
X528680D03*
X525880Y288190D03*
X528680D03*
X532906Y290755D03*
X536906D03*
X540906D03*
X524206Y354119D03*
X533027Y351836D03*
X530215Y364422D03*
X535142Y397552D03*
X532936Y519544D03*
X527936D03*
X525436D03*
X530436D03*
X538826Y633450D03*
X526756Y636005D03*
Y633205D03*
X538826Y636250D03*
Y639050D03*
X526756Y638805D03*
X524653Y643595D03*
X534940Y684489D03*
X539111Y681459D03*
X526956Y694959D03*
X526951Y699443D03*
X535387Y712617D03*
X526933Y703820D03*
X532628Y720776D03*
X526276Y721339D03*
X539763Y734097D03*
X534807D03*
X531763Y739097D03*
X526807D03*
X532450Y767474D03*
X532278Y762736D03*
X531501Y792331D03*
X531260Y794934D03*
X531666Y815724D03*
X531313Y822693D03*
X527733Y847026D03*
X527346Y911458D03*
X528674Y964851D03*
X527046Y1131935D03*
Y1139435D03*
Y1134435D03*
Y1136935D03*
X528274Y1152684D03*
X527046Y1146935D03*
Y1144435D03*
Y1141935D03*
X525304Y1345691D03*
X530260D03*
X537544Y1350683D03*
X525304D03*
X530260D03*
X537544Y1345691D03*
Y1357603D03*
X525304Y1362595D03*
X530260D03*
X525304Y1357603D03*
X530260D03*
X537544Y1362595D03*
Y1374881D03*
X525304Y1369889D03*
Y1381801D03*
Y1374881D03*
X530260Y1369889D03*
Y1381801D03*
Y1374881D03*
X537544Y1369889D03*
Y1381801D03*
Y1399079D03*
Y1394087D03*
X530260D03*
Y1399079D03*
X525304Y1394087D03*
Y1399079D03*
X537544Y1386793D03*
X525304D03*
X530260D03*
X537544Y1410991D03*
Y1405999D03*
X530260D03*
X525304D03*
X530260Y1410991D03*
X525304D03*
X532000Y1644980D03*
X543545Y84140D03*
Y80140D03*
Y76140D03*
X540998Y117557D03*
X545990D03*
Y122513D03*
Y131731D03*
X540998Y122513D03*
Y131731D03*
X544089Y146461D03*
X545990Y136687D03*
X540998D03*
X542991Y152367D03*
X549374Y180527D03*
X544691Y180572D03*
X553097Y192421D03*
X549329Y185121D03*
X544691Y185165D03*
X540639Y206760D03*
X541853Y256535D03*
X542883Y279208D03*
X546987Y281307D03*
X541644Y389047D03*
X553731Y388487D03*
X541706Y381723D03*
X552905Y430829D03*
X550274Y658676D03*
X556574Y684031D03*
Y700031D03*
Y688987D03*
Y716031D03*
Y704987D03*
Y720987D03*
X552384Y762892D03*
X552188Y766577D03*
X553871Y811298D03*
X545741Y804149D03*
X548464Y823156D03*
X540807Y816556D03*
X541129Y828335D03*
Y838865D03*
X545981Y846389D03*
X549241Y841388D03*
X545237Y850319D03*
X548521Y877859D03*
Y874859D03*
X545144Y909025D03*
X544793Y899220D03*
X548215Y1006560D03*
X552923Y997860D03*
X541766Y1018368D03*
X557681Y1035088D03*
X554740Y1345597D03*
X542500Y1345691D03*
X549784Y1345597D03*
X542500Y1350683D03*
X549784D03*
X554740D03*
Y1362595D03*
Y1357603D03*
X542500Y1362595D03*
X549784D03*
X542500Y1357603D03*
X549784D03*
X554740Y1381801D03*
Y1374881D03*
X542500D03*
X549784Y1369889D03*
Y1381801D03*
Y1374881D03*
X542500Y1369889D03*
Y1381801D03*
X554740Y1369889D03*
Y1399079D03*
Y1393993D03*
X542500Y1399079D03*
X549784Y1393993D03*
Y1399079D03*
X542500Y1394087D03*
X554740Y1386793D03*
X549784D03*
X542500D03*
X554740Y1410991D03*
Y1405999D03*
X542500Y1410991D03*
X549784D03*
X542500Y1405999D03*
X549784D03*
X552000Y1644980D03*
X566287Y60922D03*
X561123Y55513D03*
X563224Y96813D03*
X558316Y91951D03*
X556920Y117261D03*
X567100Y110784D03*
X564451Y113394D03*
X567290Y130898D03*
X568841Y134579D03*
X564627Y180665D03*
Y172665D03*
X569969Y195176D03*
X564659Y212864D03*
Y200864D03*
X569829Y203393D03*
X564659Y221864D03*
Y216864D03*
X566416Y252371D03*
X570634Y375453D03*
X559074Y696987D03*
Y692031D03*
Y712987D03*
Y708031D03*
X561886Y728138D03*
X559625Y739609D03*
X557813Y747814D03*
X570578Y749800D03*
X570695Y767052D03*
X564276Y776701D03*
X558241Y796389D03*
X569186Y787332D03*
X561401Y811242D03*
X567316Y806224D03*
X561061Y803606D03*
X563099Y829943D03*
X567316Y827724D03*
X559741Y822149D03*
X572171Y842346D03*
X559196Y846296D03*
X569577Y886913D03*
X560814Y901022D03*
X564923Y997860D03*
X560923D03*
X568923D03*
X556923D03*
X571857Y1009354D03*
X565451Y1035102D03*
X569520Y1102091D03*
X560211D03*
X566020D03*
X569520Y1114691D03*
X566020D03*
X560211D03*
X569520Y1139891D03*
X566020D03*
X560211D03*
X566020Y1127291D03*
X560211D03*
X569520D03*
X566020Y1152491D03*
X560211D03*
X569520D03*
X566020Y1165091D03*
X560211D03*
X569520D03*
X560211Y1177691D03*
X566020D03*
X569520D03*
X566502Y1202103D03*
X569882Y1223749D03*
X562024Y1350683D03*
Y1345691D03*
X566980D03*
Y1350683D03*
X562024Y1357603D03*
X566980D03*
Y1362595D03*
X562024D03*
Y1369889D03*
Y1381801D03*
Y1374881D03*
X566980Y1369889D03*
Y1381801D03*
Y1374881D03*
Y1399079D03*
Y1394087D03*
X562024Y1399079D03*
Y1394087D03*
X566980Y1386793D03*
X562024D03*
X566980Y1410991D03*
X562024D03*
X566980Y1405999D03*
X562024D03*
X565600Y1530800D03*
X569349Y1541947D03*
X560635Y1543531D03*
X566800Y1541800D03*
X582686Y109172D03*
X579686D03*
X581693Y106495D03*
X585437Y116497D03*
X574694Y133298D03*
X585437Y123584D03*
Y130670D03*
X581427Y146012D03*
X583333Y141228D03*
X585437Y137757D03*
X586221Y150847D03*
X588189Y247292D03*
X580898Y253198D03*
X581487Y336676D03*
X573805Y728301D03*
X574620Y772724D03*
X584624Y781850D03*
X581001Y814123D03*
X579758Y817753D03*
X579827Y884000D03*
X579251Y903364D03*
X582706Y908959D03*
X580923Y997860D03*
X576923D03*
X588923D03*
X577666Y1009354D03*
X581166D03*
X572923Y997860D03*
X584923D03*
X581166Y1021954D03*
X577666D03*
X578298Y1215195D03*
X584024Y1209607D03*
X587689Y1505724D03*
X583661Y1529142D03*
X573784Y1530646D03*
X575332Y1523740D03*
X583800Y1518000D03*
X583740Y1520640D03*
X587858Y1517942D03*
X577645Y1540982D03*
X580700Y1544100D03*
X592737Y109410D03*
X590237Y116497D03*
X592737D03*
X597437Y102323D03*
Y109410D03*
Y116496D03*
Y123583D03*
Y130670D03*
X592737Y123583D03*
X590237Y123584D03*
Y130670D03*
X592737D03*
X597437Y137756D03*
X590237Y137757D03*
X590178Y309760D03*
X593690Y450750D03*
X597872Y512743D03*
X592880D03*
X597789Y536382D03*
X602756Y597580D03*
X604979Y599588D03*
X604241Y589556D03*
X604180Y592354D03*
X602695Y594668D03*
X604982Y596095D03*
X605011Y615600D03*
X604979Y607588D03*
X592238Y880612D03*
X597129Y913386D03*
X602385Y940920D03*
X596923Y997860D03*
X592923D03*
X604923D03*
X600923D03*
X602603Y1012354D03*
Y1024954D03*
X604405Y1034870D03*
X591898Y1035011D03*
X590957Y1105091D03*
Y1117691D03*
Y1130291D03*
Y1155491D03*
Y1142891D03*
Y1168091D03*
Y1180691D03*
X592978Y1514812D03*
X591858Y1523542D03*
X598800Y1546400D03*
X605899Y80384D03*
Y82984D03*
Y77784D03*
Y75184D03*
X608453Y92849D03*
X605899Y85584D03*
X615413Y103037D03*
X615547Y116496D03*
Y109410D03*
Y130670D03*
Y123583D03*
X612138Y137756D03*
X617728Y293796D03*
X620228D03*
X614461Y555234D03*
X614176Y562003D03*
X609472Y634946D03*
X612489Y941024D03*
X616923Y997860D03*
X608923D03*
X620151Y1040363D03*
X619086Y1056453D03*
X620715Y1046785D03*
X612000Y1644980D03*
X636830Y94017D03*
X628830D03*
X632830D03*
X632958Y110445D03*
Y115401D03*
Y124618D03*
Y129574D03*
X630871Y151540D03*
X634521Y191941D03*
X634388Y188727D03*
X631145Y226141D03*
X628345D03*
X636215Y256535D03*
X631042Y288190D03*
Y285690D03*
X625742Y288190D03*
X628242Y285690D03*
X625742D03*
X628242Y288190D03*
X635268Y290755D03*
X634455Y389154D03*
Y396240D03*
Y403327D03*
Y410413D03*
Y417500D03*
Y424587D03*
Y431673D03*
Y438760D03*
Y445847D03*
Y467539D03*
Y474626D03*
Y488799D03*
Y481713D03*
Y495886D03*
Y511673D03*
Y518760D03*
Y525847D03*
Y532933D03*
Y540020D03*
Y547106D03*
X633736Y602197D03*
X634200Y595108D03*
X622270Y864781D03*
X630466Y1394087D03*
X625510Y1399079D03*
Y1394087D03*
X630466Y1399079D03*
X625510Y1405999D03*
X630466D03*
X625510Y1410991D03*
X630466D03*
X636015Y1460782D03*
X627354Y1461182D03*
X636015Y1465513D03*
X627354Y1465913D03*
Y1456451D03*
X636015Y1476136D03*
X627354Y1476536D03*
X636015Y1480867D03*
X627354Y1481267D03*
Y1471805D03*
X636015Y1470244D03*
X627354Y1487159D03*
X636015Y1485598D03*
Y1491490D03*
X627354Y1491890D03*
X636015Y1496221D03*
X627354Y1496621D03*
Y1507245D03*
Y1511976D03*
X636015Y1511576D03*
X627354Y1502514D03*
X636015Y1500952D03*
Y1506845D03*
Y1516307D03*
X627354Y1558813D03*
X636015Y1563144D03*
X627354Y1563544D03*
X636015Y1567875D03*
X627354Y1568275D03*
Y1574167D03*
X636015Y1572606D03*
Y1578498D03*
X627354Y1578898D03*
X636015Y1593853D03*
X627354Y1594253D03*
X636015Y1583229D03*
X627354Y1583629D03*
Y1589522D03*
X636015Y1587960D03*
X627354Y1604876D03*
X636015Y1603315D03*
Y1598584D03*
X627354Y1598984D03*
X636015Y1609207D03*
X627354Y1609607D03*
X636015Y1618669D03*
Y1613938D03*
X627354Y1614338D03*
X632000Y1644980D03*
X645907Y76140D03*
Y84140D03*
Y80140D03*
X640839Y94017D03*
X643360Y117557D03*
X637950Y110445D03*
Y115401D03*
X648352Y117557D03*
X643360Y122513D03*
Y131731D03*
X637950Y124618D03*
Y129574D03*
X648352Y122513D03*
Y131731D03*
X646451Y146461D03*
X643360Y136687D03*
X648352D03*
X645353Y152367D03*
X647053Y180572D03*
X651736Y180527D03*
X651691Y185121D03*
X647053Y185165D03*
X641021Y184619D03*
X643001Y206760D03*
X644215Y256535D03*
X645245Y279208D03*
X649349Y281307D03*
X639268Y290755D03*
X643268D03*
X649074Y389154D03*
X647604Y396240D03*
X652381Y414823D03*
X651689Y422864D03*
X651759Y429832D03*
X651364Y436447D03*
X653399Y447953D03*
X652566Y467539D03*
X651308Y472772D03*
X652042Y487711D03*
X652155Y479104D03*
X652566Y495886D03*
X647915Y516841D03*
X651166Y510565D03*
X642862Y550123D03*
X642740Y552872D03*
X644494Y572334D03*
X642185Y562443D03*
X643953Y560675D03*
X642726Y574102D03*
X647361Y653161D03*
X648352Y645467D03*
X650958Y677843D03*
X649990Y1350683D03*
Y1345691D03*
Y1357603D03*
Y1362595D03*
Y1381801D03*
X642706Y1374881D03*
Y1381801D03*
Y1369889D03*
X649990Y1374881D03*
Y1369889D03*
X637750Y1374881D03*
Y1381801D03*
Y1369889D03*
X649990Y1399079D03*
Y1394087D03*
X642706Y1386793D03*
X649990D03*
X637750Y1399079D03*
X642706Y1394087D03*
X637750D03*
X642706Y1399079D03*
X637750Y1386793D03*
X649990Y1405999D03*
Y1410991D03*
X637750D03*
X642706D03*
Y1405999D03*
X637750D03*
X653338Y1465513D03*
X644677Y1461182D03*
Y1456451D03*
Y1465913D03*
X653338Y1460782D03*
X644677Y1476536D03*
Y1471805D03*
X653338Y1480867D03*
Y1470244D03*
Y1476136D03*
X644677Y1481267D03*
X653338Y1491490D03*
X644677Y1496621D03*
Y1491890D03*
Y1487159D03*
X653338Y1496221D03*
Y1485598D03*
X644677Y1511976D03*
X653338Y1511576D03*
Y1500952D03*
Y1506845D03*
X644677Y1502514D03*
Y1507245D03*
X653338Y1516307D03*
X644677Y1558813D03*
X653338Y1563144D03*
X644677Y1563544D03*
X653338Y1572606D03*
Y1578498D03*
X644677Y1578898D03*
Y1574167D03*
X653338Y1567875D03*
X644677Y1568275D03*
X653338Y1587960D03*
Y1593853D03*
X644677Y1594253D03*
Y1589522D03*
X653338Y1583229D03*
X644677Y1583629D03*
X653338Y1609207D03*
X644677Y1598984D03*
Y1604876D03*
Y1609607D03*
X653338Y1603315D03*
Y1598584D03*
Y1613938D03*
X644677Y1614338D03*
X653338Y1618669D03*
X652000Y1644980D03*
X668649Y60922D03*
X666209Y57297D03*
X665423Y96853D03*
X660678Y91951D03*
X659282Y117261D03*
X666813Y113394D03*
X669462Y110784D03*
X669056Y133298D03*
X666989Y172665D03*
Y180665D03*
X655459Y192421D03*
X667021Y200864D03*
Y212864D03*
Y221864D03*
Y216864D03*
X668778Y252371D03*
X667666Y389153D03*
X665166Y396240D03*
X667666D03*
X665166Y403327D03*
X667666Y403326D03*
X665166Y410413D03*
X667666D03*
Y417499D03*
X665166Y424586D03*
X667666D03*
X665166Y417500D03*
Y431673D03*
Y438760D03*
X667666D03*
Y431673D03*
X665166Y445847D03*
X667666Y467539D03*
X665166Y474626D03*
X667666D03*
X665166Y488799D03*
X667666D03*
Y481712D03*
X665166D03*
Y495886D03*
X667666Y518760D03*
X665166D03*
X667666Y511673D03*
Y532933D03*
X665166D03*
Y540020D03*
Y525846D03*
X667666D03*
X669546Y560500D03*
X655752Y668885D03*
X661776Y662981D03*
X656157Y691851D03*
X661768Y705043D03*
X654946Y1350683D03*
X662230D03*
X667186D03*
Y1345691D03*
X654946D03*
X662230D03*
X654946Y1357603D03*
Y1362595D03*
X662230Y1357603D03*
Y1362595D03*
X667186Y1357603D03*
Y1362595D03*
X662230Y1369889D03*
X667186Y1374881D03*
Y1381801D03*
Y1369889D03*
X662230Y1374881D03*
Y1381801D03*
X654946D03*
Y1369889D03*
Y1374881D03*
X667186Y1399079D03*
Y1393993D03*
X662230D03*
Y1399079D03*
X655046D03*
Y1394087D03*
X667186Y1386793D03*
X662230D03*
X654946D03*
X667186Y1410991D03*
Y1405999D03*
X662230D03*
Y1410991D03*
X655046Y1405999D03*
Y1410991D03*
X662000Y1456451D03*
Y1465913D03*
Y1461182D03*
Y1481267D03*
Y1476536D03*
Y1471805D03*
Y1496621D03*
Y1491890D03*
Y1487159D03*
Y1511976D03*
Y1502514D03*
Y1507245D03*
Y1563544D03*
Y1558813D03*
Y1568275D03*
Y1578898D03*
Y1574167D03*
Y1594253D03*
Y1589522D03*
Y1583629D03*
Y1598984D03*
Y1604876D03*
Y1609607D03*
Y1614338D03*
X682048Y109172D03*
X685048D03*
X684055Y106495D03*
X677056Y133298D03*
X671203Y134579D03*
X683789Y146012D03*
X685695Y141228D03*
X677331Y195176D03*
X676950Y198883D03*
X683260Y253198D03*
X686012Y339795D03*
X672466Y389153D03*
Y410413D03*
Y396240D03*
Y403326D03*
Y424586D03*
Y417499D03*
Y438760D03*
Y431673D03*
Y467539D03*
Y474626D03*
Y488799D03*
Y481712D03*
Y518760D03*
Y511673D03*
Y525846D03*
Y532933D03*
X681586Y555000D03*
X681011Y543925D03*
X679426Y1350683D03*
X674470Y1345691D03*
X679426D03*
X674470Y1350683D03*
Y1357603D03*
Y1362595D03*
X679426Y1357603D03*
Y1362595D03*
Y1374881D03*
X674470D03*
Y1381801D03*
X679426D03*
Y1369889D03*
X674470D03*
X679426Y1399079D03*
X674470Y1394087D03*
X679426D03*
X674470Y1399079D03*
Y1386793D03*
X679426D03*
X674470Y1405999D03*
X679426D03*
X674470Y1410991D03*
X679426D03*
X679322Y1461182D03*
Y1456451D03*
Y1465913D03*
X670661Y1460782D03*
Y1465513D03*
Y1470244D03*
Y1476136D03*
X679322Y1481267D03*
Y1476536D03*
Y1471805D03*
X670661Y1480867D03*
X679322Y1487159D03*
X670661Y1496221D03*
Y1485598D03*
Y1491490D03*
X679322Y1496621D03*
Y1491890D03*
X670661Y1500952D03*
Y1506845D03*
X679322Y1511976D03*
Y1502514D03*
Y1507245D03*
X670661Y1511576D03*
Y1516307D03*
X679322Y1558813D03*
X670661Y1563144D03*
X679322Y1563544D03*
Y1578898D03*
Y1574167D03*
Y1568275D03*
X670661Y1572606D03*
Y1578498D03*
Y1567875D03*
X679322Y1583629D03*
X670661Y1587960D03*
Y1593853D03*
Y1583229D03*
X679322Y1594253D03*
Y1589522D03*
Y1604876D03*
Y1609607D03*
X670661Y1603315D03*
Y1598584D03*
Y1609207D03*
X679322Y1598984D03*
Y1614338D03*
X670661Y1618669D03*
Y1613938D03*
X672000Y1644980D03*
X695099Y109410D03*
X687799Y116497D03*
X692599D03*
X695099D03*
X699799Y116496D03*
Y109410D03*
Y102323D03*
X687799Y123584D03*
X695099Y123583D03*
X692599Y123584D03*
X687799Y130670D03*
X692599D03*
X695099D03*
X699799Y123583D03*
Y130670D03*
X687799Y137757D03*
X692599D03*
X699799Y137756D03*
X688583Y150847D03*
X690551Y247292D03*
X700164Y636842D03*
X698936Y678462D03*
X702691Y766471D03*
Y753471D03*
X702677Y771159D03*
Y784659D03*
X698950Y1350683D03*
Y1345597D03*
X686710Y1350683D03*
X691666D03*
X686710Y1345691D03*
X691666D03*
X698950Y1362595D03*
Y1357603D03*
X686710D03*
Y1362595D03*
X691666Y1357603D03*
Y1362595D03*
X698950Y1374881D03*
Y1381801D03*
Y1369889D03*
X691666D03*
Y1374881D03*
Y1381801D03*
X686710Y1374881D03*
Y1369889D03*
Y1381801D03*
X698950Y1399079D03*
Y1394087D03*
X686710D03*
Y1399079D03*
X691666Y1394087D03*
Y1399079D03*
X698950Y1386793D03*
X691666D03*
X686710D03*
X698950Y1405999D03*
Y1410991D03*
X686710D03*
X691666D03*
X686710Y1405999D03*
X691666D03*
X696645Y1461183D03*
Y1456452D03*
Y1465914D03*
X687984Y1460782D03*
Y1465513D03*
Y1470244D03*
Y1476136D03*
X696645Y1481268D03*
Y1471806D03*
Y1476537D03*
X687984Y1480867D03*
X696645Y1491891D03*
X687984Y1496221D03*
Y1485598D03*
Y1491490D03*
X696645Y1496622D03*
Y1487160D03*
Y1511977D03*
Y1502515D03*
Y1507246D03*
X687984Y1511576D03*
Y1500952D03*
Y1506845D03*
Y1516307D03*
X696645Y1558813D03*
Y1563544D03*
X687984Y1563144D03*
X696645Y1574167D03*
Y1578898D03*
X687984Y1572606D03*
Y1578498D03*
X696645Y1568275D03*
X687984Y1567875D03*
Y1583229D03*
X696645Y1589522D03*
Y1594253D03*
X687984Y1587960D03*
Y1593853D03*
X696645Y1583629D03*
Y1598984D03*
Y1609607D03*
X687984Y1603315D03*
Y1598584D03*
Y1609207D03*
X696645Y1604876D03*
X687984Y1613938D03*
X696645Y1614338D03*
X687984Y1618669D03*
X692000Y1644980D03*
X718488Y-27642D03*
X718503Y-25127D03*
X708261Y82984D03*
Y80384D03*
Y77784D03*
Y75184D03*
X710815Y92849D03*
X708261Y85584D03*
X717775Y103037D03*
X717909Y116496D03*
Y109410D03*
Y130670D03*
Y123583D03*
X714500Y137756D03*
X713162Y434493D03*
X711764Y449873D03*
X718691Y465492D03*
Y472579D03*
X716191D03*
X711391D03*
X716191Y479666D03*
X718691D03*
X711391D03*
Y486752D03*
X716191D03*
X718691D03*
X711391Y493839D03*
X716191D03*
Y516713D03*
Y523800D03*
X718691D03*
X711391D03*
Y516713D03*
X718691D03*
Y509626D03*
Y530886D03*
X716191D03*
Y537973D03*
X711391Y530886D03*
Y537973D03*
Y566752D03*
X718691Y559665D03*
Y566752D03*
X716191D03*
X711391Y573839D03*
X718691D03*
X716191D03*
X711391Y588013D03*
X718691Y588012D03*
X716191Y588013D03*
X718691Y580926D03*
X716191D03*
X711391D03*
X716191Y602186D03*
X711391D03*
X718691Y602185D03*
Y595099D03*
X711391D03*
X716191D03*
X711391Y609272D03*
X716191D03*
X718691D03*
X716191Y616359D03*
X711391D03*
X706070Y638125D03*
X716656Y646429D03*
X703669Y665140D03*
X716350Y699477D03*
X703604Y699653D03*
X716146Y1350683D03*
X711190D03*
X716146Y1345691D03*
X711190D03*
X703906Y1350683D03*
Y1345597D03*
X716146Y1357603D03*
X711190D03*
Y1362595D03*
X716146D03*
X703906Y1357603D03*
Y1362595D03*
X716146Y1374881D03*
Y1381801D03*
Y1369889D03*
X711190D03*
Y1374881D03*
Y1381801D03*
X703906D03*
Y1369889D03*
Y1374881D03*
X716146Y1399079D03*
X711190D03*
X716146Y1393993D03*
X711190D03*
X703906Y1394087D03*
Y1399079D03*
X716146Y1386793D03*
X711190D03*
X703906D03*
X716146Y1405999D03*
X711190D03*
X716146Y1410991D03*
X711190D03*
X703906Y1405999D03*
Y1410991D03*
X712000Y1644980D03*
X721741Y-27628D03*
X721756Y-25113D03*
X724781Y-26433D03*
X735192Y94017D03*
X731192D03*
X733233Y151540D03*
X736750Y188727D03*
X730707Y226141D03*
X733507D03*
X733404Y285690D03*
X720090Y293796D03*
X722590D03*
X728104Y288190D03*
X730604Y285690D03*
X728104D03*
X730604Y288190D03*
X733404D03*
X731511Y390500D03*
X734606Y379562D03*
X722097Y410394D03*
Y403307D03*
X723491Y458406D03*
Y451319D03*
Y465492D03*
X723315Y462264D03*
X723491Y472579D03*
Y479665D03*
Y486752D03*
Y493839D03*
Y523799D03*
Y516713D03*
Y509626D03*
Y530886D03*
Y537973D03*
Y566752D03*
Y559665D03*
Y573839D03*
Y588012D03*
Y580926D03*
Y595099D03*
Y602185D03*
Y609272D03*
Y616358D03*
X734819Y646429D03*
X725318Y890354D03*
X720373Y940310D03*
X724547Y958287D03*
X723430Y1350683D03*
X728386Y1345691D03*
X723430D03*
X728386Y1350683D03*
Y1357603D03*
Y1362595D03*
X723430Y1357603D03*
Y1362595D03*
X728386Y1381801D03*
Y1374881D03*
Y1369889D03*
X723430D03*
Y1381801D03*
Y1374881D03*
X728386Y1386793D03*
X723430D03*
X728386Y1398985D03*
Y1393993D03*
X723430Y1398985D03*
Y1393993D03*
X728386Y1410897D03*
Y1405905D03*
X723430Y1410897D03*
Y1405905D03*
X732000Y1644980D03*
X748269Y84140D03*
Y76140D03*
Y80140D03*
X743201Y94017D03*
X739192D03*
X750714Y117557D03*
X745722D03*
X740312Y115401D03*
Y110445D03*
X735320D03*
Y115401D03*
X745722Y131731D03*
Y122513D03*
X740312Y129574D03*
Y124618D03*
X735320D03*
Y129574D03*
X750714Y131731D03*
Y122513D03*
Y136687D03*
X745722D03*
X748813Y146461D03*
X747715Y152367D03*
X749415Y180572D03*
Y185165D03*
X743383Y184619D03*
X736883Y191941D03*
X745363Y206760D03*
X738577Y256535D03*
X746577D03*
X747607Y279208D03*
X751711Y281307D03*
X741630Y290755D03*
X737630D03*
X745630D03*
X741161Y381500D03*
X741602Y465492D03*
X741568Y460250D03*
X739333Y470136D03*
X741602Y472579D03*
X741072Y478958D03*
X741602Y486752D03*
Y493839D03*
Y509626D03*
Y516713D03*
X738062Y537973D03*
X740542Y525483D03*
X740463Y532756D03*
X741602Y559665D03*
Y566752D03*
X741452Y579978D03*
X741602Y573839D03*
X741666Y608117D03*
X741000Y771100D03*
X738707Y987952D03*
X745673Y1007009D03*
X747910Y1345691D03*
Y1350683D03*
X735670D03*
X740626D03*
X735670Y1345691D03*
X740626D03*
X747910Y1357603D03*
Y1362595D03*
X735670Y1357603D03*
Y1362595D03*
X740626Y1357603D03*
Y1362595D03*
X747910Y1374881D03*
Y1381801D03*
Y1369889D03*
X740626Y1381801D03*
Y1369889D03*
Y1374881D03*
X735670Y1381801D03*
Y1369889D03*
Y1374881D03*
X747910Y1386793D03*
X735670Y1393993D03*
X740626D03*
Y1398985D03*
X735670D03*
X740626Y1386793D03*
X735670D03*
Y1405905D03*
Y1410897D03*
X740626Y1405905D03*
Y1410897D03*
X742655Y1445733D03*
X747590Y1627871D03*
X765847Y55513D03*
X762065Y117040D03*
X754098Y180527D03*
X757821Y192421D03*
X754053Y185121D03*
X756201Y288345D03*
Y290845D03*
X753701Y288345D03*
Y290845D03*
Y293645D03*
X756201D03*
X763898Y342319D03*
X766344Y393924D03*
Y389912D03*
Y385912D03*
X758038Y381143D03*
X766344Y409924D03*
Y405924D03*
Y401924D03*
X752341Y407148D03*
X756800Y403824D03*
X758381Y395391D03*
X759543Y445787D03*
X755593Y445908D03*
X765106Y1350683D03*
Y1345597D03*
X760150D03*
Y1350683D03*
X752866Y1345691D03*
Y1350683D03*
X765106Y1362595D03*
Y1357603D03*
X760150D03*
Y1362595D03*
X752866Y1357603D03*
Y1362595D03*
X765106Y1374881D03*
Y1381801D03*
Y1369889D03*
X760150Y1374881D03*
Y1381801D03*
Y1369889D03*
X752866Y1374881D03*
Y1381801D03*
Y1369889D03*
X765106Y1386793D03*
X760150D03*
X752866D03*
X766433Y1583713D03*
X752150Y1627871D03*
X762776Y1629415D03*
X752000Y1644980D03*
X771011Y60922D03*
X767929Y96890D03*
X771824Y110784D03*
X769175Y113394D03*
X779418Y133298D03*
X771960Y130898D03*
X773565Y134579D03*
X769351Y172665D03*
Y180665D03*
X769383Y200864D03*
Y212864D03*
Y221864D03*
Y216864D03*
X771140Y252371D03*
X780968Y303839D03*
X772990Y336324D03*
X777569Y353506D03*
X772390Y1350683D03*
X777346D03*
Y1345691D03*
X772390D03*
Y1357603D03*
Y1362595D03*
X777346Y1357603D03*
Y1362595D03*
X777114Y1442270D03*
X778045Y1622545D03*
X782289Y1620109D03*
X773822Y1627418D03*
X772000Y1644980D03*
X784410Y109172D03*
X787410D03*
X794961Y116497D03*
X797461D03*
X790161D03*
X786417Y106495D03*
X797461Y109410D03*
Y123583D03*
X794961Y123584D03*
X790161D03*
X794961Y130670D03*
X797461D03*
X790161D03*
X794961Y137757D03*
X790161D03*
X788057Y141228D03*
X786151Y146012D03*
X793221Y140296D03*
X790945Y150847D03*
X792913Y247292D03*
X785622Y253198D03*
X788522Y290304D03*
X799937Y347340D03*
X791686Y1025440D03*
X794716Y1186071D03*
X792183Y1334030D03*
Y1331230D03*
X789383Y1334030D03*
Y1331230D03*
X794506Y1411307D03*
X793723Y1468071D03*
X793564Y1642682D03*
X810623Y77784D03*
Y82984D03*
Y80384D03*
Y75184D03*
X813177Y92849D03*
X810623Y85584D03*
X802161Y116496D03*
Y109410D03*
Y102323D03*
Y130670D03*
Y123583D03*
Y137756D03*
X816364Y486870D03*
X813864D03*
X813566Y744187D03*
X812661Y810032D03*
X812980Y824166D03*
X816016Y838036D03*
X813182Y852800D03*
X814731Y889365D03*
X812811Y908162D03*
X809682Y1133284D03*
X806787Y1148000D03*
X815034Y1159455D03*
X809623Y1160168D03*
X809393Y1187252D03*
X807487Y1193019D03*
X815487D03*
X811487D03*
X817446Y1210089D03*
X800627Y1392748D03*
X800703Y1426779D03*
X811457Y1639797D03*
X820137Y103037D03*
X820271Y116496D03*
Y109410D03*
Y130670D03*
Y123583D03*
X816637Y137756D03*
X824952Y293796D03*
X822452D03*
X830466Y285690D03*
Y288190D03*
X825792Y305225D03*
X823529Y467189D03*
X830318Y674164D03*
X829784Y713939D03*
X832284Y731216D03*
X830484Y746701D03*
X819993Y754109D03*
X817500Y760000D03*
X820547Y780314D03*
X826925Y769000D03*
X820500Y777500D03*
X826925Y787000D03*
X820500Y792000D03*
X818500Y814000D03*
X820432Y800529D03*
X826925Y805000D03*
Y823000D03*
X826165Y863000D03*
X819134Y863607D03*
X829000Y852000D03*
X825686Y869496D03*
X826797Y883756D03*
X825508Y913869D03*
X822462Y915095D03*
X818347Y939610D03*
X828193Y949324D03*
X832432Y977982D03*
X832711Y993268D03*
X828385Y1120599D03*
X817006Y1133027D03*
X822006Y1130208D03*
X825744Y1146937D03*
X823220Y1162817D03*
X823487Y1193019D03*
X819487D03*
X826612Y1219254D03*
X819522Y1212164D03*
X821816Y1214458D03*
X832084Y1461072D03*
X831457Y1639797D03*
X844781Y-65613D03*
X841756Y-64293D03*
X838503Y-64307D03*
X841741Y-66808D03*
X838488Y-66822D03*
X841554Y94017D03*
X837554D03*
X845563D03*
X833554D03*
X837682Y110445D03*
Y115401D03*
X848084Y117557D03*
X842674Y115401D03*
Y110445D03*
Y129574D03*
Y124618D03*
X837682D03*
Y129574D03*
X848084Y131731D03*
Y122513D03*
Y136687D03*
X839112Y188727D03*
X839245Y191941D03*
X845745Y184619D03*
X847725Y206760D03*
X833069Y226141D03*
X835869D03*
X848939Y256535D03*
X840939D03*
X832966Y288190D03*
Y285690D03*
X835766Y288190D03*
Y285690D03*
X843992Y290755D03*
X839992D03*
X847992D03*
X835236Y533174D03*
X845729Y661263D03*
X836503Y667845D03*
X845784Y713939D03*
X848284Y731181D03*
X846484Y746701D03*
X841500Y758161D03*
Y776161D03*
Y794161D03*
Y812161D03*
X838685Y832987D03*
X845654Y895437D03*
X833870Y881860D03*
X839381Y915839D03*
X839122Y939655D03*
X843734Y1008778D03*
X848520Y1016855D03*
X850631Y84140D03*
Y80140D03*
Y76140D03*
X864006Y117261D03*
X853076Y117557D03*
Y131731D03*
Y122513D03*
Y136687D03*
X851777Y180572D03*
X856460Y180527D03*
X860183Y192421D03*
X851777Y185165D03*
X856415Y185121D03*
X849969Y279208D03*
X854073Y281307D03*
X864920Y343168D03*
X854086Y385000D03*
X858586D03*
X850733Y461382D03*
X850832Y473382D03*
X850738Y477382D03*
X850909Y482382D03*
X853900Y627700D03*
X858202Y646330D03*
X851111Y656635D03*
X856145Y677887D03*
X855646Y685230D03*
X858186Y713170D03*
X867227Y722060D03*
X849500Y761000D03*
X864575Y770500D03*
X849500Y779000D03*
X864575Y788500D03*
X849500Y797000D03*
Y815000D03*
X864575Y806500D03*
X865004Y831273D03*
X864464Y828503D03*
X864575Y824500D03*
X851782Y823720D03*
X851161Y855205D03*
X856628Y915242D03*
X864253D03*
X849600Y915266D03*
X855867Y935540D03*
X849088Y951081D03*
X852247Y1009529D03*
X849996Y1091073D03*
X850023Y1095179D03*
X863342Y1120636D03*
X855542D03*
X858142D03*
X860842D03*
X863442Y1130336D03*
X858242D03*
X855642D03*
X860942D03*
Y1139336D03*
X863442D03*
X861119Y1148080D03*
X863619D03*
X851457Y1639797D03*
X873373Y60922D03*
X868209Y55513D03*
X870395Y96738D03*
X865402Y91951D03*
X871713Y172665D03*
Y180665D03*
X871745Y200864D03*
Y212864D03*
Y216864D03*
Y221864D03*
X876246Y302754D03*
X869313Y688486D03*
X872069Y700894D03*
X876286Y686970D03*
X880501Y710611D03*
X873021Y715729D03*
X877616Y749484D03*
X873318Y744597D03*
X873250Y798750D03*
X872700Y816615D03*
X872628Y915242D03*
X880628D03*
X876481Y941126D03*
X868908Y933640D03*
X867199Y949372D03*
X869390Y978003D03*
X878004Y1224406D03*
X883142Y1259935D03*
X875700Y1299700D03*
X871457Y1639797D03*
X886011Y154100D03*
X895780Y237517D03*
Y232634D03*
X886261Y252090D03*
X885741Y261150D03*
X894844Y418983D03*
X889219Y426952D03*
X887770Y415290D03*
X890270D03*
X897344Y418983D03*
X894519Y426952D03*
X889596Y437264D03*
X896388Y437614D03*
X887096Y437264D03*
X892019Y426952D03*
X897019D03*
X882891Y536122D03*
X896449Y550863D03*
X893949Y550363D03*
X882949Y557363D03*
X887949Y608863D03*
X894449Y606363D03*
X884903Y694119D03*
X886836Y729778D03*
X889083Y780371D03*
X888545Y785528D03*
X888514Y797602D03*
X891916Y808965D03*
X882609Y994245D03*
X897056Y1091391D03*
X891055Y1095407D03*
X897056Y1095984D03*
X884906Y1102760D03*
X884890Y1098724D03*
X893190Y1208069D03*
X894887Y1227209D03*
X891003Y1292765D03*
X890738Y1311132D03*
X891457Y1639797D03*
X898813Y146461D03*
X897715Y152367D03*
X898851Y231496D03*
Y238583D03*
Y245669D03*
X910977Y238583D03*
X898851Y259843D03*
X898576Y253056D03*
X910977Y252756D03*
Y257480D03*
X898851Y274016D03*
X910977Y266929D03*
X898851D03*
X912786Y306697D03*
X901848Y307782D03*
Y312738D03*
X909417Y323302D03*
X912085Y332335D03*
X898888Y437614D03*
X906996Y530707D03*
X902459Y530755D03*
X911630Y543998D03*
X910578Y550186D03*
X909362Y555614D03*
X898156Y554812D03*
X909024Y586768D03*
X908730Y619120D03*
X913686D03*
X899898Y619040D03*
X904854D03*
X910036Y702285D03*
X910753Y715864D03*
X912864Y864189D03*
Y870488D03*
Y867338D03*
X899693Y895207D03*
X904833Y915340D03*
X912628Y928101D03*
X911355Y944909D03*
X906710Y962433D03*
X906909Y951494D03*
X909296Y1020224D03*
X909300Y1014639D03*
X901739Y1091346D03*
X897815Y1078042D03*
X901366Y1078069D03*
X901694Y1095940D03*
X911071Y1123803D03*
X905771D03*
X903171D03*
X908371D03*
X910971Y1114103D03*
X908271D03*
X903071D03*
X905671D03*
X911699Y1129488D03*
X909041Y1126328D03*
X911641D03*
X903908Y1132870D03*
X904063Y1135946D03*
X901940Y1236799D03*
Y1229899D03*
Y1232399D03*
Y1246199D03*
Y1243699D03*
Y1239299D03*
X904703Y1297398D03*
X911457Y1639797D03*
X919175Y113394D03*
X921824Y110784D03*
X921418Y133298D03*
X929418D03*
X923565Y134579D03*
X920142Y308501D03*
X926801Y323302D03*
X923902Y332411D03*
X924600Y533706D03*
X920961Y550075D03*
X915949Y563363D03*
X915712Y613792D03*
X915194Y666671D03*
X928043Y677795D03*
X917286Y679625D03*
X924932Y701051D03*
X920628Y928101D03*
X928628D03*
X916628D03*
X924628D03*
X924487Y951244D03*
X918648Y964717D03*
X915490Y969886D03*
X916749Y1080659D03*
Y1088659D03*
X917110Y1101902D03*
X927598Y1120636D03*
X924898D03*
X914661Y1132612D03*
X914299Y1129488D03*
X914241Y1126328D03*
X924919Y1130336D03*
X927619D03*
X924919Y1139336D03*
X927419D03*
X925097Y1147708D03*
X927597D03*
X927146Y1328597D03*
Y1323641D03*
X929094Y1542353D03*
Y1545353D03*
X926041Y1554503D03*
Y1551503D03*
Y1548503D03*
Y1557503D03*
Y1560503D03*
X944961Y116497D03*
X934410Y109172D03*
X936417Y106495D03*
X937410Y109172D03*
X940161Y116497D03*
Y123584D03*
X944961D03*
X940161Y130670D03*
X944961D03*
X940161Y137757D03*
X944961D03*
X936151Y146012D03*
X938057Y141228D03*
X940945Y150847D03*
X932388Y330517D03*
X932622Y336817D03*
X944694Y352192D03*
X931627Y561578D03*
Y565578D03*
X943825Y581222D03*
Y591215D03*
X935281Y677795D03*
X945626Y789761D03*
X932000Y831000D03*
X942634Y886520D03*
X933700Y887508D03*
X944839Y902400D03*
X938188Y900853D03*
X944628Y928101D03*
X932628D03*
X936628D03*
X940497D03*
X941981Y1224406D03*
X947119Y1259935D03*
X933254Y1308273D03*
X940848Y1310181D03*
X930441Y1455039D03*
Y1458039D03*
Y1464039D03*
Y1461039D03*
Y1467039D03*
X938670Y1510528D03*
X941270D03*
Y1505328D03*
X938670D03*
X940170Y1507928D03*
X943870Y1510528D03*
Y1505328D03*
X945370Y1507928D03*
X942770D03*
X935094Y1542353D03*
X932094D03*
X935094Y1545353D03*
X932094D03*
X938094Y1542353D03*
Y1545353D03*
X941094Y1542353D03*
X944094D03*
X941094Y1545353D03*
X944094D03*
X931457Y1639797D03*
X960623Y82984D03*
Y77784D03*
Y80384D03*
Y75184D03*
Y85584D03*
X947461Y116497D03*
X952161Y116496D03*
Y109410D03*
Y102323D03*
X947461Y109410D03*
Y130670D03*
X952161D03*
Y123583D03*
X947461D03*
X952161Y137756D03*
X949443Y208206D03*
X949579Y330517D03*
X949813Y336817D03*
X956863Y451466D03*
X953816Y555194D03*
X951016D03*
X953816Y571194D03*
X951016D03*
X953816Y563194D03*
X951016D03*
X946625Y581222D03*
X949425D03*
Y591215D03*
X946625D03*
X948427Y611091D03*
X957551Y698251D03*
X954023Y725336D03*
X951195Y727165D03*
X952681Y735256D03*
X956323Y748412D03*
X957474Y764426D03*
X955086Y779798D03*
X956051Y793937D03*
X947735Y824921D03*
X948935Y835800D03*
X954700Y842700D03*
X947735Y854935D03*
X953091Y857440D03*
X953217Y861440D03*
X955967Y860376D03*
X946700Y849200D03*
X950251Y874268D03*
X950291Y870240D03*
Y866240D03*
X953145Y874240D03*
X952738Y886624D03*
X953587Y902814D03*
X961479Y927643D03*
X957671Y991564D03*
X946642Y991361D03*
X961033Y1091391D03*
X948883Y1102760D03*
X948867Y1098724D03*
X955032Y1095407D03*
X961033Y1095984D03*
X957167Y1208069D03*
X958864Y1227209D03*
X949970Y1321749D03*
X952070Y1367717D03*
X949070D03*
X956238Y1455139D03*
Y1458139D03*
Y1461139D03*
Y1464139D03*
X952676Y1461039D03*
Y1464039D03*
Y1458039D03*
Y1455039D03*
X956238Y1467139D03*
Y1469902D03*
X952676Y1467039D03*
X946470Y1510528D03*
Y1505328D03*
X947094Y1545353D03*
Y1542353D03*
X951457Y1639797D03*
X963177Y92849D03*
X970137Y103037D03*
X970271Y116496D03*
Y109410D03*
Y130670D03*
Y123583D03*
X966347Y137756D03*
X974952Y293796D03*
X972452D03*
X972147Y323681D03*
X975932Y437508D03*
X971932D03*
X962769Y458466D03*
X973695Y448874D03*
X969109Y449352D03*
X978723Y504699D03*
X976223D03*
X973723D03*
X978425Y516979D03*
X973425D03*
X975925D03*
X967302Y627948D03*
X969491Y629362D03*
X963187Y667620D03*
X973138Y667621D03*
X978059Y747438D03*
X976764Y786563D03*
X964070Y807686D03*
Y813006D03*
X977218Y802178D03*
X964036Y818961D03*
X968319Y826191D03*
X976635Y835018D03*
X976800Y838011D03*
X974282D03*
X976902Y847135D03*
X971808Y851242D03*
X975925Y854783D03*
X978201Y897500D03*
X969806Y993033D03*
X965716Y1091346D03*
X965671Y1095940D03*
X967148Y1123803D03*
X969748D03*
X969648Y1114103D03*
X967048D03*
X972348Y1123803D03*
X975048D03*
X972248Y1114103D03*
X974948D03*
X970485Y1132870D03*
X967885D03*
X968874Y1145169D03*
X966374D03*
X965917Y1236799D03*
Y1229899D03*
Y1232399D03*
Y1246199D03*
Y1243699D03*
Y1239299D03*
X978727Y1284908D03*
X971467Y1509515D03*
X974067D03*
X972567Y1512115D03*
X969967D03*
X976667Y1509515D03*
X977767Y1506915D03*
X975167D03*
X969967D03*
X972567D03*
X975167Y1512115D03*
X977767D03*
X971140Y1514693D03*
X968540D03*
X973740D03*
X976340D03*
X971457Y1639797D03*
X983554Y94017D03*
X987554D03*
X991554D03*
X987682Y115401D03*
X992674D03*
Y110445D03*
X987682D03*
X992674Y124618D03*
X987682D03*
Y129574D03*
X992674D03*
X985595Y151540D03*
X989245Y191941D03*
X989112Y188727D03*
X983069Y226141D03*
X985869D03*
X990939Y256535D03*
X985766Y288190D03*
X982966D03*
X985766Y285690D03*
X982966D03*
X980466Y288190D03*
Y285690D03*
X993992Y290755D03*
X989992D03*
X979932Y437508D03*
X982792Y447269D03*
X982670Y450201D03*
X989936Y519531D03*
X987436D03*
X982436D03*
X984936D03*
X983843Y633205D03*
Y636005D03*
Y638805D03*
X984307Y748432D03*
X985030Y781204D03*
X988329Y781445D03*
X991990Y773974D03*
X984963Y785387D03*
X979313Y814316D03*
X987903Y818645D03*
X993061Y833135D03*
X979203Y837159D03*
X988820Y858903D03*
X980529Y879097D03*
X988231Y878203D03*
X984892Y868720D03*
X987790Y896596D03*
X995133Y888503D03*
X982787Y899757D03*
X988461Y1013841D03*
X980726Y1080659D03*
Y1088659D03*
X981087Y1101902D03*
X988389Y1302558D03*
X980501Y1369685D03*
X983501D03*
X979538Y1464039D03*
Y1461039D03*
Y1458039D03*
Y1455039D03*
Y1467039D03*
Y1469802D03*
X979267Y1509515D03*
X984467D03*
X981867D03*
X985567Y1512115D03*
Y1506915D03*
X980367D03*
X982967D03*
Y1512115D03*
X980367D03*
X989667Y1509515D03*
X992267D03*
X987067D03*
X988167Y1512115D03*
X990767D03*
Y1506915D03*
X988167D03*
X984140Y1514693D03*
X981540D03*
X978940D03*
X986740D03*
X989340D03*
X991457Y1639797D03*
X1005256Y-25113D03*
X1002003Y-25027D03*
X1005241Y-27628D03*
X1001988Y-27542D03*
X1008281Y-26433D03*
X1000631Y84140D03*
Y76140D03*
Y80140D03*
X995563Y94017D03*
X1003076Y117557D03*
X998084D03*
X1003076Y122513D03*
Y131731D03*
X998084Y122513D03*
Y131731D03*
X1001175Y146461D03*
X1003076Y136687D03*
X998084D03*
X1000077Y152367D03*
X1001777Y180572D03*
X1006460Y180527D03*
X1010183Y192421D03*
X1001777Y185165D03*
X1006415Y185121D03*
X995745Y184619D03*
X997725Y206760D03*
X998939Y256535D03*
X999826Y278734D03*
X1004061Y280808D03*
X997992Y290755D03*
X1004544Y318050D03*
X1004933Y314535D03*
X997921Y333654D03*
X995913Y633450D03*
Y636250D03*
Y639050D03*
X1008342Y761735D03*
X1003539Y762632D03*
X1002834Y777394D03*
X1006053Y787745D03*
X999825Y819488D03*
X1002887Y834342D03*
X1000369D03*
X1005607Y874859D03*
Y877859D03*
X1002930Y906785D03*
X1010009Y998100D03*
X1005301Y1006560D03*
X999700Y1018400D03*
X1008312Y1363533D03*
X1008452Y1376752D03*
X1008483Y1372734D03*
X1006211Y1397662D03*
X1009338Y1391597D03*
Y1388597D03*
X1002538Y1463939D03*
Y1460939D03*
Y1457939D03*
Y1454939D03*
Y1466939D03*
Y1469702D03*
X1008549Y1509815D03*
X1007049Y1507215D03*
X1011149Y1509815D03*
X1009649Y1507215D03*
Y1512415D03*
X1007049D03*
X1008222Y1514993D03*
X1005622D03*
X1010822D03*
X1023373Y60922D03*
X1018209Y55513D03*
X1020254Y97068D03*
X1014006Y117261D03*
X1021537Y113394D03*
X1024186Y110784D03*
X1024289Y130898D03*
X1025927Y134579D03*
X1021713Y180665D03*
Y172665D03*
X1026915Y203393D03*
X1021745Y212864D03*
Y200864D03*
Y221864D03*
Y216864D03*
X1023502Y252371D03*
X1013354Y323362D03*
X1013327Y327453D03*
X1013318Y333190D03*
X1022845Y340944D03*
X1013313Y339909D03*
X1015195Y428305D03*
X1015804Y760454D03*
X1026090Y770943D03*
X1019375Y783056D03*
X1018044Y793592D03*
X1015800Y807535D03*
X1014587Y802788D03*
X1025859Y802275D03*
X1020703Y833659D03*
X1021221Y848712D03*
X1025219Y842155D03*
X1025239Y845070D03*
X1022009Y997860D03*
X1018009D03*
X1026009D03*
X1014009D03*
X1014767Y1035088D03*
X1022594Y1035114D03*
X1017297Y1102091D03*
X1026606Y1102591D03*
X1023106Y1102091D03*
X1017297Y1114691D03*
X1023106D03*
X1026606D03*
X1023106Y1127291D03*
X1026606D03*
X1017297Y1139891D03*
X1023106D03*
X1026606D03*
X1017297Y1127291D03*
X1026606Y1152491D03*
X1017297D03*
X1023106D03*
X1017297Y1165091D03*
X1023106D03*
X1026606D03*
X1017297Y1177691D03*
X1023106D03*
X1026606D03*
X1022420Y1203204D03*
X1026968Y1223749D03*
X1025434Y1320606D03*
X1011829Y1347471D03*
Y1342515D03*
X1015286Y1344924D03*
X1021623Y1373216D03*
X1012338Y1388597D03*
Y1391597D03*
X1015338D03*
Y1388597D03*
X1021338D03*
Y1391597D03*
X1018338D03*
Y1388597D03*
X1027338D03*
Y1391597D03*
X1024338D03*
Y1388597D03*
X1025138Y1463839D03*
Y1460839D03*
Y1457839D03*
Y1454839D03*
Y1466839D03*
Y1469602D03*
X1013749Y1509815D03*
X1016349D03*
X1021549D03*
X1018949D03*
X1024149D03*
X1022649Y1507215D03*
X1025249D03*
X1017449D03*
X1020049D03*
X1014849D03*
X1012249D03*
X1026749Y1509815D03*
X1012249Y1512415D03*
X1014849D03*
X1025249D03*
X1022649D03*
X1020049D03*
X1017449D03*
X1013422Y1514993D03*
X1023822D03*
X1021222D03*
X1018622D03*
X1016022D03*
X1026422D03*
X1011457Y1639797D03*
X1036772Y109172D03*
X1039772D03*
X1038779Y106495D03*
X1042523Y116497D03*
X1031780Y133298D03*
X1042523Y130670D03*
Y123584D03*
X1038513Y146012D03*
X1040419Y141228D03*
X1042523Y137757D03*
X1043307Y150847D03*
X1037984Y253198D03*
X1031354Y325901D03*
X1031382Y340947D03*
X1031310Y337888D03*
X1031377Y333671D03*
X1031362Y329268D03*
X1038796Y763272D03*
X1042880Y794924D03*
X1028155Y879413D03*
X1030300Y881400D03*
X1043252Y902501D03*
X1030009Y997860D03*
X1034009D03*
X1038252Y1009354D03*
X1034752D03*
X1028943D03*
X1042009Y997860D03*
X1038009D03*
X1034752Y1021954D03*
X1038252D03*
X1043553Y1035384D03*
X1040600Y1210600D03*
X1035384Y1215195D03*
X1034513Y1333665D03*
X1042586Y1345824D03*
X1030338Y1391597D03*
Y1388597D03*
X1029349Y1509815D03*
X1027849Y1507215D03*
Y1512415D03*
X1031457Y1639797D03*
X1049823Y109410D03*
X1054523Y116496D03*
Y109410D03*
Y102323D03*
X1049823Y116497D03*
X1047323D03*
X1049823Y130670D03*
X1047323D03*
Y123584D03*
X1049823Y123583D03*
X1054523Y130670D03*
Y123583D03*
Y137756D03*
X1047323Y137757D03*
X1045275Y247292D03*
X1050777Y450750D03*
X1054876Y536382D03*
X1059843Y597580D03*
X1059782Y594668D03*
X1062098Y615600D03*
X1044112Y778835D03*
X1045744Y800835D03*
X1048328Y808166D03*
X1057961Y931919D03*
X1046009Y997860D03*
X1054009D03*
X1050009D03*
X1058009D03*
X1059689Y1012354D03*
Y1024954D03*
X1048043Y1105091D03*
Y1117691D03*
Y1130291D03*
Y1155491D03*
Y1142891D03*
Y1168091D03*
Y1180691D03*
X1051249Y1290288D03*
X1052221Y1336984D03*
X1058891Y1345691D03*
Y1350683D03*
X1053935Y1345691D03*
Y1350683D03*
X1058891Y1362595D03*
X1053935D03*
X1058891Y1357603D03*
X1053935D03*
X1058891Y1381801D03*
Y1374881D03*
Y1369889D03*
X1053935Y1381801D03*
Y1374881D03*
Y1369889D03*
X1058891Y1386793D03*
X1053935D03*
X1051457Y1639797D03*
X1071988Y-66722D03*
X1075241Y-66808D03*
X1072003Y-64207D03*
X1075256Y-64293D03*
X1062985Y82984D03*
Y75184D03*
Y77784D03*
Y80384D03*
X1065539Y92849D03*
X1062985Y85584D03*
X1072499Y103037D03*
X1072633Y116496D03*
Y109410D03*
Y130670D03*
Y123583D03*
X1069224Y137756D03*
X1074814Y293796D03*
X1061325Y339509D03*
X1060679Y360151D03*
Y364276D03*
X1071548Y555234D03*
X1071263Y562003D03*
X1062066Y599588D03*
X1061328Y589556D03*
X1061267Y592354D03*
X1062069Y596095D03*
X1062066Y607588D03*
X1066559Y634946D03*
X1066009Y997860D03*
X1062009D03*
X1074009D03*
X1070778Y1012252D03*
X1066933Y1040567D03*
X1071641Y1058029D03*
X1060172Y1050481D03*
X1071348Y1050503D03*
X1066175Y1350683D03*
Y1345691D03*
X1071131Y1350683D03*
Y1345691D03*
X1066175Y1357603D03*
Y1362595D03*
X1071131Y1357603D03*
Y1362595D03*
X1066175Y1381801D03*
Y1369795D03*
Y1374881D03*
X1071131Y1381801D03*
Y1369795D03*
Y1374881D03*
X1066175Y1393993D03*
Y1399079D03*
Y1386793D03*
X1071131Y1399079D03*
Y1393993D03*
Y1386793D03*
X1066175Y1405999D03*
Y1410991D03*
X1071131Y1405999D03*
Y1410991D03*
X1071457Y1639797D03*
X1078281Y-65613D03*
X1089916Y94017D03*
X1085916D03*
X1090044Y110445D03*
Y115401D03*
Y124618D03*
Y129574D03*
X1087957Y151540D03*
X1091607Y191941D03*
X1091474Y188727D03*
X1085431Y226141D03*
X1088231D03*
X1088128Y285690D03*
Y288190D03*
X1085328D03*
X1082828Y285690D03*
X1085328D03*
X1082828Y288190D03*
X1077314Y293796D03*
X1092354Y290755D03*
X1077602Y314060D03*
X1091542Y389154D03*
Y410413D03*
Y396240D03*
Y403327D03*
Y417500D03*
Y424587D03*
Y431673D03*
Y438760D03*
Y445847D03*
Y467539D03*
Y474626D03*
Y488799D03*
Y481713D03*
Y495886D03*
Y511673D03*
Y518760D03*
Y525847D03*
Y532933D03*
Y540020D03*
Y547106D03*
X1090823Y602197D03*
X1091287Y595108D03*
X1079809Y1034386D03*
X1090655Y1350683D03*
Y1345691D03*
X1083371D03*
Y1350683D03*
X1078415Y1345691D03*
Y1350683D03*
X1090655Y1357603D03*
Y1362595D03*
X1083371Y1357603D03*
Y1362595D03*
X1078415D03*
Y1357603D03*
X1090655Y1381801D03*
Y1374881D03*
Y1369889D03*
X1083371D03*
Y1374881D03*
Y1381801D03*
X1078415Y1369889D03*
Y1374881D03*
Y1381801D03*
X1090655Y1394087D03*
Y1399079D03*
Y1386793D03*
X1083371D03*
Y1399079D03*
Y1394087D03*
X1078415Y1386793D03*
Y1394087D03*
Y1399079D03*
X1090655Y1405999D03*
Y1410991D03*
X1083371Y1405999D03*
Y1410991D03*
X1078415Y1405999D03*
Y1410991D03*
X1092000Y1644980D03*
X1102993Y84140D03*
Y76140D03*
Y80140D03*
X1097925Y94017D03*
X1093916D03*
X1100446Y117557D03*
X1095036Y115401D03*
Y110445D03*
X1105438Y117557D03*
X1095036Y129574D03*
Y124618D03*
X1105438Y131731D03*
Y122513D03*
X1100446Y131731D03*
Y122513D03*
X1103537Y146461D03*
X1100446Y136687D03*
X1105438D03*
X1102439Y152367D03*
X1104139Y180572D03*
X1108822Y180527D03*
X1104139Y185165D03*
X1108777Y185121D03*
X1098107Y184619D03*
X1100087Y206760D03*
X1101301Y256535D03*
X1093301D03*
X1102331Y279208D03*
X1106435Y281307D03*
X1096354Y290755D03*
X1100354D03*
X1100703Y340560D03*
X1101999Y353495D03*
X1093994Y374003D03*
X1106161Y389154D03*
X1104691Y396240D03*
X1108776Y422864D03*
X1108846Y429832D03*
X1108451Y436447D03*
X1108395Y472772D03*
X1105002Y516841D03*
X1108253Y510565D03*
X1099949Y550123D03*
X1099827Y552872D03*
X1101581Y572334D03*
X1099272Y562443D03*
X1101040Y560675D03*
X1099813Y574102D03*
X1104448Y653161D03*
X1108045Y677843D03*
X1107851Y1345691D03*
X1102895Y1350683D03*
Y1345691D03*
X1107851Y1350683D03*
X1095611D03*
Y1345691D03*
X1107851Y1357603D03*
X1102895Y1362595D03*
Y1357603D03*
X1107851Y1362595D03*
X1095611Y1357603D03*
Y1362595D03*
X1107851Y1369889D03*
Y1374881D03*
Y1381801D03*
X1102895Y1374881D03*
Y1369889D03*
Y1381801D03*
X1095611D03*
Y1374881D03*
Y1369889D03*
X1107851Y1386793D03*
Y1394087D03*
Y1399079D03*
X1102895Y1386793D03*
Y1394087D03*
Y1399079D03*
X1095611D03*
Y1394087D03*
Y1386793D03*
X1107851Y1405999D03*
Y1410991D03*
X1102895Y1405999D03*
Y1410991D03*
X1095611Y1405999D03*
Y1410991D03*
X1099900Y1535700D03*
X1107620Y1606752D03*
X1123052Y57511D03*
X1122613Y97042D03*
X1116368Y117261D03*
X1123899Y113394D03*
X1124075Y180665D03*
Y172665D03*
X1112545Y192421D03*
X1124107Y200864D03*
Y212864D03*
Y216864D03*
Y221864D03*
X1123500Y329000D03*
Y339000D03*
Y334000D03*
X1124753Y389153D03*
X1122253Y396240D03*
X1124753D03*
X1122253Y403327D03*
X1124753Y403326D03*
X1122253Y410413D03*
X1124753D03*
X1109468Y414823D03*
X1122253Y424586D03*
X1124753D03*
X1122253Y417500D03*
X1124753Y417499D03*
X1122253Y438760D03*
X1124753D03*
Y431673D03*
X1122253D03*
X1110486Y447953D03*
X1122253Y445847D03*
X1109653Y467539D03*
X1124753D03*
X1122253Y474626D03*
X1124753D03*
X1122253Y488799D03*
X1124753D03*
X1109129Y487711D03*
X1109242Y479104D03*
X1124753Y481712D03*
X1122253D03*
Y495886D03*
X1109653D03*
X1124753Y518760D03*
X1122253D03*
X1124753Y511673D03*
Y532933D03*
X1122253D03*
Y540020D03*
Y525846D03*
X1124753D03*
X1118863Y662981D03*
X1112839Y668885D03*
X1113244Y691851D03*
X1118855Y705043D03*
X1115135Y1345691D03*
Y1350683D03*
X1120091Y1345691D03*
Y1350683D03*
X1115135Y1357603D03*
Y1362595D03*
X1120091Y1357603D03*
Y1362595D03*
X1115135Y1374881D03*
Y1381801D03*
Y1369889D03*
X1120091D03*
Y1374881D03*
Y1381801D03*
X1115135Y1394087D03*
Y1399079D03*
Y1386793D03*
X1120091Y1399079D03*
Y1394087D03*
Y1386793D03*
X1115135Y1405999D03*
Y1410991D03*
X1120091Y1405999D03*
Y1410991D03*
X1112000Y1644980D03*
X1125735Y60922D03*
X1139134Y109172D03*
X1141141Y106495D03*
X1126548Y110784D03*
X1134142Y133298D03*
X1126142D03*
X1140875Y146012D03*
X1128289Y134579D03*
X1129277Y203393D03*
X1140346Y253198D03*
X1125864Y252371D03*
X1129553Y389153D03*
Y396240D03*
Y403326D03*
Y410413D03*
Y424586D03*
Y417499D03*
Y431673D03*
Y438760D03*
X1126931Y453564D03*
X1130355Y453483D03*
X1129553Y467539D03*
X1125178Y459792D03*
X1129553Y474626D03*
Y488799D03*
Y481712D03*
Y518760D03*
Y511673D03*
Y532933D03*
Y525846D03*
X1138098Y543925D03*
X1138673Y555000D03*
X1126633Y560500D03*
X1139615Y1350683D03*
Y1345691D03*
X1132331D03*
Y1350683D03*
X1127375D03*
Y1345691D03*
X1139615Y1357603D03*
Y1362595D03*
X1132331D03*
Y1357603D03*
X1127375D03*
Y1362595D03*
X1139615Y1374881D03*
Y1369889D03*
Y1381801D03*
X1132331Y1369889D03*
Y1381801D03*
Y1374881D03*
X1127375Y1369889D03*
Y1381801D03*
Y1374881D03*
X1139615Y1394087D03*
Y1399079D03*
Y1386793D03*
X1132331D03*
Y1394087D03*
Y1399079D03*
X1127375Y1386793D03*
Y1394087D03*
Y1399079D03*
X1139615Y1405999D03*
Y1410991D03*
X1132331Y1405999D03*
Y1410991D03*
X1127375Y1405999D03*
Y1410991D03*
X1129637Y1465913D03*
Y1461182D03*
Y1456451D03*
X1138298Y1465513D03*
Y1460782D03*
X1129637Y1476536D03*
Y1481267D03*
X1138298Y1476136D03*
Y1470244D03*
Y1480867D03*
X1129637Y1471805D03*
Y1496621D03*
X1138298Y1491490D03*
Y1485598D03*
Y1496221D03*
X1129637Y1491890D03*
Y1487159D03*
X1138298Y1500952D03*
Y1511576D03*
X1129637Y1507245D03*
Y1502514D03*
Y1511976D03*
X1138298Y1506845D03*
Y1516307D03*
X1129637Y1563544D03*
Y1558813D03*
X1138298Y1563144D03*
Y1572606D03*
X1129637Y1568275D03*
Y1578898D03*
Y1574167D03*
X1138298Y1567875D03*
Y1578498D03*
X1129637Y1583629D03*
Y1594253D03*
Y1589522D03*
X1138298Y1583229D03*
Y1593853D03*
Y1587960D03*
Y1598584D03*
Y1603315D03*
X1129637Y1609607D03*
Y1598984D03*
Y1604876D03*
X1138298Y1609207D03*
X1129637Y1614338D03*
X1138298Y1613938D03*
Y1618669D03*
X1132000Y1644980D03*
X1142134Y109172D03*
X1156885Y116496D03*
Y102323D03*
Y109410D03*
X1152185D03*
Y116497D03*
X1149685D03*
X1144885D03*
X1152185Y130670D03*
X1149685D03*
Y123584D03*
X1152185Y123583D03*
X1144885Y130670D03*
Y123584D03*
X1156885Y130670D03*
Y123583D03*
X1142781Y141228D03*
X1156885Y137756D03*
X1149685Y137757D03*
X1144885D03*
X1145669Y150847D03*
X1147637Y247292D03*
X1145761Y324148D03*
X1157251Y636842D03*
X1156023Y678462D03*
X1149345Y771517D03*
X1145910Y794217D03*
X1151277Y790996D03*
X1149627Y813323D03*
X1146985Y812642D03*
X1152510Y844642D03*
X1156811Y1350683D03*
Y1345691D03*
X1151855D03*
Y1350683D03*
X1144571D03*
Y1345691D03*
X1156811Y1357603D03*
Y1362595D03*
X1151855D03*
Y1357603D03*
X1144571D03*
Y1362595D03*
X1156811Y1374881D03*
Y1369889D03*
Y1381801D03*
X1151855Y1374881D03*
Y1369889D03*
Y1381801D03*
X1144571Y1369889D03*
Y1381801D03*
Y1374881D03*
X1156811Y1386793D03*
Y1399079D03*
Y1394087D03*
X1151855Y1386793D03*
Y1399079D03*
Y1394087D03*
X1144571D03*
Y1399079D03*
Y1386793D03*
X1156811Y1405999D03*
Y1410991D03*
X1151855Y1405999D03*
Y1410991D03*
X1144571Y1405999D03*
Y1410991D03*
X1146960Y1465913D03*
Y1461182D03*
X1155621Y1465513D03*
Y1460782D03*
X1146960Y1456451D03*
X1155621Y1480867D03*
X1146960Y1471805D03*
Y1476536D03*
Y1481267D03*
X1155621Y1476136D03*
Y1470244D03*
Y1491490D03*
Y1485598D03*
Y1496221D03*
X1146960Y1487159D03*
Y1491890D03*
Y1496621D03*
Y1507245D03*
Y1502514D03*
X1155621Y1506845D03*
Y1500952D03*
Y1511576D03*
X1146960Y1511976D03*
X1155621Y1516307D03*
X1146960Y1563544D03*
X1155621Y1563144D03*
X1146960Y1558813D03*
X1155621Y1572606D03*
X1146960Y1568275D03*
X1155621Y1567875D03*
X1146960Y1574167D03*
Y1578898D03*
X1155621Y1578498D03*
X1146960Y1594253D03*
X1155621Y1593853D03*
Y1587960D03*
X1146960Y1583629D03*
X1155621Y1583229D03*
X1146960Y1589522D03*
Y1609607D03*
Y1604876D03*
Y1598984D03*
X1155621Y1609207D03*
Y1598584D03*
Y1603315D03*
X1146960Y1614338D03*
X1155621Y1613938D03*
Y1618669D03*
X1152000Y1644980D03*
X1165347Y82984D03*
Y75184D03*
Y77784D03*
Y80384D03*
X1167756Y92734D03*
X1165347Y85584D03*
X1171586Y137756D03*
X1168902Y431029D03*
X1167931Y435029D03*
X1169173Y427017D03*
X1168851Y449873D03*
X1171255Y456287D03*
X1173278Y472579D03*
X1168478D03*
X1173278Y479666D03*
X1168478D03*
Y486752D03*
X1173278D03*
X1168478Y493839D03*
X1173278D03*
X1168478Y523800D03*
Y516713D03*
X1173278D03*
Y523800D03*
Y537973D03*
X1168478D03*
X1173278Y530886D03*
X1168478D03*
X1173278Y566752D03*
X1168478D03*
Y580926D03*
X1173278D03*
Y588013D03*
X1168478D03*
X1173278Y573839D03*
X1168478D03*
Y602186D03*
X1173278D03*
Y595099D03*
X1168478D03*
X1173278Y609272D03*
X1168478D03*
Y616359D03*
X1173278D03*
X1163157Y638125D03*
X1160756Y665140D03*
X1157985Y791142D03*
X1161291Y791662D03*
X1173697Y791911D03*
X1160516Y800900D03*
X1169051Y1345597D03*
Y1350683D03*
X1164095D03*
Y1345597D03*
X1169051Y1357603D03*
Y1362595D03*
X1164095Y1357603D03*
Y1362595D03*
X1169051Y1381801D03*
Y1374881D03*
Y1369889D03*
X1164095D03*
Y1381801D03*
Y1374881D03*
X1169051Y1393993D03*
Y1399079D03*
Y1386793D03*
X1164095Y1393993D03*
Y1399079D03*
Y1386793D03*
X1169051Y1410991D03*
Y1405999D03*
X1164095D03*
Y1410991D03*
X1164283Y1465913D03*
Y1456451D03*
Y1461182D03*
X1172944Y1465513D03*
Y1460782D03*
Y1470244D03*
Y1480867D03*
X1164283Y1471805D03*
Y1476536D03*
Y1481267D03*
X1172944Y1476136D03*
X1164283Y1487159D03*
Y1491890D03*
Y1496621D03*
X1172944Y1491490D03*
Y1485598D03*
Y1496221D03*
X1164283Y1507245D03*
Y1502514D03*
X1172944Y1506845D03*
Y1500952D03*
Y1511576D03*
X1164283Y1511976D03*
X1172944Y1516307D03*
X1164283Y1558813D03*
Y1563544D03*
X1172944Y1563144D03*
Y1567875D03*
X1164283Y1574167D03*
Y1578898D03*
X1172944Y1578498D03*
Y1572606D03*
X1164283Y1568275D03*
Y1583629D03*
X1172944Y1583229D03*
X1164283Y1589522D03*
Y1594253D03*
X1172944Y1593853D03*
Y1587960D03*
Y1598584D03*
Y1603315D03*
X1164283Y1609607D03*
Y1604876D03*
Y1598984D03*
X1172944Y1609207D03*
X1164283Y1614338D03*
X1172944Y1613938D03*
Y1618669D03*
X1172000Y1644980D03*
X1188278Y94017D03*
X1174861Y103037D03*
X1174995Y116496D03*
Y109410D03*
Y130670D03*
Y123583D03*
X1187793Y226141D03*
X1190593D03*
X1179676Y293796D03*
X1187690Y288190D03*
X1185190Y285690D03*
X1187690D03*
X1185190Y288190D03*
X1177176Y293796D03*
X1182911Y336516D03*
X1177036Y334148D03*
X1188598Y390500D03*
X1179184Y410394D03*
Y403307D03*
X1180578Y458406D03*
Y451319D03*
X1180402Y462264D03*
X1175778Y465492D03*
X1180578D03*
X1175778Y472579D03*
X1180578D03*
X1175778Y479666D03*
X1180578Y479665D03*
Y486752D03*
X1175778D03*
X1180578Y493839D03*
X1175778Y509626D03*
X1180578Y523799D03*
Y516713D03*
Y509626D03*
X1175778Y516713D03*
Y523800D03*
X1180578Y537973D03*
X1175778Y530886D03*
X1180578D03*
Y559665D03*
Y566752D03*
X1175778D03*
Y559665D03*
Y580926D03*
X1180578D03*
Y588012D03*
X1175778D03*
X1180578Y573839D03*
X1175778D03*
Y602185D03*
X1180578D03*
X1175778Y595099D03*
X1180578D03*
X1175778Y609272D03*
X1180578Y616358D03*
Y609272D03*
X1177745Y771744D03*
X1177566Y778539D03*
X1190062Y844378D03*
X1187703Y849734D03*
X1186742Y855466D03*
X1183431Y868340D03*
X1177775Y894053D03*
X1178480Y915220D03*
X1178000Y936500D03*
X1187200Y963400D03*
X1181291Y1350683D03*
Y1345691D03*
X1176335D03*
Y1350683D03*
X1181291Y1362595D03*
Y1357603D03*
X1176335Y1362595D03*
Y1357603D03*
X1181291Y1369889D03*
Y1381801D03*
Y1374881D03*
X1176335Y1369889D03*
Y1381801D03*
Y1374881D03*
X1181291Y1386793D03*
Y1399079D03*
Y1394087D03*
X1176335Y1386793D03*
Y1399079D03*
Y1394087D03*
X1181291Y1405999D03*
Y1410991D03*
X1176335Y1405999D03*
Y1410991D03*
X1181605Y1465913D03*
Y1456451D03*
Y1461182D03*
Y1471805D03*
Y1476536D03*
Y1481267D03*
Y1487159D03*
Y1491890D03*
Y1496621D03*
Y1507245D03*
Y1502514D03*
Y1511976D03*
Y1558813D03*
Y1563544D03*
Y1568275D03*
Y1574167D03*
Y1578898D03*
Y1583629D03*
Y1589522D03*
Y1594253D03*
Y1598984D03*
Y1609607D03*
Y1604876D03*
Y1614338D03*
X1205355Y84140D03*
Y76140D03*
Y80140D03*
X1196278Y94017D03*
X1200287D03*
X1192278D03*
X1202808Y117557D03*
X1197398Y110445D03*
Y115401D03*
X1192406Y110445D03*
Y115401D03*
X1197398Y129574D03*
Y124618D03*
X1192406D03*
Y129574D03*
X1202808Y122513D03*
Y131731D03*
X1205899Y146461D03*
X1202808Y136687D03*
X1204801Y152367D03*
X1190319Y151540D03*
X1200469Y184619D03*
X1193969Y191941D03*
X1193836Y188727D03*
X1202449Y206760D03*
X1203663Y256535D03*
X1195663D03*
X1204693Y279208D03*
X1194716Y290755D03*
X1202716D03*
X1190490Y285690D03*
Y288190D03*
X1198716Y290755D03*
X1198248Y381500D03*
X1198689Y465492D03*
X1198655Y460250D03*
X1196420Y470136D03*
X1198689Y472579D03*
Y486752D03*
Y479665D03*
Y493839D03*
Y509626D03*
Y516713D03*
X1195149Y537973D03*
X1197629Y525483D03*
X1197550Y532756D03*
X1198689Y559665D03*
Y566752D03*
X1198539Y579978D03*
X1198689Y573839D03*
X1198753Y608117D03*
X1198997Y790610D03*
X1198845Y998504D03*
X1204919Y1021860D03*
X1202268Y1013551D03*
X1190267Y1465513D03*
Y1460782D03*
X1198928Y1465914D03*
Y1456452D03*
Y1461183D03*
Y1481268D03*
X1190267Y1476136D03*
Y1470244D03*
Y1480867D03*
X1198928Y1476537D03*
Y1471806D03*
X1190267Y1485598D03*
Y1496221D03*
X1198928Y1491891D03*
Y1487160D03*
Y1496622D03*
X1190267Y1491490D03*
Y1506845D03*
Y1500952D03*
Y1511576D03*
X1198928Y1507246D03*
Y1502515D03*
Y1511977D03*
X1190267Y1516307D03*
X1198928Y1558813D03*
X1190267Y1563144D03*
X1198928Y1563544D03*
X1190267Y1567875D03*
X1198928Y1568275D03*
X1190267Y1578498D03*
Y1572606D03*
X1198928Y1578898D03*
Y1574167D03*
X1190267Y1583229D03*
X1198928Y1583629D03*
X1190267Y1593853D03*
Y1587960D03*
X1198928Y1594253D03*
Y1589522D03*
X1190267Y1609207D03*
Y1598584D03*
Y1603315D03*
X1198928Y1609607D03*
Y1598984D03*
Y1604876D03*
X1190267Y1613938D03*
Y1618669D03*
X1198928Y1614338D03*
X1192000Y1644980D03*
X1218730Y117261D03*
X1207800Y117557D03*
Y122513D03*
Y131731D03*
Y136687D03*
X1206501Y180572D03*
X1211184Y180527D03*
X1214907Y192421D03*
X1206501Y185165D03*
X1211139Y185121D03*
X1208797Y281307D03*
X1220985Y342319D03*
X1212680Y445908D03*
X1216630Y445787D03*
X1212000Y1644980D03*
X1222933Y55513D03*
X1228097Y60922D03*
X1225041Y97080D03*
X1228910Y110784D03*
X1226261Y113394D03*
X1229195Y130898D03*
X1236504Y133298D03*
X1230651Y134579D03*
X1226437Y180665D03*
Y172665D03*
X1226469Y200864D03*
Y212864D03*
Y216864D03*
Y221864D03*
X1228226Y252371D03*
X1238055Y303839D03*
X1230077Y336324D03*
X1234656Y353506D03*
X1223431Y393924D03*
Y389912D03*
Y385912D03*
Y409924D03*
Y405924D03*
Y401924D03*
X1229548Y1350683D03*
Y1345691D03*
X1234504D03*
Y1350683D03*
X1229548Y1362595D03*
Y1357603D03*
X1234504D03*
Y1362595D03*
X1229548Y1369889D03*
Y1374881D03*
Y1381801D03*
X1234504Y1369889D03*
Y1374881D03*
Y1381801D03*
X1229548Y1386793D03*
X1234504D03*
X1232000Y1644980D03*
X1243503Y106495D03*
X1244496Y109172D03*
X1241496D03*
X1247247Y116497D03*
X1254547Y109410D03*
Y116497D03*
X1252047D03*
X1247247Y123584D03*
Y130670D03*
X1252047Y123584D03*
X1254547Y123583D03*
Y130670D03*
X1252047D03*
X1243237Y146012D03*
X1245143Y141228D03*
X1247247Y137757D03*
X1252047D03*
X1250307Y140296D03*
X1248031Y150847D03*
X1249999Y247292D03*
X1242708Y253198D03*
X1248064Y567813D03*
Y572769D03*
Y581987D03*
Y586943D03*
Y601116D03*
Y596160D03*
Y615289D03*
Y610333D03*
X1246800Y1001600D03*
X1249200Y1014000D03*
X1248721Y1025864D03*
X1251802Y1186071D03*
X1254028Y1350683D03*
Y1345691D03*
X1241788D03*
Y1350683D03*
X1246744Y1345691D03*
Y1350683D03*
X1254028Y1357603D03*
Y1362595D03*
X1241788D03*
Y1357603D03*
X1246744Y1362595D03*
Y1357603D03*
X1254028Y1381801D03*
Y1374881D03*
Y1369889D03*
X1241788Y1374881D03*
Y1369795D03*
Y1381801D03*
X1246744Y1374881D03*
Y1369795D03*
Y1381801D03*
X1254028Y1386793D03*
Y1399079D03*
Y1394087D03*
X1241788Y1399079D03*
Y1393993D03*
Y1386793D03*
X1246744Y1393993D03*
Y1399079D03*
Y1386793D03*
X1254028Y1410991D03*
Y1405999D03*
X1241788Y1410991D03*
Y1405999D03*
X1246744Y1410991D03*
Y1405999D03*
X1245900Y1528000D03*
X1267709Y82984D03*
Y75184D03*
Y77784D03*
Y80384D03*
X1270263Y92849D03*
X1267709Y85584D03*
X1259247Y116496D03*
Y102323D03*
Y109410D03*
Y130670D03*
Y123583D03*
Y137756D03*
X1258925Y324075D03*
X1270951Y491870D03*
X1270515Y908277D03*
X1269876Y1132319D03*
X1263873Y1148000D03*
X1266709Y1160168D03*
X1258736Y1188223D03*
X1268573Y1193019D03*
X1264573D03*
X1266268Y1345691D03*
Y1350683D03*
X1258984D03*
Y1345691D03*
X1266268Y1362595D03*
Y1357603D03*
X1258984Y1362595D03*
Y1357603D03*
X1266268Y1369889D03*
Y1374881D03*
Y1381801D03*
X1258984D03*
Y1369889D03*
Y1374881D03*
X1266268Y1399079D03*
Y1394087D03*
Y1386793D03*
X1258984Y1394087D03*
Y1386793D03*
Y1399079D03*
X1266268Y1410991D03*
Y1405999D03*
X1258984D03*
Y1410991D03*
X1263242Y1523458D03*
X1262985Y1519459D03*
X1260260Y1546500D03*
X1277223Y103037D03*
X1277357Y116496D03*
Y109410D03*
Y130670D03*
Y123583D03*
X1273555Y137756D03*
X1279538Y293796D03*
X1282038D03*
X1283494Y339495D03*
X1287437Y370010D03*
X1280616Y472189D03*
X1273451Y491870D03*
X1279539Y772576D03*
Y776576D03*
X1274417Y861964D03*
X1282317Y880193D03*
X1285493Y892175D03*
X1277039Y916484D03*
X1284021Y940008D03*
X1273865Y1132497D03*
X1282830Y1146937D03*
X1272120Y1159455D03*
X1280306Y1162817D03*
X1276573Y1193019D03*
X1280573D03*
X1272573D03*
X1277108Y1211664D03*
X1279402Y1213958D03*
X1275032Y1209589D03*
X1284198Y1218754D03*
X1283464Y1345691D03*
Y1350683D03*
X1278508Y1345691D03*
Y1350683D03*
X1271224Y1345691D03*
Y1350683D03*
X1283464Y1362595D03*
Y1357603D03*
X1278508D03*
Y1362595D03*
X1271224D03*
Y1357603D03*
X1283464Y1381801D03*
Y1369889D03*
Y1374881D03*
X1278508Y1381801D03*
Y1369889D03*
Y1374881D03*
X1271224Y1369889D03*
Y1374881D03*
Y1381801D03*
X1283464Y1386793D03*
Y1399079D03*
Y1394087D03*
X1278508Y1386793D03*
Y1399079D03*
Y1394087D03*
X1271224D03*
Y1399079D03*
Y1386793D03*
X1283464Y1410991D03*
Y1405999D03*
X1278508Y1410991D03*
Y1405999D03*
X1271224Y1410991D03*
Y1405999D03*
X1291756Y-25143D03*
X1288503Y-25157D03*
X1291741Y-27658D03*
X1288488Y-27672D03*
X1294781Y-26463D03*
X1302649Y94017D03*
X1298640D03*
X1290640D03*
X1294640D03*
X1299760Y110445D03*
Y115401D03*
X1294768Y110445D03*
Y115401D03*
Y129574D03*
X1299760D03*
Y124618D03*
X1294768D03*
X1296331Y191941D03*
X1302831Y184619D03*
X1296198Y188727D03*
X1292955Y226141D03*
X1290155D03*
X1298025Y256535D03*
X1290052Y288190D03*
X1292852D03*
Y285690D03*
X1305078Y290755D03*
X1297078D03*
X1301078D03*
X1287552Y288190D03*
X1290052Y285690D03*
X1287552D03*
X1294425Y321425D03*
X1299959Y351454D03*
X1296783Y511956D03*
X1303520Y748403D03*
X1300516Y832047D03*
X1300504Y835985D03*
X1300204Y859088D03*
X1300097Y851193D03*
X1300091Y854824D03*
X1291955Y901295D03*
X1289547Y928047D03*
X1298090Y940852D03*
X1295453Y940953D03*
X1302988Y1345691D03*
Y1350683D03*
X1290748D03*
Y1345691D03*
X1295704Y1350683D03*
Y1345691D03*
X1302988Y1362595D03*
Y1357603D03*
X1290748Y1362595D03*
Y1357603D03*
X1295704Y1362595D03*
Y1357603D03*
X1302988Y1374881D03*
Y1381801D03*
Y1369889D03*
X1290748D03*
Y1381801D03*
Y1374881D03*
X1295704Y1381801D03*
Y1374881D03*
Y1369889D03*
X1302988Y1386793D03*
Y1399079D03*
Y1394087D03*
X1290748Y1399079D03*
Y1394087D03*
Y1386793D03*
X1295704Y1394087D03*
Y1399079D03*
Y1386793D03*
X1302988Y1410991D03*
Y1405999D03*
X1290748Y1410991D03*
Y1405999D03*
X1295704Y1410991D03*
Y1405999D03*
X1302866Y1461182D03*
Y1456451D03*
Y1465913D03*
Y1476536D03*
Y1471805D03*
Y1481267D03*
Y1491890D03*
Y1487159D03*
Y1496621D03*
Y1507245D03*
Y1502514D03*
Y1511976D03*
Y1558813D03*
Y1563544D03*
Y1578898D03*
Y1574167D03*
Y1568275D03*
Y1594253D03*
Y1589522D03*
Y1583629D03*
Y1609607D03*
Y1598984D03*
Y1604876D03*
Y1614338D03*
X1292000Y1644980D03*
X1307717Y84140D03*
Y76140D03*
Y80140D03*
X1310162Y117557D03*
X1305170D03*
X1310162Y122513D03*
Y131731D03*
X1305170Y122513D03*
Y131731D03*
X1310162Y136687D03*
X1305170D03*
X1313546Y180527D03*
X1308863Y180572D03*
Y185165D03*
X1317269Y192421D03*
X1313501Y185121D03*
X1304811Y206760D03*
X1306025Y256535D03*
X1307055Y279208D03*
X1311159Y281307D03*
X1314569Y318013D03*
X1312069D03*
X1317584Y313058D03*
X1316017Y349889D03*
X1308410Y370899D03*
X1313691Y402642D03*
X1316191D03*
X1309117Y398949D03*
X1306617Y401949D03*
X1308066Y413611D03*
X1310866D03*
X1313366D03*
X1315866D03*
X1315806Y423944D03*
X1313306D03*
X1310806D03*
X1308006D03*
X1307919Y478382D03*
X1307825Y482382D03*
X1305134Y812065D03*
X1313756Y829871D03*
X1308857Y836076D03*
X1316906Y842470D03*
Y867665D03*
Y883413D03*
Y892862D03*
X1316893Y925603D03*
X1318375Y943951D03*
X1303907Y960093D03*
X1307580Y990314D03*
X1304664Y1023462D03*
X1309937Y1037038D03*
X1319326Y1040723D03*
X1317437Y1152684D03*
X1307167Y1245696D03*
X1308276Y1276446D03*
X1315228Y1345691D03*
Y1350683D03*
X1307944D03*
Y1345691D03*
X1315228Y1362595D03*
Y1357603D03*
X1307944D03*
Y1362595D03*
X1315228Y1381801D03*
Y1369889D03*
Y1374881D03*
X1307944D03*
Y1381801D03*
Y1369889D03*
X1315228Y1399079D03*
Y1394087D03*
Y1386793D03*
X1307944D03*
Y1399079D03*
Y1394087D03*
X1315228Y1410991D03*
Y1405999D03*
X1307944Y1410991D03*
Y1405999D03*
X1311527Y1465513D03*
Y1460782D03*
Y1480867D03*
Y1476136D03*
Y1470244D03*
Y1491490D03*
Y1485598D03*
Y1496221D03*
Y1506845D03*
Y1500952D03*
Y1511576D03*
Y1516307D03*
Y1563144D03*
Y1567875D03*
Y1578498D03*
Y1572606D03*
Y1583229D03*
Y1593853D03*
Y1587960D03*
Y1609207D03*
Y1598584D03*
Y1603315D03*
Y1613938D03*
Y1618669D03*
X1312000Y1644980D03*
X1331756Y-64193D03*
X1328503Y-64207D03*
X1331741Y-66708D03*
X1328488Y-66722D03*
X1334781Y-65513D03*
X1321092Y117261D03*
X1328799Y172665D03*
Y180665D03*
X1328831Y212864D03*
Y200864D03*
Y221864D03*
Y216864D03*
X1330414Y310058D03*
X1325458D03*
X1322540Y313058D03*
X1333332D03*
X1331085Y334347D03*
X1323816D03*
Y341615D03*
X1331085Y348868D03*
X1323816D03*
X1332927Y468607D03*
X1326912Y493153D03*
X1325630Y513238D03*
X1335000Y590500D03*
Y586500D03*
Y633000D03*
Y637000D03*
Y677500D03*
Y681500D03*
Y724500D03*
Y728500D03*
X1324217Y780595D03*
X1332654Y836170D03*
X1323205Y861367D03*
X1335803Y851918D03*
Y877114D03*
X1326355Y886562D03*
X1328457Y959986D03*
X1321104Y964398D03*
X1323554Y967623D03*
X1331890Y1051919D03*
X1331359Y1098898D03*
X1334161Y1098518D03*
X1333905Y1123101D03*
X1331405D03*
X1323405D03*
X1320279Y1131935D03*
Y1134435D03*
Y1136935D03*
Y1139435D03*
X1334305Y1129301D03*
X1331805D03*
X1329305D03*
X1326805D03*
X1324305D03*
X1321805D03*
X1334305Y1125801D03*
X1331805D03*
X1323405D03*
X1320279Y1141935D03*
Y1146935D03*
Y1144435D03*
X1326269Y1152713D03*
Y1155213D03*
X1320493Y1204405D03*
X1334793Y1204617D03*
X1320493Y1206905D03*
Y1211905D03*
Y1209405D03*
X1334793Y1207117D03*
Y1209617D03*
Y1212117D03*
X1330070Y1297498D03*
X1335470D03*
X1332424Y1345691D03*
Y1350683D03*
X1327468D03*
Y1345691D03*
X1320184Y1350683D03*
Y1345691D03*
X1332424Y1362595D03*
Y1357603D03*
X1327468D03*
Y1362595D03*
X1320184D03*
Y1357603D03*
X1332424Y1381801D03*
Y1369889D03*
Y1374881D03*
X1327468Y1381801D03*
Y1369889D03*
Y1374881D03*
X1320184Y1381801D03*
Y1374881D03*
Y1369889D03*
X1332424Y1386793D03*
Y1394087D03*
Y1399079D03*
X1327468Y1386793D03*
Y1394087D03*
Y1399079D03*
X1320184D03*
Y1394087D03*
Y1386793D03*
X1332424Y1410991D03*
Y1405999D03*
X1327468Y1410991D03*
Y1405999D03*
X1320184Y1410991D03*
Y1405999D03*
X1328850Y1465513D03*
Y1460782D03*
X1320189Y1465913D03*
Y1456451D03*
Y1461182D03*
X1328850Y1476136D03*
Y1470244D03*
X1320189Y1481267D03*
X1328850Y1480867D03*
X1320189Y1471805D03*
Y1476536D03*
X1328850Y1491490D03*
Y1485598D03*
X1320189Y1496621D03*
X1328850Y1496221D03*
X1320189Y1487159D03*
Y1491890D03*
Y1502514D03*
X1328850Y1506845D03*
Y1500952D03*
Y1511576D03*
X1320189Y1511976D03*
Y1507245D03*
X1328850Y1516307D03*
X1320189Y1558813D03*
Y1563544D03*
X1328850Y1563144D03*
Y1567875D03*
X1320189Y1574167D03*
Y1578898D03*
X1328850Y1578498D03*
Y1572606D03*
X1320189Y1568275D03*
X1328850Y1583229D03*
X1320189Y1589522D03*
Y1594253D03*
X1328850Y1593853D03*
Y1587960D03*
X1320189Y1583629D03*
X1328850Y1603315D03*
X1320189Y1609607D03*
Y1604876D03*
Y1598984D03*
X1328850Y1609207D03*
Y1598584D03*
Y1613938D03*
Y1618669D03*
X1320189Y1614338D03*
X1332000Y1644980D03*
X1340320Y151540D03*
X1338288Y313058D03*
X1338378Y334347D03*
X1338275Y341603D03*
X1338378Y348830D03*
X1345451Y699032D03*
X1347136Y780040D03*
X1351550Y839320D03*
Y855068D03*
X1345252D03*
X1342103D03*
Y861367D03*
X1338953D03*
Y858218D03*
X1338952Y855067D03*
X1338953Y870814D03*
X1342103Y867665D03*
X1338953D03*
X1351550Y873964D03*
X1345252D03*
X1342103D03*
X1338952Y873965D03*
X1345252Y892862D03*
X1341820Y947407D03*
X1347380Y1057998D03*
Y1055498D03*
X1344880D03*
Y1057998D03*
X1347380Y1060498D03*
Y1062998D03*
X1344880D03*
Y1060498D03*
X1339349Y1098767D03*
X1339305Y1129301D03*
X1336805D03*
X1339305Y1125801D03*
X1336805D03*
X1343505Y1136935D03*
Y1134435D03*
Y1139435D03*
Y1131935D03*
X1349907D03*
Y1134435D03*
Y1136935D03*
Y1139435D03*
X1352407Y1131935D03*
Y1134435D03*
Y1136935D03*
Y1139435D03*
X1343505Y1146935D03*
Y1144435D03*
Y1141935D03*
X1349907D03*
Y1146935D03*
Y1144435D03*
X1352407Y1141935D03*
Y1146935D03*
Y1144435D03*
X1336669Y1152713D03*
Y1155213D03*
X1351405Y1154902D03*
Y1152402D03*
X1347423Y1204405D03*
X1337108Y1200821D03*
Y1198321D03*
X1347423Y1209405D03*
Y1211905D03*
Y1206905D03*
X1340870Y1297498D03*
X1346270D03*
X1351670D03*
X1351948Y1350683D03*
Y1345691D03*
X1339708Y1345597D03*
Y1350683D03*
X1344664Y1345597D03*
Y1350683D03*
X1351948Y1357603D03*
Y1362595D03*
X1339708D03*
Y1357603D03*
X1344664Y1362595D03*
Y1357603D03*
X1351948Y1374881D03*
Y1381801D03*
Y1369889D03*
X1339708Y1374881D03*
Y1381801D03*
Y1369889D03*
X1344664D03*
Y1374881D03*
Y1381801D03*
X1351948Y1386793D03*
Y1394087D03*
Y1399079D03*
X1339708D03*
Y1393993D03*
Y1386793D03*
X1344664Y1393993D03*
Y1399079D03*
Y1386793D03*
X1351948Y1410991D03*
Y1405999D03*
X1339708Y1410991D03*
Y1405999D03*
X1344664Y1410991D03*
Y1405999D03*
X1337512Y1461182D03*
X1346173Y1465513D03*
Y1460782D03*
X1337512Y1465913D03*
Y1456451D03*
X1346173Y1476136D03*
Y1470244D03*
X1337512Y1481267D03*
X1346173Y1480867D03*
X1337512Y1471805D03*
Y1476536D03*
X1346173Y1485598D03*
Y1491490D03*
X1337512Y1487159D03*
Y1491890D03*
Y1496621D03*
X1346173Y1496221D03*
X1337512Y1507245D03*
Y1502514D03*
X1346173Y1506845D03*
Y1500952D03*
Y1511576D03*
X1337512Y1511976D03*
X1346173Y1516307D03*
X1337512Y1558813D03*
Y1563544D03*
X1346173Y1563144D03*
X1337512Y1574167D03*
Y1578898D03*
X1346173Y1578498D03*
Y1572606D03*
X1337512Y1568275D03*
X1346173Y1567875D03*
X1337512Y1583629D03*
X1346173Y1583229D03*
X1337512Y1589522D03*
Y1594253D03*
X1346173Y1593853D03*
Y1587960D03*
X1337512Y1609607D03*
Y1604876D03*
Y1598984D03*
X1346173Y1609207D03*
Y1598584D03*
Y1603315D03*
X1337512Y1614338D03*
X1346173Y1613938D03*
Y1618669D03*
X1352000Y1644980D03*
X1355900Y146461D03*
X1354802Y152367D03*
X1355255Y561032D03*
Y607532D03*
Y652032D03*
X1364148Y836170D03*
X1354699Y855068D03*
X1357849Y861367D03*
X1354699D03*
X1357849Y858218D03*
X1357850Y855067D03*
X1360999Y851918D03*
Y877114D03*
X1357850Y873965D03*
X1354699Y873964D03*
X1357849Y870814D03*
Y867665D03*
X1354699D03*
X1363173Y994483D03*
X1363905Y1000855D03*
X1366493Y1000828D03*
X1367884Y1018825D03*
X1357265Y1022766D03*
X1364237Y1043140D03*
X1357265Y1030266D03*
X1363941Y1047047D03*
X1366289Y1098518D03*
X1361037Y1098428D03*
X1355533Y1123101D03*
X1363533D03*
X1366033D03*
X1366433Y1129301D03*
X1355533Y1125801D03*
X1363933D03*
X1366433D03*
X1353933Y1129301D03*
X1356433D03*
X1358933D03*
X1361433D03*
X1363933D03*
X1357397Y1155213D03*
Y1152713D03*
X1366797D03*
Y1155213D03*
X1361723Y1204617D03*
X1364038Y1198321D03*
Y1200821D03*
X1361723Y1212117D03*
Y1209617D03*
Y1207117D03*
X1357070Y1297498D03*
X1356904Y1345691D03*
Y1350683D03*
Y1357603D03*
Y1362595D03*
Y1381801D03*
Y1369889D03*
Y1374881D03*
Y1386793D03*
Y1394087D03*
Y1399079D03*
Y1410991D03*
Y1405999D03*
X1354834Y1465913D03*
Y1456451D03*
Y1461182D03*
X1363496Y1465513D03*
Y1460782D03*
X1354834Y1481267D03*
X1363496Y1476136D03*
Y1470244D03*
Y1480867D03*
X1354834Y1471805D03*
Y1476536D03*
Y1487159D03*
Y1496621D03*
X1363496Y1485598D03*
Y1491490D03*
Y1496221D03*
X1354834Y1491890D03*
Y1502514D03*
Y1511976D03*
X1363496Y1511576D03*
Y1506845D03*
Y1500952D03*
X1354834Y1507245D03*
X1363496Y1516307D03*
X1354834Y1558813D03*
Y1563544D03*
X1363496Y1563144D03*
Y1572606D03*
X1354834Y1568275D03*
Y1574167D03*
Y1578898D03*
X1363496Y1567875D03*
Y1578498D03*
X1354834Y1583629D03*
Y1589522D03*
Y1594253D03*
X1363496Y1583229D03*
Y1593853D03*
Y1587960D03*
X1354834Y1609607D03*
Y1604876D03*
Y1598984D03*
X1363496Y1609207D03*
Y1598584D03*
Y1603315D03*
X1354834Y1614338D03*
X1363496Y1613938D03*
Y1618669D03*
X1376262Y113394D03*
X1378911Y110784D03*
X1378505Y133298D03*
X1380652Y134579D03*
X1378227Y252371D03*
X1383556Y558338D03*
X1383184Y587653D03*
X1383425Y593575D03*
X1383556Y604838D03*
X1381118Y634033D03*
X1383425Y640075D03*
X1381244Y673623D03*
X1383425Y684140D03*
X1381932Y722547D03*
X1383425Y731575D03*
X1383046Y829871D03*
X1379896Y842470D03*
Y858218D03*
X1370447Y867665D03*
Y886562D03*
X1371379Y986717D03*
X1370384Y1004680D03*
X1376601Y1030218D03*
X1374451Y1090568D03*
Y1093068D03*
X1371477Y1098767D03*
X1375633Y1136935D03*
Y1134435D03*
Y1139435D03*
Y1131935D03*
X1383366D03*
Y1134435D03*
Y1136935D03*
Y1139435D03*
X1368933Y1125801D03*
X1371433D03*
X1368933Y1129301D03*
X1371433D03*
X1383024Y1152684D03*
X1376861D03*
X1375633Y1146935D03*
Y1144435D03*
Y1141935D03*
X1383366D03*
Y1146935D03*
Y1144435D03*
X1377390Y1244055D03*
Y1250760D03*
Y1254164D03*
X1372300Y1422900D03*
X1372157Y1461183D03*
Y1456452D03*
Y1465914D03*
Y1471806D03*
Y1476537D03*
Y1481268D03*
Y1487160D03*
Y1491891D03*
Y1496622D03*
Y1502515D03*
Y1507246D03*
Y1511977D03*
Y1558813D03*
Y1563544D03*
Y1568275D03*
Y1574167D03*
Y1578898D03*
Y1583629D03*
Y1589522D03*
Y1594253D03*
Y1604876D03*
Y1598984D03*
Y1609607D03*
Y1614338D03*
X1372000Y1644980D03*
X1391497Y109172D03*
X1394497D03*
X1393504Y106495D03*
X1397248Y116497D03*
X1386505Y133298D03*
X1397248Y130670D03*
Y123584D03*
X1393238Y146012D03*
X1395144Y141228D03*
X1397248Y137757D03*
X1398032Y150847D03*
X1400000Y247292D03*
X1392709Y253198D03*
X1391086Y577192D03*
X1400912Y581222D03*
Y591215D03*
X1391587Y627817D03*
X1388414Y675000D03*
X1388241Y722000D03*
X1396916Y862829D03*
X1395561Y876204D03*
X1396163Y868597D03*
X1398247Y926261D03*
X1390322Y1057998D03*
Y1055498D03*
X1392822D03*
Y1057998D03*
X1390322Y1060498D03*
Y1062998D03*
X1392822D03*
Y1060498D03*
X1399748Y1098518D03*
X1394496Y1098428D03*
X1388992Y1123101D03*
X1396992D03*
X1399492D03*
X1385866Y1131935D03*
Y1134435D03*
Y1136935D03*
Y1139435D03*
X1388992Y1125801D03*
X1397392D03*
X1399892D03*
X1387392Y1129301D03*
X1389892D03*
X1392392D03*
X1394892D03*
X1397392D03*
X1399892D03*
X1391856Y1155213D03*
Y1152713D03*
X1385866Y1141935D03*
Y1146935D03*
Y1144435D03*
X1393695Y1204405D03*
Y1206905D03*
Y1211905D03*
Y1209405D03*
X1385992Y1285466D03*
X1390492D03*
X1392000Y1644980D03*
X1409248Y109410D03*
Y102323D03*
X1404548Y116497D03*
X1402048D03*
X1404548Y109410D03*
X1409248Y116496D03*
X1402048Y130670D03*
Y123584D03*
X1404548Y123583D03*
X1409248Y130670D03*
Y123583D03*
X1404548Y130670D03*
X1409248Y137756D03*
X1402048Y137757D03*
X1408666Y324733D03*
X1411950Y448466D03*
X1408103Y555194D03*
X1410903D03*
X1408103Y563194D03*
X1410903D03*
X1408103Y571194D03*
X1410903D03*
X1406512Y581222D03*
X1403712D03*
Y591215D03*
X1406512D03*
X1405514Y611091D03*
X1405000Y656000D03*
Y699000D03*
X1404689Y910897D03*
X1413575Y915186D03*
X1413322Y958908D03*
X1404317Y989436D03*
X1411038Y985379D03*
X1404936Y1098767D03*
X1415494Y1139435D03*
Y1136935D03*
Y1134435D03*
Y1131935D03*
X1409092Y1136935D03*
Y1134435D03*
Y1139435D03*
Y1131935D03*
X1402392Y1125801D03*
X1404892D03*
X1402392Y1129301D03*
X1404892D03*
X1409092Y1141935D03*
X1416736Y1152713D03*
Y1155213D03*
X1402256D03*
Y1152713D03*
X1415494Y1144435D03*
Y1146935D03*
Y1141935D03*
X1409092Y1146935D03*
Y1144435D03*
X1407995Y1204617D03*
X1410310Y1200821D03*
Y1198321D03*
X1407995Y1207117D03*
Y1209617D03*
Y1212117D03*
X1415903Y1282590D03*
X1404019Y1285290D03*
X1414346Y1303020D03*
X1412000Y1644980D03*
X1417710Y82984D03*
Y75184D03*
Y77784D03*
Y80384D03*
X1420264Y92849D03*
X1417710Y85584D03*
X1427224Y103037D03*
X1427358Y116496D03*
Y109410D03*
Y130670D03*
Y123583D03*
X1423515Y137756D03*
X1429539Y293796D03*
X1432039D03*
X1431019Y434508D03*
X1427019D03*
X1424196Y446352D03*
X1428782Y445874D03*
X1417856Y455466D03*
X1433310Y504699D03*
X1430810D03*
X1433012Y516979D03*
X1430512D03*
X1427233Y628183D03*
X1424389Y627948D03*
X1426000Y709000D03*
Y713000D03*
Y757000D03*
Y753000D03*
X1422813Y910065D03*
X1424126Y900295D03*
X1427553Y939200D03*
X1427473Y965621D03*
X1420740Y1004766D03*
Y1000766D03*
Y1016266D03*
Y1030766D03*
X1420107Y1052514D03*
X1431876Y1098518D03*
X1426624Y1098428D03*
X1421120Y1123101D03*
X1429120D03*
X1431620D03*
X1422020Y1129301D03*
X1424520D03*
X1427020D03*
X1429520D03*
X1432020D03*
X1417994Y1139435D03*
Y1136935D03*
Y1134435D03*
Y1131935D03*
X1421120Y1125801D03*
X1429520D03*
X1432020D03*
X1419520Y1129301D03*
X1432384Y1155213D03*
Y1152713D03*
X1422984D03*
Y1155213D03*
X1417994Y1144435D03*
Y1146935D03*
Y1141935D03*
X1420625Y1204405D03*
Y1206905D03*
Y1209405D03*
X1425652Y1297411D03*
X1433386Y1343309D03*
X1428840Y1407740D03*
X1423065Y1508327D03*
X1432499Y1512175D03*
X1424245Y1543338D03*
X1425558Y1537432D03*
X1425260Y1558072D03*
X1433558Y1555366D03*
X1423701Y1563978D03*
X1432000Y1644980D03*
X1444641Y94017D03*
X1448641D03*
X1440641D03*
X1449761Y115401D03*
Y110445D03*
X1444769D03*
Y115401D03*
X1449761Y124618D03*
X1444769D03*
Y129574D03*
X1449761D03*
X1442682Y151540D03*
X1446332Y191941D03*
X1446199Y188727D03*
X1442956Y226141D03*
X1440156D03*
X1448026Y256535D03*
X1440053Y285690D03*
X1437553D03*
X1440053Y288190D03*
X1442853D03*
Y285690D03*
X1447079Y290755D03*
X1437553Y288190D03*
X1437758Y362584D03*
X1435019Y434508D03*
X1437757Y447201D03*
X1437879Y444269D03*
X1435810Y504699D03*
X1447036Y519518D03*
X1435512Y516979D03*
X1444536Y519518D03*
X1439536D03*
X1442036D03*
X1435241Y593796D03*
X1440930Y636005D03*
Y633205D03*
Y638805D03*
X1437784Y683532D03*
X1436567Y727532D03*
X1443000Y798500D03*
Y794500D03*
Y842500D03*
Y838500D03*
X1438188Y867633D03*
X1437703Y880067D03*
X1449072Y892581D03*
X1435288Y897500D03*
X1444453Y938806D03*
X1439449Y979009D03*
X1440610Y1021567D03*
X1435266Y1031522D03*
X1437064Y1098767D03*
X1441220Y1131935D03*
Y1139435D03*
Y1134435D03*
Y1136935D03*
X1434520Y1125801D03*
X1437020D03*
X1434520Y1129301D03*
X1437020D03*
X1441220Y1141935D03*
Y1144435D03*
Y1146935D03*
X1442448Y1152684D03*
X1434925Y1204617D03*
X1437240Y1200821D03*
Y1198321D03*
X1434925Y1207117D03*
Y1209617D03*
Y1212117D03*
X1436408Y1303462D03*
X1444438Y1308312D03*
X1439482D03*
X1441286Y1335776D03*
X1457718Y84140D03*
Y76140D03*
Y80140D03*
X1452650Y94017D03*
X1460163Y117557D03*
X1455171D03*
Y122513D03*
X1460163Y131731D03*
Y122513D03*
X1455171Y131731D03*
X1458262Y146461D03*
X1460163Y136687D03*
X1455171D03*
X1457164Y152367D03*
X1463547Y180527D03*
X1458864Y180572D03*
Y185165D03*
X1463502Y185121D03*
X1452832Y184619D03*
X1454812Y206760D03*
X1456026Y256535D03*
X1457056Y279208D03*
X1461160Y281307D03*
X1455079Y290755D03*
X1451079D03*
X1458982Y356861D03*
X1453000Y633450D03*
Y636250D03*
Y639050D03*
X1453032Y769032D03*
X1453775Y813032D03*
X1461241Y867475D03*
X1462694Y874859D03*
Y877859D03*
X1460472Y885985D03*
X1459420Y899226D03*
X1451005Y931848D03*
X1462819Y949996D03*
X1462000Y960378D03*
X1460655Y964253D03*
X1466076Y979746D03*
X1462388Y1006560D03*
X1455939Y1018368D03*
X1465503Y1030233D03*
X1460592Y1345691D03*
Y1350683D03*
X1465548Y1345691D03*
Y1350683D03*
X1460592Y1357603D03*
Y1362595D03*
X1465548Y1357603D03*
Y1362595D03*
X1460592Y1381801D03*
Y1374881D03*
Y1369889D03*
X1465548Y1381801D03*
Y1374881D03*
Y1369889D03*
X1460592Y1386793D03*
X1465548D03*
X1452000Y1644980D03*
X1480460Y60922D03*
X1475296Y55513D03*
X1471093Y117261D03*
X1478624Y113394D03*
X1481273Y110784D03*
X1481368Y130898D03*
X1478800Y180665D03*
Y172665D03*
X1467270Y192421D03*
X1478832Y200864D03*
Y212864D03*
Y216864D03*
Y221864D03*
X1480589Y252371D03*
X1473900Y433100D03*
X1478710Y685630D03*
X1473525Y710052D03*
X1474425Y716075D03*
X1479962Y727500D03*
X1471415Y748629D03*
X1474425Y760075D03*
X1473634Y864337D03*
X1481454Y911570D03*
X1474075Y920575D03*
X1474349Y949394D03*
X1468500Y974181D03*
X1479096Y997860D03*
X1471096D03*
X1475096D03*
X1467096D03*
X1471854Y1035088D03*
X1479624Y1035102D03*
X1468371Y1030701D03*
X1480193Y1102091D03*
X1474384D03*
X1480193Y1114691D03*
X1474384D03*
X1480193Y1127291D03*
X1474384D03*
X1480193Y1139891D03*
X1474384D03*
X1480193Y1152491D03*
X1474384D03*
X1480193Y1165091D03*
X1474384D03*
X1480193Y1177691D03*
X1474384D03*
X1480675Y1202103D03*
X1477788Y1350683D03*
Y1345691D03*
X1472832Y1350683D03*
Y1345691D03*
X1477788Y1357603D03*
Y1362595D03*
X1472832Y1357603D03*
Y1362595D03*
X1477788Y1381801D03*
Y1369795D03*
Y1374881D03*
X1472832Y1381801D03*
Y1369795D03*
Y1374881D03*
X1477788Y1386793D03*
Y1399079D03*
Y1393993D03*
X1472832Y1386793D03*
Y1393993D03*
Y1399079D03*
X1477788Y1405999D03*
Y1410991D03*
X1472832Y1405999D03*
Y1410991D03*
X1476094Y1465913D03*
Y1461182D03*
Y1456451D03*
Y1471805D03*
Y1481267D03*
Y1476536D03*
Y1491890D03*
Y1487159D03*
Y1496621D03*
Y1502514D03*
Y1511976D03*
Y1507245D03*
Y1563544D03*
Y1558813D03*
Y1568275D03*
Y1578898D03*
Y1574167D03*
Y1583629D03*
Y1594253D03*
Y1589522D03*
Y1609607D03*
Y1598984D03*
Y1604876D03*
Y1614338D03*
X1472000Y1644980D03*
X1493859Y109172D03*
X1496859D03*
X1495866Y106495D03*
X1488867Y133298D03*
X1495600Y146012D03*
X1497506Y141228D03*
X1483014Y134579D03*
X1495071Y253198D03*
X1486360Y358700D03*
Y354200D03*
X1496473Y769000D03*
X1491062Y793003D03*
X1491425Y801575D03*
X1496845Y813000D03*
X1491425Y845575D03*
X1489650Y836985D03*
X1489805Y866386D03*
X1497488Y873839D03*
X1491414Y875383D03*
X1494000Y884000D03*
X1498084Y894825D03*
X1492101Y894860D03*
X1496383Y898023D03*
X1496500Y919000D03*
X1496000Y922000D03*
X1487075Y920925D03*
X1485100Y943900D03*
X1496425Y943075D03*
X1496072Y950044D03*
X1482591Y961909D03*
X1486500Y947000D03*
X1485226Y973886D03*
X1492560Y974654D03*
X1495339Y1009354D03*
X1491839D03*
X1486030D03*
X1491096Y997860D03*
X1483096D03*
X1495096D03*
X1487096D03*
X1495339Y1021954D03*
X1491839D03*
X1486030D03*
X1483693Y1102091D03*
Y1114691D03*
Y1127291D03*
Y1139891D03*
Y1152491D03*
Y1165091D03*
Y1177691D03*
X1498197Y1209607D03*
X1492471Y1215195D03*
X1484055Y1223749D03*
X1497312Y1350683D03*
Y1345691D03*
X1485072D03*
Y1350683D03*
X1490028Y1345691D03*
Y1350683D03*
X1497312Y1357603D03*
Y1362595D03*
X1485072D03*
Y1357603D03*
X1490028D03*
Y1362595D03*
X1485072Y1369889D03*
Y1374881D03*
Y1381801D03*
X1490028Y1369889D03*
Y1374881D03*
Y1381801D03*
X1497312D03*
Y1374881D03*
Y1369889D03*
Y1386793D03*
Y1394087D03*
Y1399079D03*
X1485072Y1394087D03*
Y1399079D03*
Y1386793D03*
X1490028Y1399079D03*
Y1394087D03*
Y1386793D03*
X1497312Y1405999D03*
Y1410991D03*
X1485072Y1405999D03*
Y1410991D03*
X1490028Y1405999D03*
Y1410991D03*
X1484755Y1465513D03*
Y1460782D03*
X1493417Y1465913D03*
Y1456451D03*
Y1461182D03*
Y1471805D03*
Y1476536D03*
Y1481267D03*
X1484755Y1476136D03*
Y1470244D03*
Y1480867D03*
Y1496221D03*
X1493417Y1487159D03*
Y1491890D03*
Y1496621D03*
X1484755Y1491490D03*
Y1485598D03*
Y1506845D03*
Y1500952D03*
Y1511576D03*
X1493417Y1507245D03*
Y1502514D03*
Y1511976D03*
X1484755Y1516307D03*
Y1563144D03*
X1493417Y1558813D03*
Y1563544D03*
Y1578898D03*
X1484755Y1567875D03*
Y1578498D03*
Y1572606D03*
X1493417Y1568275D03*
Y1574167D03*
X1484755Y1583229D03*
Y1593853D03*
Y1587960D03*
X1493417Y1583629D03*
Y1589522D03*
Y1594253D03*
X1484755Y1609207D03*
Y1598584D03*
Y1603315D03*
X1493417Y1609607D03*
Y1604876D03*
Y1598984D03*
X1484755Y1613938D03*
Y1618669D03*
X1493417Y1614338D03*
X1492000Y1644980D03*
X1511610Y116496D03*
Y109410D03*
Y102323D03*
X1499610Y116497D03*
X1506910D03*
X1504410D03*
X1506910Y109410D03*
X1511610Y123583D03*
X1499610Y130670D03*
Y123584D03*
X1506910Y130670D03*
X1504410D03*
Y123584D03*
X1506910Y123583D03*
X1511610Y130670D03*
Y137756D03*
X1499610Y137757D03*
X1504410D03*
X1500394Y150847D03*
X1502362Y247292D03*
X1501807Y323766D03*
X1507864Y450750D03*
X1511963Y536382D03*
X1510280Y899732D03*
X1514354Y938811D03*
X1510500Y931500D03*
X1513955Y950396D03*
X1505888Y965964D03*
X1514000Y968739D03*
X1510740Y973740D03*
X1507096Y997860D03*
X1503096D03*
X1511096D03*
X1499096D03*
X1505130Y1105091D03*
Y1117691D03*
Y1130291D03*
Y1142891D03*
Y1155491D03*
Y1168091D03*
Y1180691D03*
X1509552Y1350683D03*
Y1345691D03*
X1514508Y1350683D03*
Y1345691D03*
X1502268Y1350683D03*
Y1345691D03*
X1509552Y1362595D03*
Y1357603D03*
X1514508D03*
Y1362595D03*
X1502268Y1357603D03*
Y1362595D03*
X1509552Y1374881D03*
Y1369889D03*
Y1381801D03*
X1514508Y1374881D03*
Y1369889D03*
Y1381801D03*
X1502268D03*
Y1374881D03*
Y1369889D03*
X1509552Y1394087D03*
Y1399079D03*
Y1386793D03*
X1514508Y1394087D03*
Y1399079D03*
Y1386793D03*
X1502268D03*
Y1399079D03*
Y1394087D03*
X1509552Y1405999D03*
Y1410991D03*
X1514508Y1405999D03*
Y1410991D03*
X1502268Y1405999D03*
Y1410991D03*
X1502078Y1465513D03*
Y1460782D03*
X1510740Y1465913D03*
Y1456451D03*
Y1461182D03*
X1502078Y1470244D03*
Y1480867D03*
X1510740Y1471805D03*
Y1476536D03*
Y1481267D03*
X1502078Y1476136D03*
Y1491490D03*
Y1485598D03*
Y1496221D03*
X1510740Y1487159D03*
Y1491890D03*
Y1496621D03*
Y1507245D03*
Y1502514D03*
Y1511976D03*
X1502078Y1506845D03*
Y1500952D03*
Y1511576D03*
Y1516307D03*
X1510740Y1563544D03*
X1502078Y1563144D03*
X1510740Y1558813D03*
Y1578898D03*
X1502078Y1567875D03*
Y1578498D03*
Y1572606D03*
X1510740Y1568275D03*
Y1574167D03*
X1502078Y1583229D03*
Y1593853D03*
Y1587960D03*
X1510740Y1583629D03*
Y1589522D03*
Y1594253D03*
X1502078Y1609207D03*
Y1598584D03*
Y1603315D03*
X1510740Y1609607D03*
Y1604876D03*
Y1598984D03*
X1502078Y1613938D03*
Y1618669D03*
X1510740Y1614338D03*
X1512000Y1644980D03*
X1520072Y82984D03*
Y75184D03*
Y77784D03*
Y80384D03*
X1522626Y92849D03*
X1520072Y85584D03*
X1529586Y103037D03*
X1529720Y116496D03*
Y109410D03*
Y130670D03*
Y123583D03*
X1526311Y137756D03*
X1528635Y555234D03*
X1528350Y562003D03*
X1519156Y596095D03*
X1516869Y594668D03*
X1518354Y592354D03*
X1518415Y589556D03*
X1519153Y599588D03*
X1516930Y597580D03*
X1519185Y615600D03*
X1519153Y607588D03*
X1523646Y634946D03*
X1519063Y876339D03*
X1517344Y896999D03*
X1515743Y888133D03*
X1517344Y903179D03*
X1517153Y908367D03*
X1523000Y923740D03*
X1526611Y921442D03*
X1525740Y928740D03*
X1528087Y936394D03*
X1524500Y949500D03*
X1530174Y956986D03*
X1525522Y971075D03*
X1523966Y980281D03*
X1515096Y997860D03*
X1531096D03*
X1519096D03*
X1523096D03*
X1516776Y1024954D03*
Y1012354D03*
X1526748Y1345691D03*
Y1350683D03*
X1521792Y1345691D03*
Y1350683D03*
X1526748Y1357603D03*
Y1362595D03*
X1521792Y1357603D03*
Y1362595D03*
X1526748Y1369889D03*
Y1374881D03*
Y1381801D03*
X1521792Y1374881D03*
Y1381801D03*
Y1369889D03*
X1526748Y1386793D03*
Y1399079D03*
Y1394087D03*
X1521792Y1386793D03*
Y1394087D03*
Y1399079D03*
X1526748Y1405999D03*
Y1410991D03*
X1521792Y1405999D03*
Y1410991D03*
X1519401Y1465513D03*
Y1460782D03*
X1528062Y1465913D03*
Y1456451D03*
Y1461182D03*
Y1481267D03*
X1519401Y1476136D03*
Y1470244D03*
Y1480867D03*
X1528062Y1471805D03*
Y1476536D03*
X1519401Y1491490D03*
Y1485598D03*
Y1496221D03*
X1528062Y1487159D03*
Y1491890D03*
Y1496621D03*
X1519401Y1506845D03*
Y1500952D03*
Y1511576D03*
X1528062Y1507245D03*
Y1502514D03*
Y1511976D03*
X1519401Y1516307D03*
Y1563144D03*
X1528062Y1558813D03*
Y1563544D03*
Y1578898D03*
X1519401Y1567875D03*
Y1578498D03*
Y1572606D03*
X1528062Y1568275D03*
Y1574167D03*
X1519401Y1587960D03*
X1528062Y1583629D03*
Y1589522D03*
Y1594253D03*
X1519401Y1583229D03*
Y1593853D03*
Y1609207D03*
Y1598584D03*
Y1603315D03*
X1528062Y1609607D03*
Y1604876D03*
Y1598984D03*
X1519401Y1613938D03*
Y1618669D03*
X1528062Y1614338D03*
X1547003Y94017D03*
X1543003D03*
X1547131Y110445D03*
Y115401D03*
Y129574D03*
Y124618D03*
X1545044Y151540D03*
X1548561Y188727D03*
X1542518Y226141D03*
X1545318D03*
X1531901Y293796D03*
X1539915Y288190D03*
X1542415Y285690D03*
X1539915D03*
X1542415Y288190D03*
X1545215D03*
Y285690D03*
X1534401Y293796D03*
X1541283Y354553D03*
X1546272Y1350683D03*
Y1345691D03*
X1534032Y1350683D03*
Y1345691D03*
X1538988D03*
Y1350683D03*
X1546272Y1357603D03*
Y1362595D03*
X1534032Y1357603D03*
Y1362595D03*
X1538988D03*
Y1357603D03*
X1546272Y1374881D03*
Y1369889D03*
Y1381801D03*
X1534032Y1369889D03*
Y1381801D03*
Y1374881D03*
X1538988Y1369889D03*
Y1381801D03*
Y1374881D03*
X1546272Y1386793D03*
Y1394087D03*
Y1399079D03*
X1534032Y1394087D03*
Y1399079D03*
Y1386793D03*
X1538988Y1394087D03*
Y1399079D03*
Y1386793D03*
X1546272Y1405999D03*
Y1410991D03*
X1534032Y1405999D03*
Y1410991D03*
X1538988Y1405999D03*
Y1410991D03*
X1545385Y1461183D03*
X1536724Y1465513D03*
Y1460782D03*
X1545385Y1465914D03*
Y1456452D03*
X1536724Y1476136D03*
Y1470244D03*
Y1480867D03*
X1545385Y1476537D03*
Y1471806D03*
Y1481268D03*
X1536724Y1491490D03*
Y1485598D03*
Y1496221D03*
X1545385Y1491891D03*
Y1487160D03*
Y1496622D03*
X1536724Y1506845D03*
Y1500952D03*
Y1511576D03*
X1545385Y1507246D03*
Y1502515D03*
Y1511977D03*
X1536724Y1516307D03*
X1545385Y1563544D03*
Y1558813D03*
X1536724Y1563144D03*
Y1567875D03*
X1545385Y1568275D03*
X1536724Y1578498D03*
Y1572606D03*
X1545385Y1578898D03*
Y1574167D03*
Y1594253D03*
Y1589522D03*
X1536724Y1583229D03*
X1545385Y1583629D03*
X1536724Y1593853D03*
Y1587960D03*
Y1609207D03*
Y1598584D03*
Y1603315D03*
X1545385Y1609607D03*
Y1598984D03*
Y1604876D03*
Y1614338D03*
X1536724Y1613938D03*
Y1618669D03*
X1532000Y1644980D03*
X1560080Y84140D03*
Y76140D03*
Y80140D03*
X1555012Y94017D03*
X1551003D03*
X1562525Y117557D03*
X1557533D03*
X1552123Y115401D03*
Y110445D03*
X1562525Y122513D03*
X1552123Y129574D03*
Y124618D03*
X1557533Y131731D03*
Y122513D03*
X1562525Y131731D03*
X1560624Y146461D03*
X1557533Y136687D03*
X1562525D03*
X1559526Y152367D03*
X1561226Y180572D03*
X1548694Y191941D03*
X1555194Y184619D03*
X1561226Y185165D03*
X1557174Y206760D03*
X1550388Y256535D03*
X1558388D03*
X1559418Y279208D03*
X1563522Y281307D03*
X1549441Y290755D03*
X1553441D03*
X1557441D03*
X1554403Y352363D03*
X1563248Y389154D03*
X1548629D03*
Y403327D03*
Y410413D03*
X1561778Y396240D03*
X1548629D03*
Y417500D03*
Y424587D03*
Y438760D03*
Y431673D03*
Y445847D03*
Y467539D03*
Y474626D03*
Y488799D03*
Y481713D03*
Y495886D03*
Y511673D03*
Y518760D03*
X1562089Y516841D03*
X1548629Y540020D03*
Y525847D03*
Y532933D03*
Y547106D03*
X1556914Y552872D03*
X1557036Y550123D03*
X1556359Y562443D03*
X1558668Y572334D03*
X1558127Y560675D03*
X1556900Y574102D03*
X1547910Y602197D03*
X1548374Y595108D03*
X1561535Y653161D03*
X1565132Y677843D03*
X1547813Y906581D03*
X1551099Y959096D03*
X1558512Y1345691D03*
Y1350683D03*
X1563468D03*
Y1345691D03*
X1551228Y1350683D03*
Y1345691D03*
X1563468Y1362595D03*
X1551228Y1357603D03*
Y1362595D03*
X1558512D03*
Y1357603D03*
X1563468D03*
X1558512Y1374881D03*
Y1369889D03*
Y1381801D03*
X1563468Y1374881D03*
Y1369889D03*
Y1381801D03*
X1551228Y1369889D03*
Y1381801D03*
Y1374881D03*
X1558512Y1399079D03*
Y1394087D03*
Y1386793D03*
X1563468Y1399079D03*
Y1394087D03*
Y1386793D03*
X1551228D03*
Y1394087D03*
Y1399079D03*
X1558512Y1405999D03*
Y1410991D03*
X1563468Y1405999D03*
Y1410991D03*
X1551228Y1405999D03*
Y1410991D03*
X1552000Y1644980D03*
X1576256Y-25273D03*
X1573003Y-25287D03*
X1576241Y-27788D03*
X1572988Y-27802D03*
X1579281Y-26693D03*
X1573455Y117261D03*
X1565909Y180527D03*
X1569632Y192421D03*
X1565864Y185121D03*
X1571625Y333549D03*
X1579340Y396240D03*
Y403327D03*
Y410413D03*
X1566555Y414823D03*
X1565863Y422864D03*
X1579340Y417500D03*
Y424586D03*
X1565933Y429832D03*
X1565538Y436447D03*
X1579340Y431673D03*
Y438760D03*
X1567573Y447953D03*
X1579340Y445847D03*
X1566740Y467539D03*
X1565482Y472772D03*
X1579340Y474626D03*
Y488799D03*
X1566216Y487711D03*
X1566329Y479104D03*
X1579340Y481712D03*
Y495886D03*
X1566740D03*
X1579340Y518760D03*
X1565050Y511673D03*
X1579340Y540020D03*
Y532933D03*
Y525846D03*
X1574222Y629872D03*
X1569926Y668885D03*
X1575950Y662981D03*
X1570331Y691851D03*
X1575942Y705043D03*
X1575708Y1345597D03*
X1570752Y1350683D03*
Y1345597D03*
X1575708Y1350683D03*
X1570752Y1357603D03*
Y1362595D03*
X1575708D03*
Y1357603D03*
Y1381801D03*
Y1374881D03*
Y1369889D03*
X1570752D03*
Y1381801D03*
Y1374881D03*
X1575708Y1386793D03*
Y1399079D03*
Y1393993D03*
X1570752Y1386793D03*
Y1393993D03*
Y1399079D03*
X1575708Y1405999D03*
Y1410991D03*
X1570752Y1405999D03*
Y1410991D03*
X1572000Y1644980D03*
X1586256Y-64207D03*
X1583003D03*
X1586241Y-66722D03*
X1582988D03*
X1589281Y-65613D03*
X1582822Y60922D03*
X1580327Y57448D03*
X1580986Y113394D03*
X1583635Y110784D03*
X1591229Y133298D03*
X1583229D03*
X1585376Y134579D03*
X1581162Y180665D03*
Y172665D03*
X1581194Y212864D03*
Y200864D03*
Y221864D03*
Y216864D03*
X1582951Y252371D03*
X1586640Y389153D03*
X1581840D03*
Y403326D03*
Y410413D03*
X1586640D03*
X1581840Y396240D03*
X1586640D03*
Y403326D03*
Y417499D03*
X1581840D03*
Y424586D03*
X1586640D03*
X1581840Y438760D03*
X1586640D03*
Y431673D03*
X1581840D03*
X1586640Y467539D03*
X1581840D03*
Y474626D03*
X1586640D03*
X1581840Y488799D03*
X1586640D03*
X1581840Y481712D03*
X1586640D03*
X1581840Y518760D03*
Y511673D03*
X1586640D03*
Y518760D03*
Y525846D03*
Y532933D03*
X1581840D03*
Y525846D03*
X1595185Y543925D03*
X1595760Y555000D03*
X1583720Y560500D03*
X1587948Y1350683D03*
Y1345691D03*
X1582992D03*
Y1350683D03*
X1587948Y1362595D03*
Y1357603D03*
X1582992Y1362595D03*
Y1357603D03*
Y1369889D03*
Y1381801D03*
Y1374881D03*
X1587948Y1369889D03*
Y1381801D03*
Y1374881D03*
X1582992Y1399079D03*
Y1394087D03*
Y1386793D03*
X1587948Y1399079D03*
Y1394087D03*
Y1386793D03*
X1582992Y1405999D03*
Y1410991D03*
X1587948Y1405999D03*
Y1410991D03*
X1592020Y1433061D03*
X1591610Y1469940D03*
X1591586Y1505130D03*
X1609272Y109410D03*
X1601972Y116497D03*
X1609272D03*
X1606772D03*
X1596221Y109172D03*
X1599221D03*
X1598228Y106495D03*
X1601972Y123584D03*
Y130670D03*
X1606772Y123584D03*
X1609272Y123583D03*
Y130670D03*
X1606772D03*
Y137757D03*
X1597962Y146012D03*
X1599868Y141228D03*
X1601972Y137757D03*
X1602756Y150847D03*
X1604724Y247292D03*
X1597433Y253198D03*
X1608240Y329000D03*
X1603664Y342596D03*
X1598223Y351003D03*
X1599127Y375587D03*
X1596714Y383003D03*
X1614338Y636842D03*
X1610620Y1345691D03*
Y1350683D03*
Y1357603D03*
Y1362595D03*
Y1381801D03*
Y1374881D03*
Y1369889D03*
Y1386793D03*
X1597225Y1437014D03*
X1603363Y1460570D03*
X1597457Y1452556D03*
X1598500Y1472500D03*
X1606745Y1474242D03*
X1602580Y1483108D03*
X1598000Y1486000D03*
X1604000Y1516000D03*
X1600700Y1534300D03*
X1622434Y82984D03*
Y80384D03*
Y75184D03*
Y77784D03*
X1624988Y92849D03*
X1622434Y85584D03*
X1613972Y116496D03*
Y102323D03*
Y109410D03*
Y130670D03*
Y123583D03*
Y137756D03*
X1625952Y431029D03*
X1626260Y427017D03*
X1625018Y435029D03*
X1625938Y449873D03*
X1625565Y472579D03*
Y479666D03*
Y486752D03*
Y493839D03*
Y523800D03*
Y516713D03*
Y537973D03*
Y530886D03*
Y566752D03*
Y588013D03*
Y573839D03*
Y580926D03*
Y602186D03*
Y595099D03*
Y609272D03*
Y616359D03*
X1620244Y638125D03*
X1617843Y665140D03*
X1613110Y678462D03*
X1624148Y708258D03*
X1627455Y759489D03*
X1619612Y783152D03*
X1620359Y774830D03*
X1619569Y796035D03*
X1620755Y787530D03*
X1613235Y808466D03*
X1620479Y815730D03*
X1620072Y801630D03*
X1616255Y824405D03*
X1619859Y839519D03*
X1615576Y1345691D03*
Y1350683D03*
X1622860D03*
Y1345691D03*
X1627816Y1350683D03*
Y1345691D03*
X1615576Y1357603D03*
Y1362595D03*
X1622860Y1357603D03*
Y1362595D03*
X1627816Y1357603D03*
Y1362595D03*
X1622860Y1381801D03*
Y1369795D03*
Y1374881D03*
X1627816Y1381801D03*
Y1369795D03*
Y1374881D03*
X1615576Y1381801D03*
Y1374881D03*
Y1369889D03*
Y1386793D03*
X1622860D03*
Y1393993D03*
Y1399079D03*
X1627816Y1386793D03*
Y1399079D03*
Y1393993D03*
X1622860Y1405999D03*
Y1410991D03*
X1627816Y1405999D03*
Y1410991D03*
X1618800Y1528558D03*
X1614200Y1519500D03*
X1614360Y1542860D03*
X1618600Y1532000D03*
X1631948Y103037D03*
X1632082Y116496D03*
Y109410D03*
Y130670D03*
Y123583D03*
X1628673Y137756D03*
X1644880Y226141D03*
X1644777Y288190D03*
X1642277Y285690D03*
X1644777D03*
X1642277Y288190D03*
X1636763Y293796D03*
X1634263D03*
X1635987Y335616D03*
X1630703Y350655D03*
X1636468Y345595D03*
X1636271Y410394D03*
Y403307D03*
X1637665Y458406D03*
Y451319D03*
X1637489Y462264D03*
X1632865Y465492D03*
X1637665D03*
Y472579D03*
X1632865D03*
X1630365D03*
Y479666D03*
X1632865D03*
X1637665Y479665D03*
Y486752D03*
X1630365D03*
X1632865D03*
X1630365Y493839D03*
X1637665D03*
X1632865Y509626D03*
Y516713D03*
X1630365D03*
Y523800D03*
X1632865D03*
X1637665Y523799D03*
Y516713D03*
Y509626D03*
X1630365Y530886D03*
X1637665D03*
X1632865D03*
X1637665Y537973D03*
X1630365D03*
X1637665Y559665D03*
Y566752D03*
X1630365D03*
X1632865D03*
Y559665D03*
Y573839D03*
X1630365Y580926D03*
X1632865D03*
X1637665D03*
Y588012D03*
X1630365Y588013D03*
X1632865Y588012D03*
X1637665Y573839D03*
X1630365D03*
X1632865Y602185D03*
X1630365Y602186D03*
X1637665Y602185D03*
Y595099D03*
X1632865D03*
X1630365D03*
Y616359D03*
X1632865Y609272D03*
X1630365D03*
X1637665Y616358D03*
Y609272D03*
X1637526Y699930D03*
X1637472Y717830D03*
X1631031Y732430D03*
X1628813Y727045D03*
X1631187Y750630D03*
X1629969Y740826D03*
X1644304Y891353D03*
X1640056Y1345691D03*
Y1350683D03*
X1635100Y1345691D03*
Y1350683D03*
X1640056Y1357603D03*
Y1362595D03*
X1635100D03*
Y1357603D03*
X1640056Y1369889D03*
Y1374881D03*
Y1381801D03*
X1635100Y1369889D03*
Y1374881D03*
Y1381801D03*
X1640056Y1399079D03*
Y1394087D03*
Y1386793D03*
X1635100Y1394087D03*
Y1399079D03*
Y1386793D03*
Y1405999D03*
Y1410991D03*
X1640056Y1405999D03*
Y1410991D03*
X1649365Y94017D03*
X1657374D03*
X1653365D03*
X1645365D03*
X1659895Y117557D03*
X1654485Y110445D03*
Y115401D03*
X1649493Y110445D03*
Y115401D03*
X1659895Y122513D03*
Y131731D03*
X1654485Y124618D03*
Y129574D03*
X1649493Y124618D03*
Y129574D03*
X1659895Y136687D03*
X1647406Y151540D03*
X1651056Y191941D03*
X1657556Y184619D03*
X1650923Y188727D03*
X1659536Y206760D03*
X1647680Y226141D03*
X1660750Y256535D03*
X1652750D03*
X1647577Y285690D03*
Y288190D03*
X1655803Y290755D03*
X1651803D03*
X1659803D03*
X1645685Y390500D03*
X1655335Y381500D03*
X1653507Y470136D03*
X1655776Y465492D03*
X1655742Y460250D03*
X1655776Y472579D03*
Y486752D03*
Y479665D03*
Y493839D03*
Y509626D03*
Y516713D03*
X1652236Y537973D03*
X1654716Y525483D03*
X1654637Y532756D03*
X1655776Y559665D03*
Y566752D03*
X1655626Y579978D03*
X1655776Y573839D03*
X1655840Y608117D03*
X1654572Y771702D03*
X1645128Y929263D03*
X1645342Y962120D03*
X1657091Y990823D03*
X1649571Y983857D03*
X1647340Y1350683D03*
Y1345691D03*
X1652296Y1350683D03*
Y1345691D03*
X1659580Y1350683D03*
Y1345691D03*
X1647340Y1357603D03*
Y1362595D03*
X1652296Y1357603D03*
Y1362595D03*
X1659580D03*
Y1357603D03*
X1647340Y1381801D03*
Y1374881D03*
Y1369889D03*
X1652296Y1381801D03*
Y1374881D03*
Y1369889D03*
X1659580Y1374881D03*
Y1369889D03*
Y1381801D03*
X1647340Y1386793D03*
Y1394087D03*
Y1399079D03*
X1652296Y1386793D03*
Y1399079D03*
Y1394087D03*
X1659580D03*
Y1399079D03*
Y1386793D03*
X1647340Y1405999D03*
Y1410991D03*
X1652296Y1405999D03*
Y1410991D03*
X1659580Y1405999D03*
Y1410991D03*
X1657983Y1460782D03*
X1649322Y1456451D03*
Y1465913D03*
X1657983Y1465513D03*
X1649322Y1461182D03*
Y1476536D03*
X1657983Y1476136D03*
Y1470244D03*
X1649322Y1471805D03*
Y1481267D03*
X1657983Y1480867D03*
X1649322Y1487159D03*
Y1496621D03*
X1657983Y1496221D03*
X1649322Y1491890D03*
X1657983Y1491490D03*
Y1485598D03*
Y1500952D03*
X1649322Y1502514D03*
X1657983Y1511576D03*
X1649322Y1511976D03*
Y1507245D03*
X1657983Y1506845D03*
Y1516307D03*
X1649322Y1558813D03*
Y1563544D03*
X1657983Y1563144D03*
Y1572606D03*
X1649322Y1574167D03*
Y1568275D03*
X1657983Y1567875D03*
X1649322Y1578898D03*
X1657983Y1578498D03*
X1649322Y1583629D03*
X1657983Y1583229D03*
X1649322Y1594253D03*
X1657983Y1593853D03*
Y1587960D03*
X1649322Y1589522D03*
Y1609607D03*
X1657983Y1609207D03*
X1649322Y1598984D03*
X1657983Y1598584D03*
Y1603315D03*
X1649322Y1604876D03*
Y1614338D03*
X1657983Y1613938D03*
Y1618669D03*
X1652000Y1644980D03*
X1662442Y84140D03*
Y76140D03*
Y80140D03*
X1675817Y117261D03*
X1664887Y117557D03*
Y122513D03*
Y131731D03*
X1662986Y146461D03*
X1664887Y136687D03*
X1661888Y152367D03*
X1663588Y180572D03*
X1668271Y180527D03*
X1671994Y192421D03*
X1663588Y185165D03*
X1668226Y185121D03*
X1661780Y279208D03*
X1665884Y281307D03*
X1669767Y445908D03*
X1673717Y445787D03*
X1664536Y1350683D03*
Y1345691D03*
X1671820D03*
Y1350683D03*
X1676776Y1345691D03*
Y1350683D03*
X1664536Y1357603D03*
Y1362595D03*
X1671820Y1357603D03*
Y1362595D03*
X1676776Y1357603D03*
Y1362595D03*
X1664536Y1374881D03*
Y1369889D03*
Y1381801D03*
X1671820Y1374881D03*
Y1381801D03*
Y1369889D03*
X1676776D03*
Y1374881D03*
Y1381801D03*
X1664536Y1394087D03*
Y1399079D03*
Y1386793D03*
X1671820D03*
Y1394087D03*
Y1399079D03*
X1676776Y1386793D03*
Y1399079D03*
Y1394087D03*
X1664536Y1405999D03*
Y1410991D03*
X1671820Y1405999D03*
Y1410991D03*
X1676776Y1405999D03*
Y1410991D03*
X1666645Y1465913D03*
Y1456451D03*
Y1461182D03*
X1675306Y1465513D03*
Y1460782D03*
X1666645Y1471805D03*
Y1476536D03*
Y1481267D03*
X1675306Y1476136D03*
Y1470244D03*
Y1480867D03*
X1666645Y1487159D03*
Y1491890D03*
Y1496621D03*
X1675306Y1491490D03*
Y1485598D03*
Y1496221D03*
Y1511576D03*
X1666645Y1511976D03*
Y1507245D03*
Y1502514D03*
X1675306Y1506845D03*
Y1500952D03*
Y1516307D03*
X1666645Y1558813D03*
Y1563544D03*
X1675306Y1563144D03*
Y1578498D03*
Y1572606D03*
X1666645Y1568275D03*
X1675306Y1567875D03*
X1666645Y1574167D03*
Y1578898D03*
Y1583629D03*
X1675306Y1583229D03*
X1666645Y1589522D03*
Y1594253D03*
X1675306Y1593853D03*
Y1587960D03*
X1666645Y1604876D03*
Y1598984D03*
X1675306Y1609207D03*
Y1598584D03*
Y1603315D03*
X1666645Y1609607D03*
Y1614338D03*
X1675306Y1613938D03*
Y1618669D03*
X1672000Y1644980D03*
X1685184Y60922D03*
X1680020Y55513D03*
X1683348Y113394D03*
X1685997Y110784D03*
X1686171Y130898D03*
X1693591Y133298D03*
X1687738Y134579D03*
X1683524Y172665D03*
Y180665D03*
X1683556Y200864D03*
Y212864D03*
Y221864D03*
Y216864D03*
X1685313Y252371D03*
X1687164Y336324D03*
X1678072Y342319D03*
X1691743Y353506D03*
X1680518Y385912D03*
Y393924D03*
Y389912D03*
Y409924D03*
Y405924D03*
Y401924D03*
X1677933Y418838D03*
X1689016Y1345691D03*
Y1350683D03*
X1684060D03*
Y1345691D03*
X1689016Y1362595D03*
Y1357603D03*
X1684060D03*
Y1362595D03*
X1689016Y1369889D03*
Y1381801D03*
Y1374881D03*
X1684060Y1369889D03*
Y1381801D03*
Y1374881D03*
X1689016Y1394087D03*
Y1399079D03*
Y1386793D03*
X1684060Y1394087D03*
Y1399079D03*
Y1386793D03*
X1689016Y1405999D03*
Y1410991D03*
X1684060Y1405999D03*
Y1410991D03*
X1683968Y1465913D03*
Y1456451D03*
Y1461182D03*
X1692629Y1465513D03*
Y1460782D03*
X1683968Y1471805D03*
Y1476536D03*
Y1481267D03*
X1692629Y1476136D03*
Y1470244D03*
Y1480867D03*
X1683968Y1487159D03*
Y1491890D03*
Y1496621D03*
X1692629Y1491490D03*
Y1485598D03*
Y1496221D03*
X1683968Y1502514D03*
Y1511976D03*
X1692629Y1506845D03*
Y1500952D03*
Y1511576D03*
X1683968Y1507245D03*
X1692629Y1516307D03*
X1683968Y1558813D03*
Y1563544D03*
X1692629Y1563144D03*
Y1572606D03*
X1683968Y1568275D03*
Y1574167D03*
Y1578898D03*
X1692629Y1567875D03*
Y1578498D03*
X1683968Y1583629D03*
Y1589522D03*
Y1594253D03*
X1692629Y1583229D03*
Y1593853D03*
Y1587960D03*
X1683968Y1598984D03*
X1692629Y1609207D03*
Y1598584D03*
Y1603315D03*
X1683968Y1609607D03*
Y1604876D03*
Y1614338D03*
X1692629Y1613938D03*
Y1618669D03*
X1692000Y1644980D03*
X1698583Y109172D03*
X1701583D03*
X1700590Y106495D03*
X1709134Y116497D03*
X1704334D03*
X1709134Y123584D03*
Y130670D03*
X1704334Y123584D03*
Y130670D03*
X1700324Y146012D03*
X1702230Y141228D03*
X1709134Y137757D03*
X1704334D03*
X1705118Y150847D03*
X1707086Y247292D03*
X1699795Y253198D03*
X1701495Y289735D03*
X1695142Y303839D03*
X1708889Y1189221D03*
X1696300Y1350683D03*
Y1345691D03*
X1701256Y1350683D03*
Y1345691D03*
X1708540D03*
Y1350683D03*
X1696300Y1357603D03*
Y1362595D03*
X1701256Y1357603D03*
Y1362595D03*
X1708540D03*
Y1357603D03*
X1696300Y1374881D03*
Y1369889D03*
Y1381801D03*
X1701256Y1369889D03*
Y1381801D03*
Y1374881D03*
X1708540D03*
Y1369889D03*
Y1381801D03*
X1696300Y1386793D03*
Y1394087D03*
Y1399079D03*
X1701256Y1386793D03*
Y1394087D03*
Y1399079D03*
X1708540D03*
Y1394087D03*
Y1386793D03*
X1696300Y1405999D03*
Y1410991D03*
X1701256Y1405999D03*
Y1410991D03*
X1708540Y1405999D03*
Y1410991D03*
X1701290Y1465913D03*
Y1456451D03*
Y1461182D03*
Y1471805D03*
Y1476536D03*
Y1481267D03*
Y1487159D03*
Y1491890D03*
Y1496621D03*
Y1507245D03*
Y1502514D03*
Y1511976D03*
Y1558813D03*
Y1563544D03*
Y1568275D03*
Y1574167D03*
Y1578898D03*
Y1583629D03*
Y1589522D03*
Y1594253D03*
Y1609607D03*
Y1604876D03*
Y1598984D03*
Y1614338D03*
X1724796Y82984D03*
Y77784D03*
Y80384D03*
Y75184D03*
Y85584D03*
X1716334Y116496D03*
Y109410D03*
Y102323D03*
X1711634Y116497D03*
Y109410D03*
X1716334Y130670D03*
Y123583D03*
X1711634D03*
Y130670D03*
X1716334Y137756D03*
X1720960Y1148000D03*
X1723796Y1160168D03*
X1725660Y1193019D03*
X1721660D03*
X1711783Y1193848D03*
X1713496Y1350683D03*
Y1345691D03*
X1720780Y1350683D03*
Y1345597D03*
X1725736Y1350683D03*
Y1345597D03*
X1713496Y1357603D03*
Y1362595D03*
X1720780Y1357603D03*
Y1362595D03*
X1725736Y1357603D03*
Y1362595D03*
X1713496Y1374881D03*
Y1369889D03*
Y1381801D03*
X1720780Y1369889D03*
Y1381801D03*
Y1374881D03*
X1725736Y1381801D03*
Y1374881D03*
Y1369889D03*
X1713496Y1399079D03*
Y1394087D03*
Y1386793D03*
X1720780D03*
Y1393993D03*
Y1399079D03*
X1725736Y1386793D03*
Y1399079D03*
Y1393993D03*
X1713496Y1405999D03*
Y1410991D03*
X1720780Y1405999D03*
Y1410991D03*
X1725736Y1405999D03*
Y1410991D03*
X1709952Y1465513D03*
Y1460782D03*
X1718613Y1465914D03*
Y1456452D03*
Y1461183D03*
Y1476537D03*
Y1471806D03*
Y1481268D03*
X1709952Y1476136D03*
Y1470244D03*
Y1480867D03*
Y1491490D03*
Y1485598D03*
Y1496221D03*
X1718613Y1491891D03*
Y1487160D03*
Y1496622D03*
Y1502515D03*
Y1511977D03*
X1709952Y1506845D03*
Y1500952D03*
Y1511576D03*
X1718613Y1507246D03*
X1709952Y1516307D03*
Y1563144D03*
X1718613Y1563544D03*
Y1558813D03*
X1709952Y1567875D03*
X1718613Y1568275D03*
X1709952Y1578498D03*
Y1572606D03*
X1718613Y1578898D03*
Y1574167D03*
Y1589522D03*
X1709952Y1583229D03*
X1718613Y1583629D03*
X1709952Y1593853D03*
Y1587960D03*
X1718613Y1594253D03*
Y1609607D03*
Y1598984D03*
Y1604876D03*
X1709952Y1609207D03*
Y1598584D03*
Y1603315D03*
Y1618669D03*
X1718613Y1614338D03*
X1709952Y1613938D03*
X1712000Y1644980D03*
X1727350Y92849D03*
X1734310Y103037D03*
X1734444Y116496D03*
Y109410D03*
Y130670D03*
Y123583D03*
X1730647Y137756D03*
X1739125Y293796D03*
X1736625D03*
X1737703Y472189D03*
X1728038Y491870D03*
X1730538D03*
X1730675Y1132361D03*
X1726963Y1132319D03*
X1739917Y1146937D03*
X1729207Y1159455D03*
X1737393Y1162817D03*
X1733660Y1193019D03*
X1729660D03*
X1737660D03*
X1733695Y1212164D03*
X1735989Y1214458D03*
X1731619Y1210089D03*
X1740785Y1219254D03*
X1737976Y1350683D03*
Y1345691D03*
X1733020D03*
Y1350683D03*
X1737976Y1362595D03*
Y1357603D03*
X1733020Y1362595D03*
Y1357603D03*
X1737976Y1369889D03*
Y1374881D03*
X1733020Y1369889D03*
Y1381801D03*
Y1374881D03*
X1737976Y1381801D03*
Y1399079D03*
Y1394087D03*
Y1386793D03*
X1733020Y1399079D03*
Y1394087D03*
Y1386793D03*
X1737976Y1405999D03*
Y1410991D03*
X1733020Y1405999D03*
Y1410991D03*
X1732000Y1644980D03*
X1755727Y94017D03*
X1747727D03*
X1751727D03*
X1751855Y110445D03*
Y115401D03*
X1756847D03*
Y110445D03*
X1751855Y129574D03*
Y124618D03*
X1756847D03*
Y129574D03*
X1753418Y191941D03*
X1753285Y188727D03*
X1747242Y226141D03*
X1750042D03*
X1755112Y256535D03*
X1749939Y288190D03*
X1747139D03*
X1744639D03*
X1749939Y285690D03*
X1744639D03*
X1747139D03*
X1758165Y290755D03*
X1754165D03*
X1744524Y370010D03*
X1753474Y542699D03*
X1757402Y825111D03*
Y820155D03*
X1744937Y912517D03*
X1747937D03*
X1750751Y910785D03*
X1748081Y984379D03*
X1756192Y996132D03*
X1743224Y1119055D03*
X1752000Y1644980D03*
X1764804Y84140D03*
Y76140D03*
Y80140D03*
X1759736Y94017D03*
X1767249Y117557D03*
X1762257D03*
Y122513D03*
Y131731D03*
X1767249Y122513D03*
Y131731D03*
X1762257Y136687D03*
X1767249D03*
X1765950Y180572D03*
X1770633Y180527D03*
X1774356Y192421D03*
X1759918Y184619D03*
X1770588Y185121D03*
X1765950Y185165D03*
X1761898Y206760D03*
X1763112Y256535D03*
X1764142Y279208D03*
X1768246Y281307D03*
X1762165Y290755D03*
X1765497Y370899D03*
X1766204Y398949D03*
X1770778Y402642D03*
X1773278D03*
X1763704Y401949D03*
X1767953Y413611D03*
X1770453D03*
X1772953D03*
X1772893Y423944D03*
X1770393D03*
X1767893D03*
X1765093D03*
X1765153Y413611D03*
X1764912Y482382D03*
X1765006Y478382D03*
X1761953Y706827D03*
Y865160D03*
X1772599Y993053D03*
X1762898Y992883D03*
X1764744Y1101930D03*
Y1097879D03*
X1766899Y1121122D03*
X1769499D03*
X1772099D03*
X1774799D03*
X1766999Y1130822D03*
X1772199D03*
X1769599D03*
X1774339Y1437975D03*
X1774216Y1470165D03*
X1772000Y1644980D03*
X1788884Y59871D03*
X1782382Y55513D03*
X1778179Y117261D03*
X1785886Y172665D03*
Y180665D03*
X1785918Y200864D03*
Y212864D03*
Y216864D03*
Y221864D03*
X1790014Y468607D03*
X1784602Y564092D03*
X1782600Y874500D03*
X1774899Y1130822D03*
Y1139822D03*
X1777399D03*
Y1147822D03*
X1774899D03*
X1785961Y1224892D03*
X1791099Y1260421D03*
X1779868Y1446668D03*
X1786564Y1478858D03*
X1777131Y1604357D03*
X1791570Y74535D03*
X1793149Y662810D03*
X1798705Y718793D03*
X1805013Y1091877D03*
X1792847Y1099210D03*
X1799012Y1095893D03*
X1805013Y1096470D03*
X1792863Y1103246D03*
X1801147Y1208555D03*
X1802844Y1227695D03*
X1793976Y1440762D03*
X1807270Y1468535D03*
X1793879Y1472952D03*
X1792000Y1644980D03*
X1816322Y977215D03*
X1823074Y992833D03*
X1812296Y1075688D03*
X1809696Y1091832D03*
X1809651Y1096426D03*
X1823028Y1124289D03*
X1817728D03*
X1815128D03*
X1820328D03*
X1822928Y1114589D03*
X1820228D03*
X1815028D03*
X1817628D03*
X1815865Y1133356D03*
X1809897Y1237285D03*
Y1230385D03*
Y1232885D03*
Y1239785D03*
Y1244185D03*
Y1246685D03*
X1807393Y1436345D03*
X1812000Y1644980D03*
X1831511Y978888D03*
X1831914Y992877D03*
X1824706Y1081145D03*
Y1089145D03*
X1837933Y1636171D03*
X1832000Y1644980D03*
G54D35*
X141337Y1228542D03*
X141336Y1247242D03*
Y1239762D03*
X161909Y1129429D03*
X160039Y1228543D03*
X169389Y1121948D03*
X167519Y1198621D03*
Y1213582D03*
X174999Y1228543D03*
X182480D03*
X167519D03*
X189960D03*
X197440D03*
X210531Y1211712D03*
X212401Y1228543D03*
X204921D03*
X213969Y1453293D03*
Y1464293D03*
X218011Y1211712D03*
X227362Y1228543D03*
X219881D03*
X227249Y1464293D03*
Y1453293D03*
X242322Y1250984D03*
X234842D03*
Y1254724D03*
X242322D03*
X249803Y1250984D03*
X257283D03*
Y1254724D03*
X249803D03*
X294685Y1127558D03*
Y1135039D03*
Y1194881D03*
Y1202362D03*
X290944Y1191141D03*
X294685Y1209842D03*
X302165Y1108858D03*
X298425Y1112598D03*
X309645D03*
Y1120078D03*
X305905Y1116338D03*
X298425Y1120078D03*
X305905Y1123818D03*
X309645Y1135039D03*
Y1127558D03*
X311515Y1136909D03*
X304035Y1140649D03*
X305905Y1131299D03*
X296555Y1151869D03*
X304035Y1155610D03*
Y1148129D03*
X296555Y1144389D03*
X311515D03*
Y1151869D03*
X296555Y1159350D03*
Y1166830D03*
X304035Y1170570D03*
X300295D03*
X311515Y1159350D03*
X300295Y1185531D03*
Y1178051D03*
X296555Y1174310D03*
X298425Y1187401D03*
X304035Y1185531D03*
Y1178051D03*
Y1193011D03*
X302165Y1198621D03*
X305905Y1206102D03*
X302165Y1213582D03*
Y1206102D03*
X298425Y1221062D03*
Y1217322D03*
X313385Y1105117D03*
X317125Y1116338D03*
Y1123818D03*
X313385D03*
Y1116338D03*
X315255Y1136909D03*
X313384Y1131299D03*
X315255Y1144389D03*
Y1151869D03*
Y1159350D03*
Y1166830D03*
Y1181791D03*
Y1189271D03*
Y1174310D03*
X313385Y1198621D03*
Y1206102D03*
X320866Y1217322D03*
X317125Y1221062D03*
X313385Y1213582D03*
X324606Y1209842D03*
Y1217322D03*
X320866Y1221062D03*
X324606D03*
X320866Y1236023D03*
Y1224803D03*
X324606Y1232283D03*
Y1236023D03*
Y1224803D03*
Y1243503D03*
X598424Y1228542D03*
X598423Y1239762D03*
Y1247242D03*
X618996Y1129429D03*
X617126Y1228543D03*
X626476Y1121948D03*
X624606Y1198621D03*
Y1213582D03*
X632086Y1228543D03*
X624606D03*
X639567D03*
X647047D03*
X667618Y1211712D03*
X654527Y1228543D03*
X662008D03*
X669488D03*
X675098Y1211712D03*
X676968Y1228543D03*
X684449D03*
X729331Y1250984D03*
X721850D03*
Y1254724D03*
X729331D03*
X748031Y1194881D03*
X744291Y1254724D03*
Y1250984D03*
X736811Y1254724D03*
Y1250984D03*
X762992Y1116338D03*
X766732Y1120078D03*
X762992Y1123818D03*
X766732Y1112598D03*
X759252Y1108858D03*
X755512Y1120078D03*
X761122Y1140649D03*
X762992Y1131299D03*
X766732Y1135039D03*
Y1127558D03*
X751772D03*
Y1135039D03*
X753642Y1144389D03*
X761122Y1148129D03*
Y1155610D03*
X753642Y1151869D03*
X757382Y1170570D03*
X761122D03*
X753642Y1166830D03*
Y1159350D03*
Y1181791D03*
Y1174310D03*
X757382Y1178051D03*
Y1185531D03*
X761122Y1178051D03*
Y1185531D03*
X753642Y1189271D03*
X759252Y1191141D03*
X762992D03*
X755512Y1194881D03*
X759252Y1198621D03*
X751772Y1202362D03*
X755512Y1221062D03*
Y1217322D03*
X759252Y1213582D03*
X762992Y1206102D03*
X759252D03*
X751772Y1209842D03*
X770472Y1105117D03*
Y1123818D03*
X774212D03*
X770472Y1116338D03*
X774212D03*
X770471Y1131299D03*
X770472Y1138779D03*
X772342Y1151869D03*
Y1144389D03*
X768602Y1151869D03*
Y1144389D03*
X772342Y1166830D03*
X768602Y1159350D03*
X772342D03*
Y1174310D03*
Y1181791D03*
Y1196751D03*
X770472Y1198621D03*
X781693Y1217322D03*
X777953D03*
X774212Y1221062D03*
X781693Y1209842D03*
X770472Y1213582D03*
Y1206102D03*
X781693Y1224803D03*
X777953D03*
X781693Y1232283D03*
X777953Y1236023D03*
X781693D03*
Y1243503D03*
X1055510Y1228542D03*
X1055509Y1239762D03*
Y1247242D03*
X1074212Y1228543D03*
X1083562Y1121948D03*
X1076082Y1129429D03*
X1081692Y1198621D03*
Y1213582D03*
Y1228543D03*
X1089172D03*
X1104133D03*
X1096653D03*
X1124704Y1211712D03*
X1119094Y1228543D03*
X1111613D03*
X1132184Y1211712D03*
X1126574Y1228543D03*
X1134054D03*
X1141535D03*
X1149015Y1254724D03*
X1156495D03*
X1149015Y1250984D03*
X1156495D03*
X1171456D03*
X1163976D03*
X1171456Y1254724D03*
X1163976D03*
X1203247Y1193011D03*
X1216338Y1108858D03*
X1212598Y1120078D03*
X1220078Y1116338D03*
Y1123818D03*
X1218208Y1140649D03*
X1208858Y1127558D03*
X1220078Y1131299D03*
X1208858Y1135039D03*
X1210728Y1151869D03*
X1218208Y1155610D03*
Y1148129D03*
X1210728Y1144389D03*
Y1159350D03*
Y1166830D03*
X1218208Y1170570D03*
X1214468D03*
X1210728Y1181791D03*
Y1189271D03*
X1218208Y1185531D03*
Y1178051D03*
X1214468Y1185531D03*
Y1178051D03*
X1210728Y1174310D03*
X1212598Y1194881D03*
X1218208Y1193011D03*
X1214468D03*
X1216338Y1198621D03*
X1208858Y1202362D03*
X1220078Y1206102D03*
X1216338D03*
X1212598Y1221062D03*
Y1217322D03*
X1216338Y1213582D03*
X1208858Y1209842D03*
X1227558Y1105117D03*
X1223818Y1112598D03*
Y1120078D03*
X1227558Y1116338D03*
X1231298D03*
X1227558Y1123818D03*
X1231298D03*
X1229428Y1136909D03*
X1223818Y1127558D03*
X1227557Y1131299D03*
X1223818Y1135039D03*
X1225688Y1144389D03*
Y1151869D03*
X1229428Y1144389D03*
Y1151869D03*
Y1159350D03*
X1225688D03*
X1229428Y1166830D03*
Y1181791D03*
Y1189271D03*
Y1174310D03*
Y1196751D03*
X1227558Y1198621D03*
Y1206102D03*
X1235039Y1217322D03*
X1231298Y1221062D03*
X1227558Y1213582D03*
X1235039Y1221062D03*
Y1224803D03*
Y1236023D03*
X1238779Y1217322D03*
Y1209842D03*
Y1221062D03*
Y1224803D03*
Y1232283D03*
Y1236023D03*
Y1243503D03*
X1514468Y1166829D03*
Y1174309D03*
Y1181790D03*
X1512597Y1228542D03*
X1512596Y1239762D03*
Y1247242D03*
X1540649Y1121948D03*
X1533169Y1129429D03*
X1538779Y1198621D03*
Y1213582D03*
X1531299Y1228543D03*
X1538779D03*
X1546259D03*
X1561220D03*
X1553740D03*
X1576181D03*
X1568700D03*
X1589271Y1211712D03*
X1581791D03*
X1583661Y1228543D03*
X1591141D03*
X1598622D03*
X1636023Y1254724D03*
Y1250984D03*
X1643504D03*
Y1254724D03*
X1660334Y1204232D03*
Y1200491D03*
Y1193011D03*
Y1196751D03*
Y1207972D03*
X1650984Y1250984D03*
Y1254724D03*
X1658464D03*
Y1250984D03*
X1673425Y1108858D03*
X1669685Y1112598D03*
Y1120078D03*
X1675295Y1140649D03*
X1665945Y1127558D03*
Y1135039D03*
X1667815Y1151869D03*
X1675295Y1155610D03*
Y1148129D03*
X1667815Y1144389D03*
Y1159350D03*
Y1166830D03*
X1675295Y1170570D03*
X1671555D03*
Y1185531D03*
Y1178051D03*
X1667815Y1174310D03*
Y1181791D03*
Y1189271D03*
X1675295Y1185531D03*
Y1178051D03*
X1669685Y1194881D03*
X1675295Y1193011D03*
X1671555D03*
X1665945Y1202362D03*
X1673425Y1198621D03*
X1669685Y1221062D03*
Y1217322D03*
X1673425Y1213582D03*
X1665945Y1209842D03*
X1673425Y1206102D03*
X1684645Y1105117D03*
X1677165Y1116338D03*
X1680905Y1112598D03*
X1677165Y1123818D03*
X1680905Y1120078D03*
X1684645Y1116338D03*
X1688385D03*
X1684645Y1123818D03*
X1688385D03*
X1686515Y1136909D03*
X1682775D03*
X1680905Y1127558D03*
X1677165Y1131299D03*
X1684644D03*
X1680905Y1135039D03*
X1682775Y1144389D03*
Y1151869D03*
X1686515Y1144389D03*
Y1151869D03*
Y1159350D03*
X1682775D03*
X1686515Y1166830D03*
Y1174310D03*
Y1181791D03*
Y1189271D03*
X1684645Y1198621D03*
X1692126Y1217322D03*
X1688385Y1221062D03*
X1684645Y1213582D03*
Y1206102D03*
X1677165D03*
X1692126Y1224803D03*
Y1236023D03*
X1695866Y1217322D03*
Y1209842D03*
Y1232283D03*
Y1236023D03*
Y1224803D03*
Y1243503D03*
G54D26*
X73872Y1348187D03*
X81752D03*
X73872Y1360099D03*
X81752D03*
X73872Y1384297D03*
Y1372385D03*
X81752Y1384297D03*
Y1372385D03*
X86112Y1348187D03*
X98352D03*
X93992D03*
X86112Y1360099D03*
X98352D03*
X93992D03*
X86112Y1384297D03*
Y1372385D03*
X98352Y1384297D03*
Y1372385D03*
X93992D03*
Y1384297D03*
X86112Y1396583D03*
X93992D03*
X98352D03*
X86112Y1408495D03*
X93992D03*
X98352D03*
X110592Y1348187D03*
X106232D03*
X110592Y1360099D03*
X106232D03*
X110592Y1384297D03*
X106232D03*
Y1372385D03*
X110592D03*
Y1396583D03*
X106232D03*
X110592Y1408495D03*
X106232D03*
X118472Y1348187D03*
X122832D03*
X130712D03*
X118472Y1360099D03*
X122832D03*
X130712D03*
X118472Y1384297D03*
Y1372385D03*
X122832Y1384297D03*
Y1372385D03*
X130712Y1384297D03*
Y1372385D03*
X118472Y1396583D03*
X122832D03*
X130712D03*
X118472Y1408495D03*
X122832D03*
X130712D03*
X146948Y1080806D03*
Y1103247D03*
X143208D03*
X146948Y1133169D03*
Y1140649D03*
X139468Y1136909D03*
X143208Y1125688D03*
Y1133169D03*
Y1140649D03*
X146948Y1125688D03*
X143208Y1144389D03*
Y1151870D03*
X146948Y1144389D03*
Y1151870D03*
X140707Y1170569D03*
X143208Y1159350D03*
X146948D03*
X148818Y1183661D03*
X140707Y1178050D03*
X145078Y1187401D03*
Y1183661D03*
X148818Y1187401D03*
X146947Y1174310D03*
X141337Y1191142D03*
X145078Y1194881D03*
Y1202362D03*
X148818Y1194881D03*
Y1202362D03*
X141337Y1198622D03*
Y1206103D03*
X145078Y1209842D03*
Y1217322D03*
X148818Y1209842D03*
Y1217322D03*
X141337Y1213583D03*
Y1221063D03*
X148818Y1224803D03*
X145078Y1232283D03*
Y1236023D03*
X148818Y1232283D03*
Y1236023D03*
X145078Y1224803D03*
X148818Y1254724D03*
Y1239763D03*
X145078D03*
X135072Y1348187D03*
X142952D03*
X147312D03*
X135072Y1360099D03*
X147312D03*
X142952D03*
X135072Y1384297D03*
Y1372385D03*
X147312Y1384297D03*
Y1372385D03*
X142952Y1384297D03*
Y1372385D03*
X135072Y1396583D03*
X147312D03*
X142952D03*
X135072Y1408495D03*
X147312D03*
X142952D03*
X150688Y1077066D03*
X158169Y1106988D03*
X165649D03*
X161909D03*
X158169Y1118208D03*
Y1121948D03*
X154429D03*
X150689D03*
X165649Y1114468D03*
X161909D03*
X158169Y1133169D03*
X161909Y1140649D03*
X158169Y1125688D03*
X154429Y1129429D03*
X150689D03*
Y1136909D03*
X154429Y1140649D03*
X150689D03*
X165649D03*
Y1129429D03*
Y1136909D03*
X158169Y1140649D03*
X150689Y1151870D03*
X158169Y1155610D03*
X154429D03*
X150689D03*
X161909Y1144389D03*
Y1148129D03*
Y1151870D03*
Y1155610D03*
X150689Y1144389D03*
Y1148129D03*
Y1159350D03*
X158169Y1166830D03*
X150688D03*
X154429Y1170570D03*
X150688D03*
X161909Y1159350D03*
X160039Y1187401D03*
X156299Y1183661D03*
X152559D03*
X161909Y1174310D03*
Y1178051D03*
X165649Y1181791D03*
X161909D03*
X158169Y1174310D03*
X154429D03*
X150688Y1178051D03*
Y1174310D03*
X156299Y1179921D03*
X160039Y1183661D03*
X163779D03*
Y1187401D03*
X156299Y1198621D03*
X152559D03*
X163779D03*
X160039D03*
X152559Y1191141D03*
X156299D03*
X160039D03*
X163779D03*
Y1194881D03*
Y1202362D03*
X160039Y1206102D03*
X156299D03*
X152559D03*
X163779D03*
X156299Y1213582D03*
X152559D03*
X160039Y1221062D03*
X156299D03*
X152559D03*
X163779D03*
Y1209842D03*
Y1217322D03*
X152559Y1228543D03*
X160039Y1224803D03*
X152559D03*
X156299Y1232283D03*
Y1236023D03*
X163779D03*
Y1232283D03*
Y1224803D03*
X156299D03*
Y1228543D03*
X163779D03*
X160039Y1239763D03*
X152559D03*
Y1243503D03*
X160039D03*
X163779Y1239763D03*
X152559Y1258465D03*
X160039D03*
X159552Y1348187D03*
X155192D03*
X159552Y1360099D03*
X155192D03*
X159552Y1372385D03*
Y1384297D03*
X155192D03*
Y1372385D03*
X159552Y1396583D03*
X155192D03*
X159552Y1408495D03*
X155192D03*
X174998Y1071455D03*
X182479D03*
X178740Y1090157D03*
X174999D03*
X171259D03*
X182480D03*
X178740Y1093897D03*
Y1097637D03*
X174999Y1101377D03*
X169389Y1106988D03*
X171259Y1093897D03*
X174999Y1105117D03*
X182480Y1101377D03*
Y1105117D03*
X174999Y1108858D03*
X178740D03*
X176870Y1114468D03*
Y1118208D03*
Y1121948D03*
X178740Y1112598D03*
X173129Y1110728D03*
X169389D03*
X180610Y1114468D03*
Y1118208D03*
Y1121948D03*
X182480Y1112598D03*
Y1108858D03*
X180610Y1136909D03*
X173129Y1133169D03*
X169389D03*
X176870Y1140649D03*
Y1125688D03*
Y1129429D03*
Y1133169D03*
Y1136909D03*
X173129Y1140649D03*
X169389D03*
X180610D03*
Y1125688D03*
Y1129429D03*
Y1133169D03*
Y1148129D03*
X173129Y1144389D03*
X169389D03*
X173129Y1148129D03*
Y1155610D03*
Y1151870D03*
X180610Y1155610D03*
Y1151870D03*
Y1144389D03*
X176870Y1170570D03*
X173129Y1159350D03*
Y1166830D03*
Y1170570D03*
X180610Y1166830D03*
Y1159350D03*
Y1174310D03*
Y1181791D03*
X173129Y1174310D03*
Y1178051D03*
Y1181791D03*
X171259Y1187401D03*
X174999D03*
X180610Y1178051D03*
X167519Y1183661D03*
X178740Y1187401D03*
X182480D03*
X176870Y1185531D03*
X173129D03*
X167519Y1187401D03*
X171259Y1202362D03*
Y1194881D03*
X174999Y1202362D03*
Y1194881D03*
X167519Y1191141D03*
X178740D03*
Y1194881D03*
Y1198621D03*
Y1202362D03*
X182480Y1191141D03*
Y1198621D03*
Y1202362D03*
X174999Y1198621D03*
Y1191141D03*
X167519Y1194881D03*
X171259Y1198621D03*
Y1191141D03*
X167519Y1202362D03*
X171259Y1209842D03*
X174999Y1217322D03*
X171259Y1221062D03*
X174999D03*
X171259Y1217322D03*
X167519Y1206102D03*
X178740D03*
Y1209842D03*
Y1213582D03*
Y1221062D03*
X182480D03*
X178740Y1217322D03*
X182480Y1206102D03*
Y1209842D03*
Y1213582D03*
Y1217322D03*
X167519Y1209842D03*
X171259Y1213582D03*
Y1206102D03*
X174999D03*
X167519Y1217322D03*
X174999Y1213582D03*
X178740Y1228543D03*
X171259Y1224803D03*
Y1228543D03*
X178740Y1224803D03*
Y1232283D03*
Y1236023D03*
X171259Y1232283D03*
X174999Y1224803D03*
X171259Y1236023D03*
X182480Y1224803D03*
X167519D03*
X182480Y1243503D03*
X171259Y1250984D03*
X174999Y1247243D03*
Y1239763D03*
X171259D03*
X167519D03*
Y1243503D03*
X175000Y1258465D03*
X182480D03*
X167519D03*
X167432Y1348187D03*
X171792D03*
X179672D03*
X167432Y1360099D03*
X171792D03*
X179672D03*
X167432Y1384297D03*
Y1372385D03*
X171792Y1384297D03*
Y1372385D03*
X179672Y1384297D03*
Y1372385D03*
X171792Y1396583D03*
X179672D03*
X167432D03*
Y1408495D03*
X171792D03*
X179672D03*
X197439Y1071455D03*
X189959D03*
X193700Y1090157D03*
X189960D03*
X186220D03*
X197440D03*
X193700Y1093897D03*
X189960Y1101377D03*
X186220Y1097637D03*
X189960Y1105117D03*
X186220Y1093897D03*
X193700Y1097637D03*
X197440Y1101377D03*
Y1105117D03*
X189960Y1093897D03*
X195570Y1121948D03*
X191830Y1118208D03*
X188090D03*
X184350D03*
X191830Y1121948D03*
X188090D03*
X184350D03*
X195570Y1118208D03*
X186220Y1108858D03*
X189960D03*
X193700D03*
X197440D03*
X191830Y1125688D03*
X188090D03*
X184350D03*
X188090Y1129429D03*
X184350D03*
X188090Y1133169D03*
X184350D03*
X188090Y1136909D03*
Y1140649D03*
X184350D03*
X195570Y1133169D03*
Y1129429D03*
Y1125688D03*
Y1136909D03*
X188090Y1144389D03*
Y1151870D03*
X191830Y1155610D03*
Y1148129D03*
X195570Y1151869D03*
Y1144389D03*
X188090Y1159350D03*
Y1170570D03*
X191830Y1166830D03*
X195570Y1159350D03*
Y1170570D03*
X188090Y1185531D03*
X195570Y1189271D03*
X191830Y1181791D03*
Y1174310D03*
X195570Y1185531D03*
Y1178051D03*
X188090Y1196751D03*
Y1200491D03*
Y1204232D03*
X191830D03*
Y1196751D03*
Y1200491D03*
X184350Y1193011D03*
Y1196751D03*
X195570Y1200491D03*
Y1196751D03*
Y1193011D03*
Y1204232D03*
X186220Y1198621D03*
X193700Y1209842D03*
X191830Y1207972D03*
X189960Y1209842D03*
X195570Y1207972D03*
X193700Y1213582D03*
X191830Y1219192D03*
X186220Y1221062D03*
X189960D03*
X193700D03*
X197440D03*
X186220Y1206102D03*
Y1209842D03*
Y1213582D03*
X197440Y1209842D03*
X186220Y1224803D03*
X193700Y1228543D03*
X197440Y1224803D03*
X193700Y1232283D03*
X186220D03*
X189960Y1224803D03*
X193700Y1236023D03*
X186220D03*
Y1228543D03*
X193700Y1224803D03*
X197440Y1239763D03*
Y1243503D03*
X193700Y1239763D03*
X186220D03*
X189960Y1243503D03*
Y1258465D03*
X197441D03*
X184032Y1348187D03*
X191912D03*
X196272D03*
X184032Y1360099D03*
X196272D03*
X191912D03*
X184032Y1384297D03*
Y1372385D03*
X196272Y1384297D03*
Y1372385D03*
X191912Y1384297D03*
Y1372385D03*
X184032Y1396583D03*
X191912D03*
X196272D03*
X184032Y1408495D03*
X191912D03*
X196272D03*
X204920Y1071455D03*
X212400D03*
X204921Y1090157D03*
X212401D03*
X208661D03*
X201181D03*
X204921Y1101377D03*
X208661Y1097637D03*
X201181D03*
X204921Y1105117D03*
X212401Y1101377D03*
Y1105117D03*
X201181Y1093897D03*
X208661D03*
X199311Y1118208D03*
Y1121948D03*
X206791Y1118208D03*
X203051D03*
Y1121948D03*
X206791D03*
X210531Y1118208D03*
X214271Y1110728D03*
X210531Y1121948D03*
X214271Y1118208D03*
Y1121948D03*
X201181Y1108858D03*
X204921D03*
X208661D03*
X212401D03*
X199311Y1140649D03*
X203051D03*
X206791D03*
X199311Y1125688D03*
X203051D03*
X206791D03*
Y1133169D03*
X203051D03*
X199311D03*
X210531D03*
Y1140649D03*
X214271D03*
Y1125688D03*
X210531D03*
X214271Y1133169D03*
X203051Y1148129D03*
X199311D03*
X206791D03*
X214271D03*
X210531D03*
X199311Y1155610D03*
X206791D03*
X214271D03*
X206791Y1166830D03*
X203051Y1159350D03*
X199311Y1166830D03*
X203051Y1170570D03*
X214271Y1166830D03*
X210531Y1159350D03*
Y1170570D03*
X206791Y1181791D03*
X203051D03*
X199311D03*
X206791Y1189271D03*
X203051D03*
X199311D03*
X214271Y1181791D03*
X210531D03*
X214271Y1189271D03*
X210531D03*
X199311Y1174310D03*
X206791D03*
X214271D03*
X206791Y1196751D03*
X203051D03*
X199311D03*
Y1204232D03*
X203051D03*
X206791D03*
X214271Y1196751D03*
X210531D03*
Y1204232D03*
X214271D03*
X206791Y1207972D03*
X203051D03*
X199311D03*
X210531D03*
X214271D03*
X212401Y1221062D03*
X208661D03*
X204921D03*
X201181D03*
Y1224803D03*
X208661Y1228543D03*
X212401Y1224803D03*
X208661Y1232283D03*
X201181D03*
X204921Y1224803D03*
X201181Y1236023D03*
X208661D03*
Y1224803D03*
X201181Y1228543D03*
X212401Y1243503D03*
X208661Y1239763D03*
X204921Y1243503D03*
X208661D03*
X204921Y1250984D03*
X208661Y1247243D03*
X212401Y1254724D03*
X201181Y1243503D03*
X212401Y1250984D03*
X201181Y1247243D03*
X204921Y1254724D03*
X212401Y1258465D03*
X204921D03*
X204152Y1348187D03*
Y1360099D03*
Y1384297D03*
Y1372385D03*
Y1396583D03*
Y1408495D03*
X219880Y1071455D03*
X227361D03*
X227362Y1090157D03*
X223622D03*
X219881D03*
X231102D03*
X216141D03*
X223622Y1093897D03*
X231102D03*
Y1097637D03*
X227362Y1101377D03*
Y1105117D03*
X219881Y1101377D03*
Y1105117D03*
X223622Y1097637D03*
X216141D03*
Y1093897D03*
X225492Y1118208D03*
Y1121948D03*
X218011Y1118208D03*
X221751D03*
X218011Y1121948D03*
X221751D03*
X229232D03*
Y1118208D03*
Y1114468D03*
X216141Y1108858D03*
X219881D03*
X223622D03*
X227362D03*
X231102D03*
X225492Y1133169D03*
Y1140649D03*
Y1125688D03*
X218011Y1140649D03*
X221751D03*
X218011Y1125688D03*
X221751D03*
Y1133169D03*
X218011D03*
X229330Y1132677D03*
X229232Y1140649D03*
Y1125688D03*
X225492Y1148129D03*
X221751D03*
X218011D03*
X229232D03*
X221751Y1155610D03*
X229232D03*
X225492Y1170570D03*
Y1159350D03*
X218011Y1170570D03*
X221752Y1166830D03*
X218011Y1159350D03*
X229232Y1166830D03*
X225492Y1181791D03*
Y1189271D03*
X221751Y1181791D03*
X218011D03*
X221751Y1189271D03*
X218011D03*
X229232Y1181791D03*
Y1189271D03*
X221751Y1174310D03*
X229232D03*
X218011Y1204232D03*
X229232Y1196751D03*
Y1204232D03*
X225492Y1196751D03*
Y1204232D03*
X221751D03*
Y1196751D03*
X218011D03*
X225492Y1207972D03*
X221751D03*
X218011D03*
X229232D03*
X231102Y1221062D03*
X227362D03*
X219881Y1217322D03*
X223622Y1221062D03*
X219881D03*
X216141D03*
X231102Y1224803D03*
X227362D03*
X223622Y1232283D03*
X219881Y1224803D03*
X223622Y1236023D03*
X231102Y1232283D03*
Y1236023D03*
X216141Y1232283D03*
Y1236023D03*
Y1224803D03*
X223622D03*
Y1228543D03*
X216141D03*
X223622Y1239763D03*
X231102D03*
X227362Y1243503D03*
X219881D03*
X216141Y1239763D03*
X231102Y1243503D03*
Y1247243D03*
X223622Y1243503D03*
X216141Y1247243D03*
X223622D03*
X216141Y1243503D03*
X219881Y1250984D03*
Y1254724D03*
X227362D03*
Y1250984D03*
X219882Y1258465D03*
X227363D03*
X246062Y1075196D03*
X234841Y1071454D03*
X242321Y1071455D03*
X238582Y1075196D03*
X234842Y1090157D03*
X246062D03*
Y1078936D03*
X238582Y1090157D03*
X242322Y1086417D03*
X234842Y1082677D03*
Y1086417D03*
X242322Y1090157D03*
X246062Y1097637D03*
Y1093897D03*
X242322Y1105117D03*
X234842Y1101377D03*
X238582Y1093897D03*
X242322Y1101377D03*
X234842Y1105117D03*
X236712Y1121948D03*
X240452D03*
X244192D03*
X234842Y1108858D03*
X238582D03*
X242322D03*
X246062D03*
X236712Y1133464D03*
X240452Y1133169D03*
X236712Y1140649D03*
X240452D03*
X236712Y1125688D03*
X240452D03*
X244192Y1133169D03*
Y1140649D03*
Y1125688D03*
X236712Y1148129D03*
X240452D03*
X244192D03*
X240452Y1155610D03*
Y1166830D03*
X236712Y1170570D03*
Y1159350D03*
X244192Y1170570D03*
Y1159350D03*
X240452Y1181791D03*
X236712D03*
Y1189271D03*
X240452D03*
X244192Y1181791D03*
Y1189271D03*
X240452Y1174310D03*
Y1204232D03*
X236712D03*
Y1196751D03*
X240452D03*
X244192Y1204232D03*
Y1196751D03*
X240452Y1207972D03*
Y1211712D03*
X242322Y1221062D03*
X244192Y1211712D03*
Y1207972D03*
X236712D03*
X234842Y1221062D03*
X238582D03*
X246062Y1232283D03*
Y1236023D03*
X238582Y1232283D03*
X234842Y1228543D03*
Y1224803D03*
X238582Y1236023D03*
X242322Y1228543D03*
Y1224803D03*
X246062Y1239763D03*
X238582D03*
Y1247243D03*
X246062Y1243503D03*
Y1247243D03*
X238582Y1243503D03*
X234842Y1258465D03*
X242322D03*
X239383Y1348187D03*
X247263D03*
Y1360099D03*
X239383D03*
X247263Y1384297D03*
Y1372385D03*
X239383Y1384297D03*
Y1372385D03*
X253543Y1075196D03*
X261023D03*
X249802Y1071455D03*
X257282D03*
X253543Y1090157D03*
X249803D03*
Y1086417D03*
X253543Y1078936D03*
X257283Y1090157D03*
Y1086417D03*
X261023Y1090157D03*
Y1078936D03*
X249803Y1105117D03*
X253543Y1093897D03*
Y1097637D03*
X257283Y1105117D03*
X261023Y1093897D03*
Y1097637D03*
X249802D03*
X257282D03*
X249802Y1093897D03*
X257282D03*
X255413Y1121948D03*
X251673D03*
X247933D03*
X262893D03*
X259153D03*
X249803Y1108858D03*
X253543D03*
X257283D03*
X261023D03*
X247933Y1133169D03*
X251673D03*
X255413D03*
X247933Y1140649D03*
X251673D03*
X255413D03*
X247933Y1125688D03*
X251673D03*
X255413D03*
X259153Y1133169D03*
X262893D03*
Y1140649D03*
X259153Y1125688D03*
X262893D03*
X259153Y1140649D03*
Y1148129D03*
X262893D03*
Y1155610D03*
X247933Y1148129D03*
X251673D03*
X255413D03*
X247933Y1155610D03*
X255413D03*
X262893Y1166830D03*
X251673Y1170570D03*
X255413Y1166830D03*
X247933D03*
X251673Y1159350D03*
X259153D03*
Y1170570D03*
X247933Y1181791D03*
X251673D03*
X255413D03*
X247933Y1189271D03*
X251673D03*
X255413D03*
X262893D03*
Y1174310D03*
X259153Y1181791D03*
X262893D03*
X259153Y1189271D03*
X255413Y1174310D03*
X247933D03*
Y1204232D03*
X255413D03*
X251673D03*
X247933Y1196751D03*
X251673D03*
X255413D03*
X259153Y1204232D03*
X262893D03*
X259153Y1196751D03*
X262893D03*
X247933Y1207972D03*
X251673D03*
X255413Y1211712D03*
Y1207972D03*
X262893D03*
X259153D03*
X262893Y1211712D03*
X259153D03*
X249803Y1228543D03*
X257283D03*
X249803Y1224803D03*
X253543Y1236023D03*
X257283Y1224803D03*
X261023Y1236023D03*
X253543Y1232283D03*
X261023D03*
X257283Y1239763D03*
X253543Y1247243D03*
Y1243503D03*
X249803Y1258465D03*
X257283D03*
X263863Y1348187D03*
X259503D03*
X251623D03*
X263863Y1360099D03*
X259503D03*
X251623D03*
X263863Y1384297D03*
Y1372385D03*
X259503Y1384297D03*
Y1372385D03*
X251623D03*
Y1384297D03*
X263863Y1396583D03*
X259503D03*
X251623D03*
X263863Y1408495D03*
X259503D03*
X251623D03*
X279723Y1071455D03*
X264762D03*
X272243D03*
X268503Y1075196D03*
X275984D03*
X279724Y1090157D03*
X272244Y1082677D03*
X275984Y1090157D03*
X272244Y1086417D03*
X268503Y1078936D03*
Y1090157D03*
X264763Y1086417D03*
X272244Y1090157D03*
X264763D03*
X268503Y1093897D03*
Y1097637D03*
X272244Y1105117D03*
X279724D03*
X275984Y1093897D03*
X264763Y1105117D03*
X274114Y1118208D03*
X270373D03*
X266633Y1121948D03*
X270373D03*
X277854Y1118208D03*
X264763Y1108858D03*
X268503D03*
X272244D03*
X275984D03*
X279724D03*
X274114Y1125688D03*
X270373Y1136909D03*
X266633Y1133169D03*
X270373D03*
X266633Y1140649D03*
X270373Y1125688D03*
Y1129429D03*
X266633Y1125688D03*
X270373Y1140649D03*
X277854Y1136909D03*
Y1140649D03*
X274114Y1155610D03*
Y1151869D03*
Y1148129D03*
X266633D03*
X270373Y1144389D03*
Y1148129D03*
Y1151869D03*
X277854Y1144389D03*
Y1148129D03*
Y1151870D03*
X270373Y1155610D03*
X274114Y1166830D03*
Y1159350D03*
Y1170570D03*
X266633Y1181791D03*
X270373Y1189271D03*
X277854Y1178051D03*
Y1189271D03*
Y1185531D03*
X270373Y1174310D03*
X277854Y1181791D03*
X274114D03*
Y1174310D03*
X266633Y1189271D03*
X270373Y1178051D03*
Y1185531D03*
X274114Y1196751D03*
X270393Y1196732D03*
X270373Y1204232D03*
X266633D03*
X270373Y1200491D03*
X266633Y1196751D03*
X270373Y1193011D03*
X277854D03*
X274114Y1207972D03*
X270373Y1211712D03*
X266633Y1207972D03*
Y1211712D03*
X270373Y1207972D03*
X277854Y1211712D03*
X279724Y1221062D03*
X275984D03*
X272244D03*
X268503D03*
X279724Y1224803D03*
X272244D03*
X268503Y1236023D03*
Y1232283D03*
X272244Y1228543D03*
X264763Y1224803D03*
X275984Y1232283D03*
Y1236023D03*
X264763Y1228543D03*
X279724D03*
X268503Y1239763D03*
X279724Y1258465D03*
X264763D03*
X272244D03*
X276103Y1348187D03*
X271743D03*
X276103Y1360099D03*
X271743D03*
X276103Y1384297D03*
Y1372385D03*
X271743Y1384297D03*
Y1372385D03*
X276103Y1396583D03*
X271743D03*
Y1408495D03*
X276103D03*
X294684Y1071455D03*
X290944Y1075196D03*
X287203Y1071455D03*
X283464Y1075196D03*
X287204Y1090157D03*
X283464Y1078936D03*
Y1090157D03*
X290943D03*
X290944Y1093897D03*
X287204Y1101377D03*
Y1105117D03*
X294685D03*
X294684Y1120078D03*
Y1112598D03*
X283464Y1108858D03*
X287204D03*
X290944D03*
X294685D03*
X290944Y1112598D03*
Y1116338D03*
Y1120078D03*
Y1123818D03*
X281594Y1140649D03*
Y1136909D03*
X290944Y1127558D03*
Y1131299D03*
Y1135039D03*
Y1138779D03*
X281594Y1148129D03*
Y1155610D03*
Y1151869D03*
X285334D03*
X289074D03*
Y1155610D03*
X292814Y1151869D03*
Y1144389D03*
X281594Y1159350D03*
X289074Y1166830D03*
Y1170570D03*
Y1159350D03*
X281594Y1170570D03*
Y1166830D03*
X292814Y1159350D03*
Y1166830D03*
Y1181791D03*
X285334Y1185531D03*
X289074Y1174310D03*
Y1178051D03*
Y1185531D03*
X281594Y1189271D03*
Y1185531D03*
X285334Y1181791D03*
X281594Y1178051D03*
Y1174310D03*
X292814D03*
Y1189271D03*
X281594Y1196751D03*
Y1204232D03*
Y1193011D03*
X285334D03*
X290944Y1194881D03*
Y1198621D03*
Y1202362D03*
X294685Y1221062D03*
Y1217322D03*
X290944Y1221062D03*
X287204D03*
X283464D03*
X290944Y1206102D03*
Y1209842D03*
Y1213582D03*
Y1217322D03*
X294685Y1228543D03*
Y1224803D03*
X290944Y1232283D03*
Y1236023D03*
X283464Y1232283D03*
X287204Y1228543D03*
X283464Y1236023D03*
X287204Y1224803D03*
X283464Y1239763D03*
X290944D03*
X294685Y1254724D03*
Y1250984D03*
X290944Y1247243D03*
Y1243503D03*
X294685Y1258465D03*
X287204D03*
X288343Y1348187D03*
X296223D03*
X283983D03*
X288343Y1360099D03*
X296223D03*
X283983D03*
X288343Y1384297D03*
Y1372385D03*
X296223Y1384297D03*
Y1372385D03*
X283983D03*
Y1384297D03*
X288343Y1396583D03*
X296223D03*
X283983D03*
X288343Y1408495D03*
X296223D03*
X283983D03*
X309645Y1071455D03*
X302165D03*
X298425Y1075196D03*
X305906D03*
X298424Y1090157D03*
X298426Y1078936D03*
X305906D03*
X302165Y1105117D03*
X309645D03*
X298425Y1093897D03*
X305905D03*
X302165Y1123818D03*
X305904Y1108857D03*
X302165Y1116338D03*
X298425Y1108858D03*
X300295Y1140649D03*
X302165Y1131299D03*
X300295Y1148129D03*
Y1159350D03*
Y1166830D03*
X311515D03*
X307775Y1170570D03*
X300295Y1181791D03*
Y1174310D03*
Y1189271D03*
X311515Y1174310D03*
X307775Y1178051D03*
X311515Y1181791D03*
X307775Y1185531D03*
X311515Y1189271D03*
X298425Y1202362D03*
Y1194881D03*
X309645Y1198621D03*
X307775Y1193011D03*
X311515Y1196751D03*
X305905Y1198621D03*
X309645Y1202362D03*
X298425Y1209842D03*
X302165Y1221062D03*
X309645Y1217322D03*
Y1209842D03*
X305905Y1213582D03*
X309645D03*
Y1206102D03*
Y1221062D03*
X305905D03*
X298425Y1236023D03*
Y1232283D03*
X302165Y1228543D03*
Y1224803D03*
X305905Y1232283D03*
X309645Y1228543D03*
Y1224803D03*
X305905Y1236023D03*
X298425Y1239763D03*
X309645D03*
Y1254724D03*
X298425Y1247243D03*
X309645Y1250984D03*
X298425Y1243503D03*
X305905D03*
Y1247243D03*
X302165Y1254724D03*
Y1250984D03*
X309645Y1258465D03*
X302165D03*
X308463Y1348187D03*
X300583D03*
X308463Y1360099D03*
X300583D03*
X308463Y1372385D03*
X300583D03*
Y1384297D03*
X308463D03*
Y1396583D03*
X300583D03*
X308463Y1408495D03*
X300583D03*
X317125Y1071455D03*
X320866Y1075196D03*
X313386D03*
X320866Y1078936D03*
X313384Y1090157D03*
X313386Y1078936D03*
X328347Y1082677D03*
Y1090158D03*
X324606Y1078936D03*
X313385Y1093897D03*
X328347Y1101378D03*
Y1116339D03*
Y1123819D03*
Y1108859D03*
X313385Y1108858D03*
X328347Y1131300D03*
X318996Y1140649D03*
Y1155610D03*
Y1148129D03*
X322736Y1170570D03*
X318996D03*
Y1185531D03*
Y1178051D03*
X322736D03*
Y1185531D03*
X328347Y1198621D03*
X322736Y1193011D03*
X320866Y1202362D03*
X318996Y1193011D03*
X326416D03*
X324606Y1202362D03*
X328347Y1206102D03*
Y1221062D03*
Y1213582D03*
X320866Y1209842D03*
X313385Y1221062D03*
X320866Y1206102D03*
Y1232283D03*
X313385D03*
X317125Y1228543D03*
Y1224803D03*
X313385Y1236023D03*
X328347Y1228543D03*
Y1239762D03*
Y1247243D03*
X324606Y1250984D03*
X317125Y1254724D03*
X324606Y1239763D03*
X313385Y1247243D03*
X317125Y1250984D03*
X320866Y1239763D03*
X313385Y1243503D03*
X317125Y1258465D03*
X320703Y1348187D03*
X312823D03*
X325063D03*
X320703Y1360099D03*
X312823D03*
X325063D03*
X320703Y1372385D03*
Y1384297D03*
X312823Y1372385D03*
Y1384297D03*
X325063Y1372385D03*
Y1384297D03*
Y1396583D03*
X320703D03*
X312823D03*
X320703Y1408495D03*
X312823D03*
X325063D03*
X318448Y1750941D03*
Y1760941D03*
X318348Y1796941D03*
Y1806941D03*
X337303Y1348187D03*
X332943D03*
Y1360099D03*
X337303D03*
X332943Y1384297D03*
Y1372385D03*
X337303D03*
Y1384297D03*
X332943Y1396583D03*
X337303D03*
X332943Y1408495D03*
X337303D03*
X349543Y1348187D03*
X357423D03*
X345183D03*
X349543Y1360099D03*
X357423D03*
X345183D03*
Y1372385D03*
Y1384297D03*
X349543D03*
Y1372385D03*
X357423D03*
Y1384297D03*
X345183Y1396583D03*
X349543D03*
X357423D03*
X345183Y1408495D03*
X349543D03*
X357423D03*
X369663Y1348187D03*
X361783D03*
X369663Y1360099D03*
X361783D03*
X369663Y1372385D03*
Y1384297D03*
X361783D03*
Y1372385D03*
X369663Y1396583D03*
X361783D03*
X369663Y1408495D03*
X361783D03*
X458282Y1348187D03*
X446042D03*
X458282Y1360099D03*
X446042D03*
X458282Y1372385D03*
X446042D03*
X458282Y1384297D03*
X446042D03*
X458282Y1396583D03*
Y1408495D03*
X470522Y1348187D03*
Y1360099D03*
Y1384297D03*
Y1372385D03*
Y1396583D03*
Y1408495D03*
X482762Y1348187D03*
Y1360099D03*
Y1384297D03*
Y1372385D03*
Y1396583D03*
Y1408495D03*
X507242Y1348187D03*
X495002D03*
X507242Y1360099D03*
X495002D03*
Y1384297D03*
X507242D03*
X495002Y1372385D03*
X507242D03*
Y1396583D03*
X495002D03*
X507242Y1408495D03*
X495002D03*
X519482Y1348187D03*
Y1360099D03*
Y1384297D03*
Y1372385D03*
Y1396583D03*
Y1408495D03*
X531722Y1348187D03*
Y1360099D03*
Y1384297D03*
Y1372385D03*
Y1396583D03*
Y1408495D03*
X556202Y1348187D03*
X543962D03*
X556202Y1360099D03*
X543962D03*
Y1372385D03*
Y1384297D03*
X556202D03*
Y1372385D03*
Y1396583D03*
X543962D03*
X556202Y1408495D03*
X543962D03*
X568442Y1348187D03*
Y1360099D03*
Y1384297D03*
Y1372385D03*
Y1396583D03*
Y1408495D03*
X604035Y1080806D03*
Y1103247D03*
X600295D03*
Y1125688D03*
Y1133169D03*
Y1140649D03*
X604035Y1125688D03*
Y1133169D03*
Y1140649D03*
X600295Y1144389D03*
Y1151870D03*
X604035Y1144389D03*
Y1151870D03*
X600295Y1159350D03*
X604035D03*
X597795Y1170570D03*
X604034Y1174310D03*
X597795Y1178050D03*
X602165Y1183661D03*
Y1187401D03*
Y1202362D03*
Y1194881D03*
X598424Y1198622D03*
Y1191142D03*
X602165Y1191141D03*
Y1198621D03*
Y1217322D03*
Y1209842D03*
X598424Y1221063D03*
Y1213583D03*
Y1206103D03*
X602165Y1221062D03*
Y1206102D03*
Y1213582D03*
Y1224803D03*
Y1236023D03*
Y1232283D03*
Y1247243D03*
Y1239763D03*
X605386Y1728583D03*
Y1738583D03*
X605312Y1774624D03*
Y1784624D03*
X607775Y1077066D03*
X615256Y1106988D03*
X618996D03*
X615256Y1118208D03*
Y1121948D03*
X611516D03*
X607776D03*
X618996Y1114468D03*
X615256Y1125688D03*
X611516Y1129429D03*
X607776D03*
Y1136909D03*
X615256Y1140649D03*
X611516D03*
X607776D03*
X618996D03*
Y1144389D03*
Y1148129D03*
Y1151870D03*
Y1155610D03*
X607776Y1144389D03*
Y1148129D03*
Y1151870D03*
X615256Y1155610D03*
X611516D03*
X607776D03*
Y1159350D03*
X615256Y1166830D03*
X607775D03*
X611516Y1170570D03*
X607775D03*
X618996Y1159350D03*
Y1174310D03*
Y1178051D03*
X607775Y1174310D03*
Y1178051D03*
X611516Y1174310D03*
X615256D03*
X613386Y1183661D03*
X617126Y1187401D03*
Y1183661D03*
X613386Y1179921D03*
X620866Y1183661D03*
X609646D03*
X605905D03*
Y1187401D03*
X613386D03*
X609646D03*
X620866D03*
X613386Y1198621D03*
X609646Y1191141D03*
X613386D03*
X617126Y1198621D03*
X620866D03*
X617126Y1191141D03*
X620866D03*
X605905Y1202362D03*
Y1194881D03*
X609646Y1198621D03*
X605905Y1191141D03*
X613386Y1194881D03*
X605905Y1198621D03*
X609646Y1194881D03*
Y1202362D03*
X613386D03*
X620866D03*
Y1194881D03*
X613386Y1221062D03*
X609646D03*
Y1213582D03*
X613386D03*
X620866Y1206102D03*
X617126D03*
X620866Y1221062D03*
X617126D03*
X613386Y1206102D03*
X605905Y1217322D03*
Y1209842D03*
X609646Y1206102D03*
X613386Y1217322D03*
X605905Y1221062D03*
X609646Y1217322D03*
Y1209842D03*
X605905Y1206102D03*
Y1213582D03*
X620866Y1209842D03*
X613386D03*
X620866Y1217322D03*
X605905Y1224803D03*
Y1232283D03*
Y1236023D03*
X620866D03*
Y1232283D03*
X617126Y1224803D03*
X609646D03*
Y1228543D03*
X613386Y1232283D03*
Y1236023D03*
X620866Y1228543D03*
Y1224803D03*
X613386Y1228543D03*
Y1224803D03*
X617126Y1243503D03*
Y1239763D03*
X620866D03*
X609646Y1243503D03*
Y1239763D03*
X605905Y1247243D03*
X617126Y1250984D03*
X620866Y1243503D03*
Y1247243D03*
X609646Y1254724D03*
X613386Y1247243D03*
X617126Y1254724D03*
X613386Y1243503D03*
X609646Y1250984D03*
X605905Y1239763D03*
X617126Y1258465D03*
X609646D03*
X632085Y1071455D03*
X626476Y1092027D03*
X635827Y1090157D03*
X628346D03*
X632086D03*
X630216Y1099507D03*
X626476Y1106988D03*
X622736D03*
X626476Y1095767D03*
X630216Y1103247D03*
X635827Y1093897D03*
X632086Y1101377D03*
Y1105117D03*
X628346Y1093897D03*
X635827Y1097637D03*
X633957Y1110728D03*
X630216D03*
X626476D03*
X622736Y1114468D03*
X630216Y1118208D03*
X626476D03*
X633957Y1114468D03*
Y1118208D03*
Y1121948D03*
X635827Y1108858D03*
X632086D03*
X633957Y1140649D03*
Y1125688D03*
Y1129429D03*
Y1133169D03*
Y1136909D03*
X630216Y1140649D03*
X626476D03*
X622736D03*
Y1129429D03*
X630216Y1144389D03*
X626476D03*
X630216Y1148129D03*
Y1155610D03*
Y1151870D03*
Y1159350D03*
Y1166830D03*
Y1170570D03*
X633957D03*
Y1185531D03*
X628346Y1183661D03*
X630216Y1174310D03*
Y1178051D03*
Y1181791D03*
X632086Y1187401D03*
X628346D03*
X624606Y1183661D03*
X635827Y1187401D03*
X624606D03*
Y1191141D03*
X632086Y1202362D03*
X628346D03*
X632086Y1194881D03*
X628346D03*
X635827Y1191141D03*
Y1194881D03*
Y1198621D03*
Y1202362D03*
X628346Y1191141D03*
X624606Y1194881D03*
X632086Y1191141D03*
X628346Y1198621D03*
X624606Y1202362D03*
X632086Y1198621D03*
X624606Y1206102D03*
X628346Y1209842D03*
Y1217322D03*
Y1221062D03*
X632086D03*
Y1217322D03*
X635827Y1221062D03*
Y1206102D03*
Y1209842D03*
Y1213582D03*
Y1217322D03*
X628346Y1206102D03*
X632086D03*
X624606Y1217322D03*
X628346Y1213582D03*
X632086D03*
X624606Y1209842D03*
X632086Y1224803D03*
X624606D03*
X628346Y1236023D03*
Y1232283D03*
X635827Y1236023D03*
Y1232283D03*
X628346Y1224803D03*
Y1228543D03*
X635827D03*
Y1224803D03*
X632086Y1247243D03*
Y1239763D03*
X628346D03*
Y1250984D03*
X624606Y1243503D03*
Y1239763D03*
Y1254724D03*
Y1250984D03*
X632086Y1254724D03*
X635827Y1243503D03*
X632086Y1250984D03*
X635827Y1247243D03*
X628346Y1243503D03*
Y1247243D03*
X632087Y1258465D03*
X624606D03*
X631928Y1396583D03*
Y1408495D03*
X647046Y1071455D03*
X639566D03*
X643307Y1090157D03*
X639567D03*
X650787D03*
X647047D03*
X639567Y1101377D03*
Y1105117D03*
X647047D03*
Y1101377D03*
X650787Y1097637D03*
X643307D03*
Y1093897D03*
X650787D03*
X647047D03*
X637697Y1114468D03*
X648917Y1118208D03*
X645177D03*
X641437D03*
X637697D03*
X648917Y1121948D03*
X645177D03*
X641437D03*
X637697D03*
Y1110728D03*
X652657Y1118208D03*
Y1121948D03*
X650787Y1108858D03*
X647047D03*
X643307D03*
X639567D03*
X641437Y1133169D03*
X637697D03*
X645177Y1136909D03*
X637697D03*
X645177Y1140649D03*
X641437D03*
X652657Y1133169D03*
Y1129429D03*
Y1125688D03*
Y1136909D03*
X637697Y1140649D03*
X648917Y1125688D03*
X645177D03*
X641437D03*
X637697D03*
X645177Y1129429D03*
X641437D03*
X637697D03*
X645177Y1133169D03*
X637697Y1155610D03*
Y1151870D03*
X645177Y1144389D03*
X637697D03*
Y1148129D03*
X645177Y1151870D03*
X648917Y1155610D03*
Y1148129D03*
X652657Y1151869D03*
Y1144389D03*
X645177Y1170570D03*
X637697Y1166830D03*
X645177Y1159350D03*
X637697D03*
X648917Y1166830D03*
X652657Y1159350D03*
Y1170570D03*
X637697Y1189271D03*
X645177Y1185531D03*
X637697D03*
Y1178051D03*
Y1174310D03*
Y1181791D03*
X652657Y1189271D03*
X648917Y1181791D03*
Y1174310D03*
X652657Y1185531D03*
Y1178051D03*
Y1193011D03*
Y1204232D03*
X637697Y1193011D03*
X645177Y1196751D03*
Y1200491D03*
X641437D03*
Y1204232D03*
X645177D03*
X648917D03*
Y1196751D03*
Y1200491D03*
X641437Y1193011D03*
Y1196751D03*
X652657Y1200491D03*
Y1196751D03*
Y1211712D03*
X648917Y1219192D03*
X641437D03*
Y1211712D03*
X645177D03*
X648917D03*
Y1207972D03*
X645177D03*
X641437D03*
X652657D03*
X639567Y1221062D03*
X647047D03*
X643307D03*
X650787D03*
X639567Y1224803D03*
X643307Y1236023D03*
Y1232283D03*
X650787Y1236023D03*
X647047Y1224803D03*
X650787Y1232283D03*
X643307Y1224803D03*
Y1228543D03*
X650787D03*
Y1224803D03*
X639567Y1243503D03*
X647047D03*
X650787Y1239763D03*
X643307D03*
X639567Y1250984D03*
Y1254724D03*
X650787Y1247243D03*
Y1243503D03*
X647047Y1254724D03*
Y1250984D03*
X643307Y1247243D03*
Y1243503D03*
X647047Y1258465D03*
X639567D03*
X644168Y1384297D03*
Y1372385D03*
Y1396583D03*
Y1408495D03*
X669487Y1071455D03*
X662007D03*
X654526D03*
X669488Y1090157D03*
X665748D03*
X654527D03*
X658268D03*
X662008D03*
Y1101377D03*
X665748Y1093897D03*
X658268D03*
X654527Y1105117D03*
Y1101377D03*
X662008Y1105117D03*
X658268Y1097637D03*
X669488Y1101377D03*
Y1105117D03*
X665748Y1097637D03*
X656398Y1118208D03*
Y1121948D03*
X663878Y1118208D03*
X660138D03*
Y1121948D03*
X663878D03*
X667618Y1118208D03*
Y1121948D03*
X669488Y1108858D03*
X665748D03*
X662008D03*
X658268D03*
X654527D03*
X656398Y1140649D03*
X660138D03*
X663878D03*
X656398Y1125688D03*
X660138D03*
X663878D03*
Y1133169D03*
X660138D03*
X656398D03*
X667618D03*
Y1140649D03*
Y1125688D03*
Y1148129D03*
X660138D03*
X656398D03*
X663878D03*
X656398Y1155610D03*
X663878D03*
Y1166830D03*
X660138Y1159350D03*
X656398Y1166830D03*
X660138Y1170570D03*
X667618Y1159350D03*
Y1170570D03*
X663878Y1181791D03*
X660138D03*
X656398D03*
X663878Y1189271D03*
X660138D03*
X656398D03*
X667618Y1181791D03*
Y1189271D03*
X656398Y1174310D03*
X663878D03*
Y1196751D03*
X660138D03*
X656398D03*
Y1204232D03*
X660138D03*
X663878D03*
X667618Y1196751D03*
Y1204232D03*
X663878Y1207972D03*
X660138D03*
X656398D03*
X667618D03*
X654527Y1221062D03*
X658268D03*
X662008D03*
X665748D03*
X669488D03*
X654527Y1224803D03*
X658268Y1236023D03*
Y1232283D03*
X662008Y1224803D03*
X665748Y1236023D03*
Y1232283D03*
X669488Y1224803D03*
X665748D03*
X658268D03*
X665748Y1228543D03*
X658268D03*
X654527Y1239763D03*
Y1243503D03*
X665748Y1239763D03*
X669488Y1243503D03*
X662008D03*
X654527Y1254724D03*
Y1250984D03*
X662008Y1258465D03*
X669488D03*
X654528D03*
X668648Y1348187D03*
X656408D03*
X668648Y1360099D03*
X656408D03*
Y1384297D03*
Y1372385D03*
X668648D03*
Y1384297D03*
Y1396583D03*
X656408D03*
X668648Y1408495D03*
X656408D03*
X684448Y1071455D03*
X676967D03*
X680709Y1090157D03*
X676968D03*
X684449D03*
X673228D03*
X676968Y1105117D03*
X684449Y1101377D03*
Y1105117D03*
X680709Y1093897D03*
X676968Y1101377D03*
X680709Y1097637D03*
X673228D03*
Y1093897D03*
X682579Y1118208D03*
Y1121948D03*
X671358Y1118208D03*
X675098D03*
X678838D03*
X675098Y1121948D03*
X678838D03*
X671358D03*
X684449Y1108858D03*
X680709D03*
X676968D03*
X673228D03*
X682579Y1133169D03*
Y1140649D03*
Y1125688D03*
X671358Y1140649D03*
X675098D03*
X678838D03*
X675098Y1125688D03*
X671358D03*
X678838D03*
Y1133169D03*
X675098D03*
X671358D03*
X682579Y1148129D03*
X678838D03*
X675098D03*
X671358D03*
Y1155610D03*
X678838D03*
X682579Y1170570D03*
Y1159350D03*
X675098Y1170570D03*
X678839Y1166830D03*
X671358D03*
X675098Y1159350D03*
Y1181791D03*
X671358D03*
X678838Y1189271D03*
X675098D03*
X671358D03*
X682579Y1181791D03*
Y1189271D03*
X678838Y1181791D03*
X671358Y1174310D03*
X678838D03*
X682579Y1196751D03*
Y1204232D03*
X678838D03*
Y1196751D03*
X675098D03*
X671358D03*
Y1204232D03*
X675098D03*
X682579Y1207972D03*
X678838Y1219192D03*
Y1207972D03*
X675098D03*
X671358D03*
X673228Y1221062D03*
X676968D03*
X680709D03*
X684449D03*
X673228Y1236023D03*
Y1232283D03*
X676968Y1224803D03*
X680709Y1236023D03*
Y1232283D03*
X684449Y1224803D03*
X673228Y1228543D03*
X680709Y1224803D03*
X673228D03*
X680709Y1228543D03*
X673228Y1239763D03*
X680709D03*
X676968Y1243503D03*
X684449D03*
X684450Y1258465D03*
X676969D03*
X680888Y1348187D03*
Y1360099D03*
Y1372385D03*
Y1384297D03*
Y1396583D03*
Y1408495D03*
X695669Y1075196D03*
X699408Y1071455D03*
X691928Y1071454D03*
X688189Y1090157D03*
X691929Y1082677D03*
Y1086417D03*
X695669Y1090157D03*
X699409D03*
Y1086417D03*
X691929Y1090157D03*
X688189Y1097637D03*
X695669Y1093897D03*
X688189D03*
X699409Y1105117D03*
X691929Y1101377D03*
X699409D03*
X691929Y1105117D03*
X693799Y1121948D03*
X697539D03*
X701279D03*
X686319D03*
Y1118208D03*
Y1114468D03*
X699409Y1108858D03*
X695669D03*
X691929D03*
X688189D03*
X693799Y1133464D03*
X697539Y1133169D03*
X686417Y1132677D03*
X693799Y1140649D03*
X697539D03*
X693799Y1125688D03*
X697539D03*
X701279D03*
Y1140649D03*
Y1133169D03*
X686319Y1140649D03*
Y1125688D03*
X697539Y1148129D03*
X701279D03*
X693799D03*
X697539Y1155610D03*
X686319Y1148129D03*
Y1155610D03*
X697539Y1166830D03*
X693799Y1170570D03*
Y1159350D03*
X701279D03*
Y1170570D03*
X686319Y1166830D03*
X693799Y1181791D03*
Y1189271D03*
X697539D03*
X701279D03*
Y1181791D03*
X697539D03*
Y1174310D03*
X686319Y1181791D03*
Y1189271D03*
Y1174310D03*
X697539Y1204232D03*
X693799D03*
Y1196751D03*
X697539D03*
X701279D03*
Y1204232D03*
X686319Y1196751D03*
Y1204232D03*
X693799Y1207972D03*
X697539D03*
Y1211712D03*
X701279Y1207972D03*
Y1211712D03*
X686319Y1207972D03*
X695669Y1221062D03*
X699409D03*
X691929D03*
X688189D03*
Y1236023D03*
Y1232283D03*
X691929Y1224803D03*
Y1228543D03*
X699409Y1224803D03*
Y1228543D03*
X695669Y1236023D03*
Y1232283D03*
X688189Y1224803D03*
Y1239763D03*
X695669D03*
X699409Y1258465D03*
X691929D03*
X693128Y1348187D03*
Y1360099D03*
Y1372385D03*
Y1384297D03*
Y1396583D03*
Y1408495D03*
X703149Y1075196D03*
X718110D03*
X710630D03*
X714369Y1071455D03*
X706889D03*
X710630Y1078936D03*
X706890Y1086417D03*
Y1090157D03*
X718110Y1078936D03*
X714370Y1086417D03*
Y1090157D03*
X710630D03*
X718110D03*
X703149Y1078936D03*
Y1090157D03*
X706890Y1105117D03*
X714370D03*
X710630Y1097637D03*
Y1093897D03*
X718110Y1097637D03*
Y1093897D03*
X703149D03*
Y1097637D03*
X714369D03*
X706889Y1093897D03*
X714369D03*
X706889Y1097637D03*
X716240Y1121948D03*
X705020D03*
X708760D03*
X712500D03*
X718110Y1108858D03*
X714370D03*
X710630D03*
X706890D03*
X703149D03*
X716240Y1140649D03*
Y1125688D03*
Y1133169D03*
X712500Y1125688D03*
X708760D03*
X705020D03*
X712500Y1140649D03*
X708760D03*
X705020D03*
X712500Y1133169D03*
X708760D03*
X705020D03*
X716240Y1148129D03*
X712500D03*
X708760D03*
X705020D03*
X712500Y1155610D03*
X705020D03*
X716240Y1170570D03*
Y1159350D03*
X708760D03*
X705020Y1166830D03*
X712500D03*
X708760Y1170570D03*
X716240Y1189271D03*
Y1181791D03*
X712500Y1189271D03*
X708760D03*
X705020D03*
X712500Y1181791D03*
X708760D03*
X705020D03*
Y1174310D03*
X712500D03*
X716240Y1196751D03*
Y1204232D03*
X712500Y1196751D03*
X708760D03*
X705020D03*
X708760Y1204232D03*
X712500D03*
X705020D03*
X716240Y1211712D03*
Y1207972D03*
X712500D03*
Y1211712D03*
X708760Y1207972D03*
X705020D03*
X703149Y1221062D03*
X706890D03*
X710630D03*
X714370D03*
X718110D03*
X703149Y1236023D03*
Y1232283D03*
X710630Y1236023D03*
X718110D03*
Y1232283D03*
X710630D03*
X714370Y1224803D03*
Y1228543D03*
X706890Y1224803D03*
Y1228543D03*
X703149Y1239763D03*
X714370D03*
X718110Y1243503D03*
Y1247243D03*
X714370Y1258465D03*
X706890D03*
X705368Y1348187D03*
X717608D03*
X705368Y1360099D03*
X717608D03*
X705368Y1372385D03*
Y1384297D03*
X717608Y1372385D03*
Y1384297D03*
Y1396583D03*
X705368D03*
X717608Y1408495D03*
X705368D03*
X725590Y1075196D03*
X733071D03*
X729330Y1071455D03*
X721849D03*
X729331Y1086417D03*
Y1082677D03*
X733071Y1090157D03*
X729331D03*
X725590D03*
X721850D03*
X725590Y1078936D03*
X721850Y1086417D03*
X725590Y1097637D03*
X721850Y1105117D03*
X725590Y1093897D03*
X729331Y1105117D03*
X733071Y1093897D03*
X734941Y1118208D03*
X727460Y1121948D03*
X719980D03*
X723720D03*
X727460Y1118208D03*
X731201D03*
X733071Y1108858D03*
X729331D03*
X725590D03*
X721850D03*
X734941Y1140649D03*
Y1136909D03*
X727460Y1140649D03*
X723720Y1125688D03*
X719980D03*
X727460Y1129429D03*
Y1125688D03*
X723720Y1140649D03*
X719980D03*
X727460Y1133169D03*
X723720D03*
X719980D03*
X727460Y1136909D03*
X731201Y1125688D03*
X727460Y1151869D03*
Y1148129D03*
Y1144389D03*
X723720Y1148129D03*
X719980D03*
X731201D03*
Y1151869D03*
Y1155610D03*
X734941Y1151870D03*
Y1148129D03*
Y1144389D03*
X719980Y1155610D03*
X727460D03*
X731201Y1170570D03*
X719980Y1166830D03*
X731201Y1159350D03*
Y1166830D03*
X727460Y1185531D03*
X734941Y1181791D03*
Y1185531D03*
Y1189271D03*
Y1178051D03*
X727460Y1189271D03*
X723720Y1181791D03*
X719980D03*
Y1174310D03*
X727460Y1178051D03*
X723720Y1189271D03*
X719980D03*
X731201Y1174310D03*
Y1181791D03*
X727460Y1174310D03*
X719980Y1204232D03*
X727460D03*
X727480Y1196732D03*
X731201Y1196751D03*
X734941Y1193011D03*
X727460D03*
X723720Y1196751D03*
X719980D03*
X727460Y1200491D03*
X723720Y1204232D03*
X734941Y1211712D03*
X727460Y1207972D03*
X723720Y1211712D03*
Y1207972D03*
X719980Y1211712D03*
Y1207972D03*
X727460Y1211712D03*
X731201Y1207972D03*
X733071Y1221062D03*
X721850D03*
X725590D03*
X729331D03*
Y1224803D03*
Y1228543D03*
X733071Y1236023D03*
Y1232283D03*
X725590Y1236023D03*
Y1232283D03*
X721850Y1224803D03*
Y1228543D03*
X725590Y1239763D03*
X733071Y1247243D03*
X725590Y1243503D03*
X733071D03*
X725590Y1247243D03*
X729331Y1258465D03*
X721850D03*
X729848Y1348187D03*
Y1360099D03*
Y1372385D03*
Y1384297D03*
Y1396489D03*
Y1408401D03*
X740551Y1075196D03*
X748031D03*
X744290Y1071455D03*
X736810D03*
X748030Y1090157D03*
X744291D03*
X740551Y1078936D03*
Y1090157D03*
X736811D03*
X744291Y1101377D03*
X748031Y1093897D03*
X744291Y1105117D03*
X736811D03*
X748031Y1123818D03*
Y1120078D03*
Y1116338D03*
Y1112598D03*
Y1108858D03*
X744291D03*
X740551D03*
X736811D03*
X738681Y1136909D03*
Y1140649D03*
X748031Y1138779D03*
Y1135039D03*
Y1131299D03*
Y1127558D03*
X738681Y1155610D03*
Y1148129D03*
X749901Y1144389D03*
Y1151869D03*
X746161Y1155610D03*
Y1151869D03*
X742421D03*
X738681D03*
Y1166830D03*
X746161Y1170570D03*
Y1166830D03*
X738681Y1159350D03*
X749901Y1166830D03*
Y1159350D03*
X738681Y1170570D03*
X746161Y1159350D03*
X749901Y1181791D03*
Y1174310D03*
X738681D03*
Y1178051D03*
X742421Y1181791D03*
X738681Y1185531D03*
Y1189271D03*
X746161Y1185531D03*
Y1178051D03*
Y1174310D03*
X742421Y1185531D03*
X748031Y1191141D03*
X738681Y1204232D03*
Y1193011D03*
Y1196751D03*
X742421Y1193011D03*
X748031Y1202362D03*
Y1198621D03*
X736811Y1221062D03*
X740551D03*
X748031D03*
X744291D03*
X748031Y1217322D03*
Y1213582D03*
Y1209842D03*
Y1206102D03*
X736811Y1224803D03*
Y1228543D03*
X748031Y1236023D03*
Y1232283D03*
X740551Y1236023D03*
X744291Y1228543D03*
X740551Y1232283D03*
X744291Y1224803D03*
X748031Y1239763D03*
X740551D03*
Y1243503D03*
Y1247243D03*
X744291Y1258465D03*
X736811D03*
X742088Y1348187D03*
Y1360099D03*
Y1384297D03*
Y1372385D03*
Y1396489D03*
Y1408401D03*
X755512Y1075196D03*
X762993D03*
X766732Y1071455D03*
X759252D03*
X751771D03*
X755511Y1090157D03*
X762993Y1078936D03*
X755513D03*
X751772Y1105117D03*
X762992Y1093897D03*
X759252Y1105117D03*
X766732D03*
X755512Y1093897D03*
X762991Y1108857D03*
X755512Y1108858D03*
X751772D03*
X759252Y1116338D03*
Y1123818D03*
X751771Y1112598D03*
Y1120078D03*
X757382Y1140649D03*
X759252Y1131299D03*
X757382Y1148129D03*
X764862Y1170570D03*
X757382Y1166830D03*
Y1159350D03*
Y1174310D03*
Y1181791D03*
X764862Y1185531D03*
Y1178051D03*
X755512Y1187401D03*
X764862Y1189271D03*
X766732Y1194881D03*
X751772D03*
X755512Y1202362D03*
X766732D03*
Y1198621D03*
X762992D03*
X766732Y1221062D03*
Y1217322D03*
X762992Y1221062D03*
X759252D03*
X762992Y1213582D03*
X766732D03*
Y1209842D03*
X755512D03*
X766732Y1206102D03*
X751772Y1221062D03*
Y1217322D03*
X759252Y1224803D03*
Y1228543D03*
X755512Y1232283D03*
Y1236023D03*
X766732Y1224803D03*
Y1228543D03*
X762992Y1232283D03*
Y1236023D03*
X751772Y1224803D03*
Y1228543D03*
X755512Y1239763D03*
X766732D03*
Y1258465D03*
X759252D03*
X751772D03*
X766568Y1348187D03*
X754328D03*
X766568Y1360099D03*
X754328D03*
Y1372385D03*
Y1384297D03*
X766568Y1372385D03*
Y1384297D03*
X777953Y1075196D03*
X770473D03*
X774212Y1071455D03*
X777953Y1078936D03*
X781693D03*
X770473D03*
X770471Y1090157D03*
X770472Y1093897D03*
Y1108858D03*
X776083Y1140649D03*
Y1148129D03*
Y1155610D03*
Y1170570D03*
X768602Y1166830D03*
X779823Y1170570D03*
X776083Y1178051D03*
Y1185531D03*
X779823D03*
Y1178051D03*
X768602Y1181791D03*
Y1174310D03*
X772342Y1189271D03*
X783503Y1193011D03*
X776083D03*
X779823D03*
X781693Y1202362D03*
X777953D03*
X770472Y1221062D03*
X777953Y1209842D03*
X774212Y1224803D03*
Y1228543D03*
X770472Y1236023D03*
Y1232283D03*
X777953D03*
X781693Y1250984D03*
X777953Y1239763D03*
X781693D03*
X774212Y1258465D03*
X778808Y1348187D03*
Y1360099D03*
X785434Y1090158D03*
Y1082677D03*
Y1101378D03*
Y1123819D03*
Y1116339D03*
Y1108859D03*
Y1131300D03*
Y1198621D03*
Y1221062D03*
Y1213582D03*
Y1206102D03*
Y1228543D03*
Y1247243D03*
Y1239762D03*
X892183Y1728286D03*
Y1738286D03*
X891761Y1775438D03*
Y1785438D03*
X1057381Y1103247D03*
Y1140649D03*
Y1133169D03*
Y1125688D03*
Y1151870D03*
Y1144389D03*
X1054881Y1170570D03*
X1057381Y1159350D03*
X1054881Y1178050D03*
X1059251Y1187401D03*
Y1183661D03*
Y1194881D03*
Y1202362D03*
X1055510Y1198622D03*
Y1191142D03*
X1059251Y1209842D03*
Y1217322D03*
X1055510Y1221063D03*
Y1213583D03*
Y1206103D03*
X1059251Y1232283D03*
Y1236023D03*
Y1224803D03*
Y1239763D03*
X1052473Y1348187D03*
Y1360099D03*
Y1384297D03*
Y1372385D03*
X1064861Y1077066D03*
X1061121Y1080806D03*
X1072342Y1106988D03*
X1061121Y1103247D03*
X1072342Y1121948D03*
Y1118208D03*
X1064862Y1121948D03*
X1068602D03*
X1072342Y1140649D03*
Y1125688D03*
X1061121D03*
Y1140649D03*
X1064862D03*
X1068602D03*
X1064862Y1136909D03*
X1061121Y1133169D03*
X1064862Y1129429D03*
X1068602D03*
X1072342Y1155610D03*
X1064862D03*
X1068602D03*
X1061121Y1151870D03*
X1064862D03*
Y1148129D03*
X1061121Y1144389D03*
X1064862D03*
X1072342Y1166830D03*
X1064861Y1170570D03*
X1068602D03*
X1064861Y1166830D03*
X1061121Y1159350D03*
X1064862D03*
X1072342Y1181791D03*
Y1174310D03*
X1061120Y1181791D03*
X1064861D03*
X1068602D03*
Y1174310D03*
X1064861Y1178051D03*
X1061120Y1174310D03*
X1064861D03*
X1074212Y1187401D03*
X1062991D03*
Y1183661D03*
X1066732D03*
X1070472D03*
X1074212D03*
Y1191141D03*
Y1198621D03*
X1070472Y1191141D03*
X1066732D03*
X1070472Y1198621D03*
X1066732D03*
X1062991Y1194881D03*
Y1202362D03*
X1074212Y1206102D03*
X1066732D03*
X1070472D03*
Y1213582D03*
X1066732D03*
X1062991Y1209842D03*
Y1217322D03*
X1074212Y1221062D03*
X1066732D03*
X1070472D03*
Y1236023D03*
Y1232283D03*
X1066732Y1228543D03*
Y1224803D03*
X1074212D03*
X1062991Y1236023D03*
Y1232283D03*
Y1224803D03*
X1070472Y1228543D03*
Y1224803D03*
X1066732Y1239763D03*
Y1243503D03*
X1074212Y1239763D03*
Y1243503D03*
X1062991Y1239763D03*
X1074212Y1258465D03*
X1066732D03*
X1072593Y1348187D03*
X1064713D03*
X1060353D03*
X1072593Y1360099D03*
X1064713D03*
X1060353D03*
X1072593Y1384297D03*
Y1372385D03*
X1064713D03*
Y1384297D03*
X1060353D03*
Y1372385D03*
X1072593Y1396583D03*
X1064713D03*
X1072593Y1408495D03*
X1064713D03*
X1089171Y1071455D03*
X1083562Y1092027D03*
X1089172Y1090157D03*
X1083562Y1095767D03*
X1087302Y1106988D03*
X1079822D03*
X1083562D03*
X1076082D03*
X1089172Y1101377D03*
Y1105117D03*
X1083562Y1118208D03*
X1087302D03*
X1079822Y1114468D03*
X1083562Y1110728D03*
X1087302D03*
X1091043D03*
Y1121948D03*
Y1118208D03*
Y1114468D03*
X1076082D03*
X1089172Y1108858D03*
X1091043Y1125688D03*
Y1140649D03*
X1079822Y1129429D03*
Y1140649D03*
X1083562D03*
X1087302D03*
X1091043Y1136909D03*
Y1133169D03*
Y1129429D03*
X1076082Y1140649D03*
X1087302Y1151870D03*
Y1155610D03*
Y1148129D03*
X1083562Y1144389D03*
X1087302D03*
X1076082Y1155610D03*
Y1151870D03*
Y1148129D03*
Y1144389D03*
X1087302Y1170570D03*
Y1166830D03*
Y1159350D03*
X1091043Y1170570D03*
X1076082Y1159350D03*
X1081692Y1179921D03*
X1083562Y1181791D03*
X1087302D03*
Y1178051D03*
Y1174310D03*
X1076082Y1181791D03*
Y1178051D03*
Y1174310D03*
X1077952Y1183661D03*
X1081692D03*
X1085432D03*
X1089172Y1187401D03*
X1085432D03*
X1091043Y1185531D03*
X1077952Y1187401D03*
X1081692D03*
X1077952Y1191141D03*
Y1198621D03*
X1081692Y1191141D03*
X1085432Y1194881D03*
X1089172D03*
X1085432Y1202362D03*
X1089172D03*
X1077952Y1194881D03*
Y1202362D03*
X1089172Y1191141D03*
Y1198621D03*
X1081692Y1202362D03*
X1085432Y1198621D03*
X1081692Y1194881D03*
X1085432Y1191141D03*
X1077952Y1206102D03*
X1081692D03*
X1085432Y1209842D03*
X1077952Y1221062D03*
X1089172Y1217322D03*
Y1221062D03*
X1085432D03*
Y1217322D03*
X1089172Y1206102D03*
X1077952Y1209842D03*
X1081692D03*
Y1217322D03*
X1089172Y1213582D03*
X1077952Y1217322D03*
X1085432Y1206102D03*
Y1213582D03*
X1077952Y1232283D03*
Y1236023D03*
X1085432Y1232283D03*
Y1236023D03*
X1081692Y1224803D03*
X1089172D03*
X1077952D03*
Y1228543D03*
X1085432Y1224803D03*
Y1228543D03*
X1077952Y1239763D03*
X1081692D03*
Y1243503D03*
X1085432Y1250984D03*
Y1239763D03*
X1089172D03*
Y1247243D03*
X1089173Y1258465D03*
X1081692D03*
X1089193Y1348187D03*
X1084833D03*
X1076953D03*
X1089193Y1360099D03*
X1084833D03*
X1076953D03*
X1089193Y1384297D03*
Y1372385D03*
X1084833Y1384297D03*
Y1372385D03*
X1076953Y1384297D03*
Y1372385D03*
X1089193Y1396583D03*
X1084833D03*
X1076953D03*
X1089193Y1408495D03*
X1084833D03*
X1076953D03*
X1104132Y1071455D03*
X1096652D03*
X1092913Y1090157D03*
X1104133D03*
X1107873D03*
X1100393D03*
X1096653D03*
X1104133Y1093897D03*
X1092913D03*
Y1097637D03*
X1107873Y1093897D03*
Y1097637D03*
X1104133Y1101377D03*
X1100393Y1097637D03*
Y1093897D03*
X1096653Y1101377D03*
X1104133Y1105117D03*
X1096653D03*
X1094783Y1110728D03*
Y1121948D03*
X1098523D03*
X1102263D03*
X1106003D03*
X1094783Y1118208D03*
X1098523D03*
X1102263D03*
X1106003D03*
X1094783Y1114468D03*
X1107873Y1108858D03*
X1104133D03*
X1100393D03*
X1096653D03*
X1092913D03*
X1098523Y1140649D03*
X1102263D03*
X1094783Y1136909D03*
X1102263D03*
X1094783Y1133169D03*
X1098523D03*
X1102263D03*
X1094783Y1129429D03*
X1098523D03*
X1102263D03*
X1094783Y1125688D03*
X1098523D03*
X1102263D03*
X1106003D03*
X1094783Y1140649D03*
Y1151870D03*
Y1155610D03*
X1102263Y1151870D03*
X1094783Y1148129D03*
Y1144389D03*
X1102263D03*
X1106003Y1148129D03*
Y1155610D03*
X1102263Y1170570D03*
X1094783Y1159350D03*
X1102263D03*
X1094783Y1166830D03*
X1106003D03*
X1094783Y1181791D03*
X1102263Y1185531D03*
X1094783Y1174310D03*
Y1178051D03*
X1106003Y1181791D03*
Y1174310D03*
X1092913Y1187401D03*
X1098523Y1196751D03*
Y1193011D03*
X1106003Y1200491D03*
Y1196751D03*
Y1204232D03*
X1102263D03*
X1098523D03*
Y1200491D03*
X1102263D03*
Y1196751D03*
X1092913Y1191141D03*
Y1194881D03*
Y1198621D03*
Y1202362D03*
X1098523Y1207972D03*
X1102263D03*
X1106003D03*
Y1211712D03*
X1102263D03*
X1098523D03*
Y1219192D03*
X1106003D03*
X1092913Y1206102D03*
Y1209842D03*
Y1213582D03*
Y1217322D03*
X1107873Y1221062D03*
X1104133D03*
X1100393D03*
X1096653D03*
X1092913D03*
Y1232283D03*
Y1236023D03*
X1107873Y1232283D03*
X1104133Y1224803D03*
X1107873Y1236023D03*
X1100393Y1232283D03*
Y1236023D03*
X1096653Y1224803D03*
X1100393Y1228543D03*
X1092913Y1224803D03*
X1107873D03*
X1100393D03*
X1107873Y1228543D03*
X1092913D03*
X1100393Y1239763D03*
X1107873D03*
X1104133Y1243503D03*
X1096653D03*
X1104133Y1258465D03*
X1096653D03*
X1101433Y1348187D03*
X1097073D03*
X1101433Y1360099D03*
X1097073D03*
X1101433Y1384297D03*
Y1372385D03*
X1097073D03*
Y1384297D03*
X1101433Y1396583D03*
X1097073D03*
X1101433Y1408495D03*
X1097073D03*
X1119093Y1071455D03*
X1111612D03*
X1115354Y1090157D03*
X1119094D03*
X1122834D03*
X1111613D03*
X1122834Y1093897D03*
X1115354D03*
X1122834Y1097637D03*
X1115354D03*
X1119094Y1101377D03*
X1111613D03*
X1119094Y1105117D03*
X1111613D03*
X1117224Y1121948D03*
Y1118208D03*
X1120964D03*
X1109743Y1121948D03*
X1113484D03*
X1109743Y1118208D03*
X1113484D03*
X1124704Y1121948D03*
Y1118208D03*
X1120964Y1121948D03*
X1122834Y1108858D03*
X1119094D03*
X1115354D03*
X1111613D03*
X1109743Y1136909D03*
X1124704Y1125688D03*
Y1140649D03*
Y1133169D03*
X1113484D03*
X1117224D03*
X1120964D03*
X1109743Y1125688D03*
X1120964D03*
X1117224D03*
X1113484D03*
X1120964Y1140649D03*
X1117224D03*
X1113484D03*
X1109743Y1129429D03*
Y1133169D03*
X1113484Y1155610D03*
X1109743Y1144389D03*
X1120964Y1155610D03*
X1109743Y1151869D03*
X1120964Y1148129D03*
X1113484D03*
X1117224D03*
X1124704D03*
X1117224Y1170570D03*
X1109743D03*
X1113484Y1166830D03*
X1117224Y1159350D03*
X1120964Y1166830D03*
X1109743Y1159350D03*
X1124704Y1170570D03*
Y1159350D03*
X1109743Y1189271D03*
X1113484D03*
X1117224D03*
X1120964D03*
X1113484Y1181791D03*
X1117224D03*
X1120964D03*
X1124704Y1189271D03*
Y1181791D03*
X1109743Y1178051D03*
X1120964Y1174310D03*
X1109743Y1185531D03*
X1113484Y1174310D03*
X1124704Y1204232D03*
Y1196751D03*
X1120964Y1204232D03*
X1117224D03*
X1113484D03*
X1109743D03*
Y1193011D03*
Y1196751D03*
Y1200491D03*
X1113484Y1196751D03*
X1117224D03*
X1120964D03*
X1113484Y1207972D03*
X1117224D03*
X1120964D03*
X1109743Y1211712D03*
Y1207972D03*
X1124704D03*
X1122834Y1221062D03*
X1119094D03*
X1115354D03*
X1111613D03*
X1122834Y1224803D03*
Y1232283D03*
Y1236023D03*
X1119094Y1224803D03*
X1115354Y1232283D03*
Y1236023D03*
X1111613Y1224803D03*
X1115354Y1228543D03*
Y1224803D03*
X1122834Y1228543D03*
X1119094Y1243503D03*
X1122834Y1239763D03*
X1111613Y1243503D03*
Y1239763D03*
X1122834Y1243503D03*
X1119094Y1250984D03*
Y1254724D03*
X1122834Y1247243D03*
X1115354Y1243503D03*
Y1247243D03*
X1119094Y1258465D03*
X1111614D03*
X1113673Y1348187D03*
X1121553D03*
X1109313D03*
X1113673Y1360099D03*
X1121553D03*
X1109313D03*
X1113673Y1372385D03*
Y1384297D03*
X1121553Y1372385D03*
Y1384297D03*
X1109313D03*
Y1372385D03*
X1113673Y1396583D03*
X1121553D03*
X1109313D03*
X1113673Y1408495D03*
X1121553D03*
X1109313D03*
X1134053Y1071455D03*
X1126573D03*
X1126574Y1090157D03*
X1130314D03*
X1134054D03*
X1137795D03*
X1126574Y1101377D03*
X1130314Y1097637D03*
Y1093897D03*
X1137795D03*
Y1097637D03*
X1134054Y1101377D03*
X1126574Y1105117D03*
X1134054D03*
X1139665Y1121948D03*
X1130314Y1112598D03*
X1128444Y1118208D03*
X1132184D03*
X1135924D03*
X1132184Y1121948D03*
X1135924D03*
X1128444D03*
X1139665Y1118208D03*
X1137795Y1108858D03*
X1134054D03*
X1130314D03*
X1126574D03*
X1139665Y1125688D03*
X1128444Y1140649D03*
X1132184D03*
X1135924D03*
X1132184Y1125688D03*
X1128444D03*
X1135924D03*
Y1133169D03*
X1132184D03*
X1128444D03*
X1139665D03*
Y1140649D03*
X1135924Y1148129D03*
X1132184D03*
X1128444D03*
X1139665D03*
X1128444Y1155610D03*
X1135924D03*
X1139665Y1170570D03*
Y1159350D03*
X1132184Y1170570D03*
X1135925Y1166830D03*
X1128444D03*
X1132184Y1159350D03*
X1135924Y1181791D03*
X1132184D03*
X1128444D03*
X1135924Y1189271D03*
X1132184D03*
X1128444D03*
Y1174310D03*
X1135924D03*
X1139665Y1181791D03*
Y1189271D03*
Y1196751D03*
Y1204232D03*
X1135924D03*
Y1196751D03*
X1132184D03*
X1128444D03*
Y1204232D03*
X1132184D03*
X1139665Y1207972D03*
X1134054Y1217322D03*
X1135924Y1207972D03*
X1132184D03*
X1128444D03*
X1137795Y1221062D03*
X1134054D03*
X1130314D03*
X1126574D03*
Y1224803D03*
X1137795Y1232283D03*
Y1236023D03*
X1134054Y1224803D03*
X1130314Y1232283D03*
Y1236023D03*
X1137795Y1228543D03*
Y1224803D03*
X1130314Y1228543D03*
Y1224803D03*
X1126574Y1243503D03*
X1134054D03*
X1137795Y1239763D03*
X1130314D03*
X1126574Y1254724D03*
X1137795Y1243503D03*
X1130314Y1247243D03*
X1126574Y1250984D03*
X1137795Y1247243D03*
X1130314Y1243503D03*
X1134054Y1250984D03*
Y1254724D03*
X1134055Y1258465D03*
X1126574D03*
X1138153Y1348187D03*
X1133793D03*
X1125913D03*
X1138153Y1360099D03*
X1133793D03*
X1125913D03*
X1138153Y1384297D03*
Y1372385D03*
X1133793Y1384297D03*
Y1372385D03*
X1125913Y1384297D03*
Y1372385D03*
X1138153Y1396583D03*
X1133793D03*
X1125913D03*
X1138153Y1408495D03*
X1133793D03*
X1125913D03*
X1152755Y1075196D03*
X1156494Y1071455D03*
X1149014Y1071454D03*
X1141534Y1071455D03*
X1141535Y1090157D03*
X1149015Y1082677D03*
Y1086417D03*
X1152755Y1090157D03*
X1156495D03*
Y1086417D03*
X1149015Y1090157D03*
X1145275D03*
X1141535Y1101377D03*
X1149015D03*
X1152755Y1093897D03*
X1156495Y1101377D03*
X1145275Y1093897D03*
Y1097637D03*
X1141535Y1105117D03*
X1149015D03*
X1156495D03*
X1150885Y1121948D03*
X1143405D03*
Y1118208D03*
Y1114468D03*
X1154625Y1121948D03*
X1156495Y1108858D03*
X1152755D03*
X1149015D03*
X1145275D03*
X1141535D03*
X1154625Y1125688D03*
X1150885Y1133464D03*
X1154625Y1133169D03*
X1143503Y1132677D03*
X1143405Y1140649D03*
Y1125688D03*
X1150885Y1140649D03*
X1154625D03*
X1150885Y1125688D03*
X1143405Y1148129D03*
X1150885D03*
X1154625D03*
X1143405Y1155610D03*
X1154625D03*
Y1166830D03*
X1150885Y1170570D03*
X1143405Y1166830D03*
X1150885Y1159350D03*
X1143405Y1181791D03*
X1154625D03*
X1150885D03*
Y1189271D03*
X1154625D03*
X1143405D03*
Y1174310D03*
X1154625D03*
X1150885Y1196751D03*
X1154625Y1204232D03*
X1150885D03*
X1154625Y1196751D03*
X1143405D03*
Y1204232D03*
X1150885Y1207972D03*
X1154625D03*
Y1211712D03*
X1143405Y1207972D03*
X1149015Y1221062D03*
X1156495D03*
X1152755D03*
X1145275D03*
X1141535D03*
X1145275Y1224803D03*
X1141535D03*
X1152755Y1232283D03*
Y1236023D03*
X1156495Y1228543D03*
Y1224803D03*
X1149015Y1228543D03*
Y1224803D03*
X1145275Y1232283D03*
Y1236023D03*
X1141535Y1243503D03*
X1152755Y1239763D03*
X1145275D03*
X1141535Y1254724D03*
Y1250984D03*
X1145275Y1247243D03*
X1152755Y1243503D03*
X1145275D03*
X1152755Y1247243D03*
X1156495Y1258465D03*
X1149015D03*
X1141536D03*
X1150393Y1348187D03*
X1146033D03*
X1150393Y1360099D03*
X1146033D03*
X1150393Y1384297D03*
Y1372385D03*
X1146033D03*
Y1384297D03*
X1150393Y1396583D03*
X1146033D03*
X1150393Y1408495D03*
X1146033D03*
X1167716Y1075196D03*
X1160235D03*
X1171455Y1071455D03*
X1163975D03*
X1167716Y1078936D03*
X1163976Y1086417D03*
Y1090157D03*
X1171456Y1086417D03*
Y1090157D03*
X1167716D03*
X1160235Y1078936D03*
Y1090157D03*
X1167716Y1097637D03*
Y1093897D03*
X1160235D03*
Y1097637D03*
X1163976Y1105117D03*
X1171456D03*
X1171455Y1093897D03*
Y1097637D03*
X1163975Y1093897D03*
Y1097637D03*
X1169586Y1121948D03*
X1165846D03*
X1162106D03*
X1158365D03*
X1173326D03*
X1171456Y1108858D03*
X1167716D03*
X1163976D03*
X1160235D03*
X1162106Y1133169D03*
X1165846D03*
X1169586D03*
X1158365Y1140649D03*
X1162106D03*
X1165846D03*
X1169586D03*
X1158365Y1125688D03*
X1162106D03*
X1165846D03*
X1169586D03*
X1173326Y1133169D03*
Y1125688D03*
Y1140649D03*
X1158365Y1133169D03*
X1173326Y1148129D03*
X1158365D03*
X1162106D03*
X1165846D03*
X1169586D03*
X1162106Y1155610D03*
X1169586D03*
X1158365Y1170570D03*
X1165846D03*
X1169586Y1166830D03*
X1158365Y1159350D03*
X1162106Y1166830D03*
X1165846Y1159350D03*
X1173326D03*
Y1170570D03*
Y1189271D03*
X1158365Y1181791D03*
X1162106D03*
X1165846D03*
X1169586D03*
X1158365Y1189271D03*
X1162106D03*
X1165846D03*
X1169586D03*
X1173326Y1181791D03*
X1169586Y1174310D03*
X1162106D03*
Y1204232D03*
X1158365D03*
X1169586D03*
X1165846D03*
X1158365Y1196751D03*
X1162106D03*
X1165846D03*
X1169586D03*
X1173326Y1204232D03*
Y1196751D03*
X1158365Y1211712D03*
Y1207972D03*
X1173326D03*
Y1211712D03*
X1162106Y1207972D03*
X1165846D03*
X1169586Y1211712D03*
Y1207972D03*
X1171456Y1221062D03*
X1167716D03*
X1163976D03*
X1160235D03*
X1163976Y1228543D03*
Y1224803D03*
X1171456Y1228543D03*
Y1224803D03*
X1167716Y1232283D03*
Y1236023D03*
X1160235Y1232283D03*
Y1236023D03*
X1171456Y1239763D03*
X1160235D03*
X1167716Y1247243D03*
X1160235D03*
Y1243503D03*
X1167716D03*
X1171456Y1258465D03*
X1163976D03*
X1162633Y1348187D03*
X1170513D03*
X1158273D03*
X1162633Y1360099D03*
X1170513D03*
X1158273D03*
X1162633Y1372385D03*
Y1384297D03*
X1170513Y1372385D03*
Y1384297D03*
X1158273D03*
Y1372385D03*
X1162633Y1396583D03*
X1170513D03*
X1158273D03*
X1162633Y1408495D03*
X1170513D03*
X1158273D03*
X1175196Y1075196D03*
X1182676D03*
X1186416Y1071455D03*
X1178935D03*
X1175196Y1078936D03*
Y1090157D03*
X1178936D03*
X1182676Y1078936D03*
X1178936Y1086417D03*
X1182676Y1090157D03*
X1186417D03*
Y1086417D03*
Y1082677D03*
X1175196Y1097637D03*
Y1093897D03*
X1182676Y1097637D03*
Y1093897D03*
X1178936Y1105117D03*
X1186417D03*
X1188287Y1118208D03*
X1184546D03*
X1180806Y1121948D03*
X1177066D03*
X1184546D03*
X1186417Y1108858D03*
X1182676D03*
X1178936D03*
X1175196D03*
X1188287Y1125688D03*
X1184546Y1136909D03*
X1177066Y1133169D03*
X1180806D03*
X1184546D03*
X1177066Y1140649D03*
X1180806D03*
X1184546Y1125688D03*
Y1129429D03*
X1177066Y1125688D03*
X1180806D03*
X1184546Y1140649D03*
X1188287Y1155610D03*
Y1151869D03*
Y1148129D03*
X1177066D03*
X1180806D03*
X1184546Y1144389D03*
Y1148129D03*
Y1151869D03*
X1177066Y1155610D03*
X1184546D03*
X1177066Y1166830D03*
X1188287D03*
Y1159350D03*
Y1170570D03*
Y1181791D03*
Y1174310D03*
X1177066Y1189271D03*
X1180806D03*
X1184546Y1178051D03*
X1177066Y1174310D03*
X1184546Y1185531D03*
X1177066Y1181791D03*
X1180806D03*
X1184546Y1189271D03*
Y1174310D03*
Y1204232D03*
X1177066D03*
X1180806D03*
X1184546Y1200491D03*
X1177066Y1196751D03*
X1180806D03*
X1184546Y1193011D03*
X1188287Y1196751D03*
X1184566Y1196732D03*
X1188287Y1207972D03*
X1184546Y1211712D03*
X1177066Y1207972D03*
Y1211712D03*
X1180806Y1207972D03*
Y1211712D03*
X1184546Y1207972D03*
X1186417Y1221062D03*
X1182676D03*
X1178936D03*
X1175196D03*
Y1232283D03*
Y1236023D03*
X1178936Y1228543D03*
Y1224803D03*
X1182676Y1232283D03*
Y1236023D03*
X1186417Y1228543D03*
Y1224803D03*
X1182676Y1239763D03*
X1186417Y1258465D03*
X1178936D03*
X1182753Y1348187D03*
X1174873D03*
X1182753Y1360099D03*
X1174873D03*
X1182753Y1384297D03*
Y1372385D03*
X1174873Y1384297D03*
Y1372385D03*
X1182753Y1396583D03*
X1174873D03*
X1182753Y1408495D03*
X1174873D03*
X1179329Y1728990D03*
Y1738990D03*
X1179123Y1776014D03*
Y1786014D03*
X1190157Y1075196D03*
X1197637D03*
X1205117D03*
X1201376Y1071455D03*
X1193896D03*
X1190157Y1090157D03*
X1197637Y1078936D03*
Y1090157D03*
X1201377D03*
X1205116D03*
X1193897D03*
X1190157Y1093897D03*
X1201377Y1101377D03*
X1205117Y1093897D03*
X1201377Y1105117D03*
X1193897D03*
X1192027Y1118208D03*
X1205117Y1123818D03*
Y1120078D03*
Y1116338D03*
Y1108858D03*
X1201377D03*
X1197637D03*
X1193897D03*
X1190157D03*
X1192027Y1136909D03*
X1195767Y1140649D03*
X1192027D03*
X1195767Y1136909D03*
X1205117Y1135039D03*
Y1131299D03*
Y1127558D03*
X1195767Y1148129D03*
X1192027Y1144389D03*
X1195767Y1155610D03*
X1192027Y1148129D03*
X1195767Y1151869D03*
X1199507D03*
X1203247D03*
Y1155610D03*
X1192027Y1151870D03*
X1195767Y1170570D03*
Y1159350D03*
X1203247Y1166830D03*
Y1170570D03*
Y1159350D03*
X1195767Y1166830D03*
X1192027Y1181791D03*
X1199507Y1185531D03*
X1203247Y1174310D03*
Y1178051D03*
Y1185531D03*
X1192027Y1178051D03*
Y1189271D03*
X1195767D03*
X1192027Y1185531D03*
X1195767D03*
X1199507Y1181791D03*
X1195767Y1178051D03*
Y1174310D03*
Y1204232D03*
X1199507Y1193011D03*
X1195767Y1196751D03*
Y1193011D03*
X1192027D03*
X1205117Y1198621D03*
Y1202362D03*
X1192027Y1211712D03*
X1205117Y1206102D03*
Y1209842D03*
Y1213582D03*
Y1217322D03*
Y1221062D03*
X1201377D03*
X1197637D03*
X1193897D03*
X1190157D03*
Y1232283D03*
Y1236023D03*
X1197637Y1232283D03*
X1201377Y1228543D03*
X1197637Y1236023D03*
X1201377Y1224803D03*
X1205117Y1232283D03*
Y1236023D03*
X1193897Y1228543D03*
Y1224803D03*
X1197637Y1239763D03*
X1205117D03*
Y1243503D03*
Y1247243D03*
X1201377Y1258465D03*
X1193897D03*
X1212598Y1075196D03*
X1220079D03*
X1216338Y1071455D03*
X1208857D03*
X1220079Y1078936D03*
X1212599D03*
X1212597Y1090157D03*
X1212598Y1093897D03*
X1220078D03*
X1216338Y1105117D03*
X1208858D03*
X1212598Y1108858D03*
X1216338Y1116338D03*
Y1123818D03*
X1208857Y1112598D03*
Y1120078D03*
X1220077Y1108857D03*
X1208858Y1108858D03*
X1214468Y1140649D03*
X1206987Y1136909D03*
X1216338Y1131299D03*
X1206987Y1151869D03*
X1214468Y1148129D03*
X1206987Y1144389D03*
Y1159350D03*
X1214468D03*
X1206987Y1166830D03*
X1214468D03*
X1221948Y1170570D03*
X1206987Y1181791D03*
X1214468Y1189271D03*
X1221948Y1178051D03*
Y1185531D03*
X1206987Y1174310D03*
Y1189271D03*
X1214468Y1181791D03*
Y1174310D03*
X1208858Y1194881D03*
X1221948Y1193011D03*
X1212598Y1202362D03*
X1220078Y1198621D03*
Y1221062D03*
X1216338D03*
X1220078Y1213582D03*
X1212598Y1209842D03*
X1208858Y1221062D03*
Y1217322D03*
X1216338Y1224803D03*
Y1228543D03*
X1212598Y1232283D03*
Y1236023D03*
X1220078Y1232283D03*
Y1236023D03*
X1208858Y1224803D03*
Y1228543D03*
X1212598Y1239763D03*
Y1243503D03*
X1220078Y1247243D03*
Y1243503D03*
X1212598Y1247243D03*
X1208858Y1254724D03*
Y1250984D03*
X1216338Y1254724D03*
Y1250984D03*
Y1258465D03*
X1208858D03*
X1227559Y1075196D03*
X1235039D03*
X1231298Y1071455D03*
X1223818D03*
X1235039Y1078936D03*
X1227559D03*
X1227557Y1090157D03*
X1227558Y1093897D03*
X1223818Y1105117D03*
X1227558Y1108858D03*
X1233169Y1140649D03*
Y1155610D03*
Y1148129D03*
X1236909Y1170570D03*
X1225688Y1166830D03*
X1233169Y1170570D03*
X1236909Y1178051D03*
Y1185531D03*
X1233169D03*
Y1178051D03*
X1225688Y1174310D03*
Y1181791D03*
Y1189271D03*
X1233169Y1193011D03*
X1223818Y1194881D03*
X1236909Y1193011D03*
X1223818Y1202362D03*
Y1198621D03*
X1235039Y1202362D03*
X1223818Y1206102D03*
Y1221062D03*
Y1217322D03*
Y1213582D03*
Y1209842D03*
X1227558Y1221062D03*
X1235039Y1209842D03*
Y1206102D03*
X1223818Y1224803D03*
Y1228543D03*
X1231298Y1224803D03*
Y1228543D03*
X1227558Y1236023D03*
Y1232283D03*
X1235039D03*
X1225688Y1222932D03*
X1223818Y1239763D03*
X1227558Y1247243D03*
X1231298Y1254724D03*
X1223818D03*
Y1250984D03*
X1235039Y1239763D03*
X1227558Y1243503D03*
X1231298Y1250984D03*
Y1258465D03*
X1223818D03*
X1235966Y1348187D03*
X1228086D03*
X1235966Y1360099D03*
X1228086D03*
X1235966Y1372385D03*
Y1384297D03*
X1228086Y1372385D03*
Y1384297D03*
X1238779Y1078936D03*
X1242520Y1090158D03*
Y1082677D03*
Y1101378D03*
Y1123819D03*
Y1116339D03*
Y1108859D03*
Y1131300D03*
X1240589Y1193011D03*
X1238779Y1202362D03*
X1242520Y1198621D03*
Y1221062D03*
Y1213582D03*
Y1206102D03*
Y1228543D03*
X1238779Y1250984D03*
X1242520Y1247243D03*
Y1239762D03*
X1238779Y1239763D03*
X1252566Y1348187D03*
X1240326D03*
X1248206D03*
X1252566Y1360099D03*
X1240326D03*
X1248206D03*
X1252566Y1372385D03*
Y1384297D03*
X1240326D03*
Y1372385D03*
X1248206D03*
Y1384297D03*
X1252566Y1396583D03*
X1240326D03*
X1248206D03*
X1252566Y1408495D03*
X1240326D03*
X1248206D03*
X1264806Y1348187D03*
X1260446D03*
X1264806Y1360099D03*
X1260446D03*
X1264806Y1372385D03*
Y1384297D03*
X1260446Y1372385D03*
Y1384297D03*
X1264806Y1396583D03*
X1260446D03*
X1264806Y1408495D03*
X1260446D03*
X1284926Y1348187D03*
X1277046D03*
X1272686D03*
X1284926Y1360099D03*
X1277046D03*
X1272686D03*
X1284926Y1372385D03*
Y1384297D03*
X1277046Y1372385D03*
Y1384297D03*
X1272686D03*
Y1372385D03*
X1284926Y1396583D03*
X1277046D03*
X1272686D03*
X1284926Y1408495D03*
X1277046D03*
X1272686D03*
X1301526Y1348187D03*
X1289286D03*
X1297166D03*
X1301526Y1360099D03*
X1289286D03*
X1297166D03*
X1301526Y1372385D03*
Y1384297D03*
X1289286D03*
Y1372385D03*
X1297166Y1384297D03*
Y1372385D03*
X1301526Y1396583D03*
X1289286D03*
X1297166D03*
X1301526Y1408495D03*
X1289286D03*
X1297166D03*
X1313766Y1348187D03*
X1309406D03*
X1313766Y1360099D03*
X1309406D03*
X1313766Y1372385D03*
Y1384297D03*
X1309406Y1372385D03*
Y1384297D03*
X1313766Y1396583D03*
X1309406D03*
X1313766Y1408495D03*
X1309406D03*
X1333886Y1348187D03*
X1326006D03*
X1321646D03*
X1333886Y1360099D03*
X1326006D03*
X1321646D03*
X1333886Y1372385D03*
Y1384297D03*
X1326006Y1372385D03*
Y1384297D03*
X1321646D03*
Y1372385D03*
X1333886Y1396583D03*
X1326006D03*
X1321646D03*
X1333886Y1408495D03*
X1326006D03*
X1321646D03*
X1350486Y1348187D03*
X1338246D03*
X1346126D03*
X1350486Y1360099D03*
X1338246D03*
X1346126D03*
X1350486Y1372385D03*
Y1384297D03*
X1338246D03*
Y1372385D03*
X1346126Y1384297D03*
Y1372385D03*
X1350486Y1396583D03*
X1338246D03*
X1346126D03*
X1350486Y1408495D03*
X1338246D03*
X1346126D03*
X1358366Y1348187D03*
Y1360099D03*
Y1372385D03*
Y1384297D03*
Y1396583D03*
Y1408495D03*
X1459130Y1348187D03*
Y1360099D03*
Y1384297D03*
Y1372385D03*
X1479250Y1348187D03*
X1471370D03*
X1467010D03*
X1479250Y1360099D03*
X1471370D03*
X1467010D03*
X1479250Y1384297D03*
Y1372385D03*
X1471370D03*
Y1384297D03*
X1467010D03*
Y1372385D03*
X1479250Y1396583D03*
X1471370D03*
X1479250Y1408495D03*
X1471370D03*
X1495850Y1348187D03*
X1483610D03*
X1491490D03*
X1495850Y1360099D03*
X1483610D03*
X1491490D03*
X1483610Y1384297D03*
Y1372385D03*
X1491490Y1384297D03*
Y1372385D03*
X1495850Y1384297D03*
Y1372385D03*
Y1396583D03*
X1483610D03*
X1491490D03*
X1495850Y1408495D03*
X1483610D03*
X1491490D03*
X1514468Y1103247D03*
Y1125688D03*
Y1133169D03*
Y1140649D03*
Y1144389D03*
Y1151870D03*
Y1159350D03*
X1512597Y1198622D03*
Y1191142D03*
Y1221063D03*
Y1213583D03*
Y1206103D03*
X1508090Y1348187D03*
X1503730D03*
X1508090Y1360099D03*
X1503730D03*
X1508090Y1384297D03*
Y1372385D03*
X1503730D03*
Y1384297D03*
X1508090Y1396583D03*
X1503730D03*
X1508090Y1408495D03*
X1503730D03*
X1521948Y1077066D03*
X1518208Y1080806D03*
Y1103247D03*
X1529429Y1106988D03*
Y1118208D03*
Y1121948D03*
X1525689D03*
X1521949D03*
X1529429Y1125688D03*
X1518208D03*
X1525689Y1129429D03*
X1521949D03*
X1518208Y1133169D03*
X1521949Y1136909D03*
X1529429Y1140649D03*
X1525689D03*
X1521949D03*
X1518208D03*
X1521949Y1144389D03*
X1518208D03*
X1521949Y1148129D03*
Y1151870D03*
X1518208D03*
X1529429Y1155610D03*
X1525689D03*
X1521949D03*
Y1159350D03*
X1518208D03*
X1529429Y1166830D03*
X1521948D03*
X1525689Y1170570D03*
X1521948D03*
Y1174310D03*
X1518207D03*
X1521948Y1178051D03*
X1525689Y1174310D03*
X1529429D03*
X1527559Y1179921D03*
X1523819D03*
X1518207Y1181791D03*
X1516338Y1187401D03*
X1520078D03*
X1527559Y1183661D03*
X1523819D03*
X1520078D03*
X1516338D03*
X1523819Y1187401D03*
X1527559D03*
X1516338Y1194881D03*
Y1202362D03*
X1527559Y1191141D03*
X1523819D03*
X1527559Y1198621D03*
X1523819D03*
X1520078Y1194881D03*
Y1202362D03*
X1516338Y1198621D03*
X1523819Y1194881D03*
X1520078Y1198621D03*
X1523819Y1202362D03*
X1516338Y1191141D03*
X1527559Y1202362D03*
Y1194881D03*
X1520078Y1191141D03*
X1516338Y1209842D03*
Y1217322D03*
X1523819Y1206102D03*
X1527559D03*
Y1213582D03*
X1523819D03*
X1520078Y1209842D03*
Y1217322D03*
X1523819Y1221062D03*
X1527559D03*
X1520078D03*
X1516338Y1213582D03*
Y1206102D03*
X1520078D03*
X1527559Y1217322D03*
X1523819Y1209842D03*
X1516338Y1221062D03*
X1527559Y1209842D03*
X1523819Y1217322D03*
X1520078Y1213582D03*
X1527559Y1228543D03*
X1516338Y1232283D03*
Y1236023D03*
Y1224803D03*
X1527559Y1236023D03*
Y1232283D03*
X1523819Y1228543D03*
Y1224803D03*
X1520078Y1236023D03*
Y1232283D03*
Y1224803D03*
X1527559D03*
X1516338Y1239763D03*
X1523819D03*
Y1243503D03*
X1520078Y1239763D03*
Y1247243D03*
X1516338D03*
X1527559Y1243503D03*
Y1247243D03*
X1523819Y1250984D03*
Y1254724D03*
Y1258465D03*
X1528210Y1348187D03*
X1520330D03*
X1515970D03*
X1528210Y1360099D03*
X1520330D03*
X1515970D03*
X1528210Y1372385D03*
Y1384297D03*
X1520330Y1372385D03*
Y1384297D03*
X1515970D03*
Y1372385D03*
X1528210Y1396583D03*
X1520330D03*
X1515970D03*
X1528210Y1408495D03*
X1520330D03*
X1515970D03*
X1546258Y1071455D03*
X1540649Y1092027D03*
X1546259Y1090157D03*
X1544389Y1099507D03*
X1540649Y1106988D03*
X1536909D03*
X1533169D03*
X1544389D03*
X1540649Y1095767D03*
X1546259Y1101377D03*
Y1105117D03*
X1544389Y1118208D03*
X1540649D03*
X1544389Y1110728D03*
X1540649D03*
X1536909Y1114468D03*
X1533169D03*
X1544389Y1140649D03*
X1540649D03*
X1536909D03*
X1533169D03*
X1536909Y1129429D03*
X1544389Y1144389D03*
X1540649D03*
X1533169D03*
Y1148129D03*
Y1151870D03*
Y1155610D03*
X1544389Y1148129D03*
Y1155610D03*
Y1151870D03*
X1533169Y1159350D03*
X1544389D03*
Y1166830D03*
Y1170570D03*
X1535039Y1187401D03*
X1533169Y1174310D03*
Y1178051D03*
X1544389Y1174310D03*
Y1178051D03*
Y1181791D03*
X1540649D03*
X1538779Y1179921D03*
X1531299D03*
Y1187401D03*
X1546259D03*
X1542519D03*
Y1183661D03*
X1538779D03*
X1535039D03*
X1531299D03*
X1538779Y1187401D03*
X1542519Y1191141D03*
X1538779Y1202362D03*
X1535039Y1194881D03*
X1542519Y1198621D03*
X1535039Y1191141D03*
X1531299D03*
X1535039Y1198621D03*
X1531299D03*
X1538779Y1191141D03*
X1542519Y1194881D03*
X1546259D03*
X1542519Y1202362D03*
X1546259D03*
Y1198621D03*
Y1191141D03*
X1535039Y1202362D03*
X1538779Y1194881D03*
X1542519Y1213582D03*
Y1206102D03*
X1546259Y1213582D03*
X1535039Y1209842D03*
X1531299Y1206102D03*
X1535039D03*
X1538779D03*
X1542519Y1209842D03*
X1531299Y1221062D03*
X1535039D03*
X1546259Y1217322D03*
Y1221062D03*
X1542519D03*
Y1217322D03*
X1535039D03*
X1546259Y1206102D03*
X1538779Y1209842D03*
Y1217322D03*
X1535039Y1224803D03*
X1542519Y1228543D03*
X1535039D03*
X1531299Y1224803D03*
X1535039Y1232283D03*
Y1236023D03*
X1542519Y1232283D03*
Y1236023D03*
X1538779Y1224803D03*
X1546259D03*
X1542519D03*
X1535039Y1239763D03*
X1531299D03*
Y1243503D03*
X1538779Y1239763D03*
Y1243503D03*
X1542519Y1250984D03*
Y1239763D03*
X1546259D03*
Y1247243D03*
Y1250984D03*
X1542519Y1243503D03*
X1546259Y1254724D03*
X1542519Y1247243D03*
X1538779Y1250984D03*
Y1254724D03*
X1535039Y1243503D03*
X1531299Y1250984D03*
X1535039Y1247243D03*
X1531299Y1254724D03*
X1546260Y1258465D03*
X1538779D03*
X1531299D03*
X1544810Y1348187D03*
X1532570D03*
X1540450D03*
X1544810Y1360099D03*
X1532570D03*
X1540450D03*
X1544810Y1384297D03*
Y1372385D03*
X1532570Y1384297D03*
Y1372385D03*
X1540450Y1384297D03*
Y1372385D03*
X1544810Y1396583D03*
X1532570D03*
X1540450D03*
X1544810Y1408495D03*
X1532570D03*
X1540450D03*
X1561219Y1071455D03*
X1553739D03*
X1561220Y1090157D03*
X1557480D03*
X1553740D03*
X1550000D03*
X1561220Y1093897D03*
Y1105117D03*
X1553740D03*
X1561220Y1101377D03*
X1557480Y1097637D03*
Y1093897D03*
X1553740Y1101377D03*
X1550000Y1093897D03*
Y1097637D03*
X1551870Y1114468D03*
X1548130D03*
X1563090Y1118208D03*
X1559350D03*
X1555610D03*
X1551870D03*
X1548130D03*
X1563090Y1121948D03*
X1559350D03*
X1555610D03*
X1551870D03*
X1548130D03*
Y1110728D03*
X1561220Y1108858D03*
X1557480D03*
X1553740D03*
X1550000D03*
X1551870Y1110728D03*
X1548130Y1140649D03*
X1563090Y1125688D03*
X1559350D03*
X1555610D03*
X1551870D03*
X1548130D03*
X1559350Y1129429D03*
X1555610D03*
X1551870D03*
X1548130D03*
X1559350Y1133169D03*
X1555610D03*
X1551870D03*
X1548130D03*
X1559350Y1136909D03*
X1551870D03*
X1548130D03*
X1559350Y1140649D03*
X1555610D03*
X1551870D03*
Y1155610D03*
Y1151870D03*
X1559350Y1144389D03*
X1551870D03*
Y1148129D03*
X1559350Y1151870D03*
X1563090Y1155610D03*
Y1148129D03*
X1559350Y1170570D03*
X1551870Y1166830D03*
X1559350Y1159350D03*
X1551870D03*
X1548130Y1170570D03*
X1563090Y1166830D03*
X1551870Y1189271D03*
X1559350Y1185531D03*
X1551870D03*
Y1178051D03*
Y1174310D03*
Y1181791D03*
X1563090D03*
Y1174310D03*
X1550000Y1187401D03*
X1548130Y1185531D03*
X1551870Y1193011D03*
X1559350Y1196751D03*
Y1200491D03*
X1555610D03*
Y1204232D03*
X1559350D03*
X1563090D03*
Y1196751D03*
Y1200491D03*
X1555610Y1193011D03*
Y1196751D03*
X1550000Y1191141D03*
Y1194881D03*
Y1198621D03*
Y1202362D03*
X1555610Y1211712D03*
X1559350D03*
X1563090D03*
Y1207972D03*
X1559350D03*
X1555610D03*
X1563090Y1219192D03*
X1550000Y1221062D03*
X1553740D03*
X1557480D03*
X1561220D03*
X1550000Y1206102D03*
Y1209842D03*
Y1213582D03*
Y1217322D03*
X1553740D03*
X1550000Y1228543D03*
Y1224803D03*
X1557480Y1228543D03*
X1550000Y1232283D03*
Y1236023D03*
X1561220Y1224803D03*
X1557480Y1232283D03*
Y1236023D03*
X1553740Y1224803D03*
X1557480D03*
Y1239763D03*
X1561220Y1243503D03*
X1553740D03*
X1561220Y1250984D03*
Y1254724D03*
X1550000Y1243503D03*
X1557480Y1247243D03*
X1550000D03*
X1557480Y1243503D03*
X1553740Y1250984D03*
Y1254724D03*
X1561220Y1258465D03*
X1553740D03*
X1557050Y1348187D03*
X1552690D03*
Y1360099D03*
X1557050D03*
Y1384297D03*
Y1372385D03*
X1552690D03*
Y1384297D03*
X1557050Y1396583D03*
X1552690D03*
X1557050Y1408495D03*
X1552690D03*
X1576180Y1071455D03*
X1568699D03*
X1564960Y1090157D03*
X1572441D03*
X1576181D03*
X1568700D03*
X1576181Y1105117D03*
X1568700D03*
X1564960Y1093897D03*
Y1097637D03*
X1572441Y1093897D03*
Y1097637D03*
X1576181Y1101377D03*
X1568700D03*
X1566830Y1121948D03*
X1578051Y1118208D03*
X1574311D03*
Y1121948D03*
X1578051D03*
X1570571Y1118208D03*
X1566830D03*
X1570571Y1121948D03*
X1576181Y1108858D03*
X1572441D03*
X1568700D03*
X1564960D03*
X1566830Y1133169D03*
Y1129429D03*
X1570571Y1140649D03*
X1574311D03*
X1578051D03*
X1570571Y1125688D03*
X1574311D03*
X1578051D03*
X1566830D03*
X1578051Y1133169D03*
X1574311D03*
X1570571D03*
X1566830Y1136909D03*
X1574311Y1148129D03*
X1570571D03*
X1578051D03*
X1570571Y1155610D03*
X1566830Y1151869D03*
X1578051Y1155610D03*
X1566830Y1144389D03*
Y1159350D03*
X1578051Y1166830D03*
X1574311Y1159350D03*
X1570571Y1166830D03*
X1566830Y1170570D03*
X1574311D03*
X1578051Y1181791D03*
X1574311D03*
X1570571D03*
X1578051Y1189271D03*
X1574311D03*
X1570571D03*
X1566830D03*
Y1178051D03*
X1570571Y1174310D03*
X1566830Y1185531D03*
X1578051Y1174310D03*
X1574311Y1204232D03*
X1578051D03*
Y1196751D03*
X1574311D03*
X1570571D03*
X1566830Y1200491D03*
Y1196751D03*
Y1193011D03*
Y1204232D03*
X1570571D03*
X1566830Y1207972D03*
Y1211712D03*
X1578051Y1207972D03*
X1574311D03*
X1570571D03*
X1564960Y1221062D03*
X1568700D03*
X1572441D03*
X1576181D03*
X1572441Y1228543D03*
X1564960Y1224803D03*
Y1232283D03*
Y1236023D03*
X1576181Y1224803D03*
X1572441Y1232283D03*
Y1236023D03*
X1568700Y1224803D03*
X1572441D03*
X1564960Y1228543D03*
Y1239763D03*
X1576181Y1243503D03*
X1568700D03*
Y1239763D03*
Y1254724D03*
X1564960Y1243503D03*
Y1247243D03*
X1568700Y1250984D03*
X1576181Y1258465D03*
X1568701D03*
X1564930Y1348187D03*
X1569290D03*
X1577170D03*
X1569290Y1360099D03*
X1577170D03*
X1564930D03*
X1577170Y1372385D03*
Y1384297D03*
X1569290Y1372385D03*
Y1384297D03*
X1564930D03*
Y1372385D03*
X1577170Y1396583D03*
X1569290D03*
X1564930D03*
X1577170Y1408495D03*
X1569290D03*
X1564930D03*
X1591140Y1071455D03*
X1583660D03*
X1579921Y1090157D03*
X1583661D03*
X1587401D03*
X1591141D03*
X1594882D03*
X1583661Y1105117D03*
X1591141D03*
X1579921Y1093897D03*
Y1097637D03*
X1583661Y1101377D03*
X1587401Y1097637D03*
Y1093897D03*
X1594882D03*
Y1097637D03*
X1591141Y1101377D03*
X1581791Y1121948D03*
X1585531Y1118208D03*
X1589271D03*
X1593011D03*
X1589271Y1121948D03*
X1593011D03*
X1585531D03*
X1581791Y1118208D03*
X1594882Y1108858D03*
X1591141D03*
X1587401D03*
X1583661D03*
X1579921D03*
X1587401Y1112598D03*
X1581791Y1133169D03*
Y1140649D03*
X1585531D03*
X1589271D03*
X1593011D03*
X1589271Y1125688D03*
X1585531D03*
X1581791D03*
X1593011D03*
Y1133169D03*
X1589271D03*
X1585531D03*
X1593011Y1148129D03*
X1589271D03*
X1585531D03*
X1581791D03*
X1593011Y1155610D03*
X1585531D03*
X1589271Y1170570D03*
X1593012Y1166830D03*
X1585531D03*
X1581791Y1159350D03*
X1589271D03*
X1581791Y1170570D03*
X1593011Y1181791D03*
X1589271D03*
X1585531D03*
X1581791D03*
X1593011Y1189271D03*
X1589271D03*
X1585531D03*
X1581791D03*
X1585531Y1174310D03*
X1593011D03*
Y1204232D03*
Y1196751D03*
X1589271D03*
X1585531D03*
X1581791D03*
Y1204232D03*
X1585531D03*
X1589271D03*
X1593011Y1219192D03*
X1591141Y1217322D03*
X1593011Y1207972D03*
X1589271D03*
X1585531D03*
X1581791D03*
X1591141Y1221062D03*
X1587401D03*
X1579921D03*
X1583661D03*
X1594882D03*
Y1224803D03*
X1579921Y1228543D03*
X1594882D03*
X1583661Y1224803D03*
X1579921Y1232283D03*
Y1236023D03*
X1594882Y1232283D03*
Y1236023D03*
X1591141Y1224803D03*
X1587401Y1232283D03*
Y1236023D03*
X1579921Y1224803D03*
X1587401Y1228543D03*
Y1224803D03*
X1583661Y1243503D03*
X1579921Y1239763D03*
X1591141Y1243503D03*
X1594882Y1239763D03*
X1587401D03*
X1591142Y1258465D03*
X1583661D03*
X1589410Y1348187D03*
X1581530D03*
X1589410Y1360099D03*
X1581530D03*
Y1384297D03*
Y1372385D03*
X1589410Y1384297D03*
Y1372385D03*
X1581530Y1396583D03*
X1589410D03*
X1581530Y1408495D03*
X1589410D03*
X1609842Y1075196D03*
X1606101Y1071454D03*
X1598621Y1071455D03*
X1598622Y1090157D03*
X1606102Y1082677D03*
Y1086417D03*
X1609842Y1090157D03*
X1606102D03*
X1602362D03*
X1598622Y1105117D03*
X1606102D03*
X1598622Y1101377D03*
X1606102D03*
X1609842Y1093897D03*
X1602362D03*
Y1097637D03*
X1596752Y1121948D03*
X1600492Y1118208D03*
Y1114468D03*
X1611712Y1121948D03*
X1607972D03*
X1596752Y1118208D03*
X1600492Y1121948D03*
X1609842Y1108858D03*
X1606102D03*
X1602362D03*
X1598622D03*
X1607972Y1125688D03*
X1611712D03*
X1607972Y1133464D03*
X1611712Y1133169D03*
X1600590Y1132677D03*
X1596752Y1133169D03*
Y1140649D03*
X1600492D03*
Y1125688D03*
X1596752D03*
X1607972Y1140649D03*
X1611712D03*
X1600492Y1148129D03*
X1596752D03*
X1607972D03*
X1611712D03*
X1600492Y1155610D03*
X1611712D03*
X1596752Y1170570D03*
Y1159350D03*
X1611712Y1166830D03*
X1607972Y1170570D03*
X1600492Y1166830D03*
X1607972Y1159350D03*
X1600492Y1181791D03*
X1611712D03*
X1607972D03*
Y1189271D03*
X1611712D03*
X1596752Y1181791D03*
X1600492Y1189271D03*
X1596752D03*
X1600492Y1174310D03*
X1611712D03*
Y1204232D03*
X1607972D03*
Y1196751D03*
X1611712D03*
X1600492D03*
X1596752D03*
Y1204232D03*
X1600492D03*
X1606102Y1221062D03*
X1596752Y1207972D03*
X1607972D03*
X1611712D03*
Y1211712D03*
X1596752Y1219192D03*
X1600492Y1207972D03*
X1598622Y1221062D03*
X1609842D03*
X1602362D03*
Y1224803D03*
X1598622D03*
X1609842Y1232283D03*
Y1236023D03*
X1606102Y1228543D03*
Y1224803D03*
X1602362Y1232283D03*
Y1236023D03*
X1598622Y1243503D03*
X1609842Y1239763D03*
X1602362D03*
X1606102Y1258465D03*
X1598623D03*
X1609158Y1348187D03*
Y1360099D03*
Y1384297D03*
Y1372385D03*
X1624803Y1075196D03*
X1617322D03*
X1621062Y1071455D03*
X1613581D03*
X1617322Y1090157D03*
Y1078936D03*
X1613582Y1090157D03*
Y1086417D03*
X1624803Y1078936D03*
X1621063Y1086417D03*
Y1090157D03*
X1624803D03*
X1621062Y1093897D03*
X1617322D03*
Y1097637D03*
X1624803Y1093897D03*
Y1097637D03*
X1621063Y1105117D03*
X1613582D03*
Y1101377D03*
X1621062Y1097637D03*
X1626673Y1121948D03*
X1622933D03*
X1619193D03*
X1615452D03*
X1624803Y1108858D03*
X1621063D03*
X1617322D03*
X1613582D03*
X1615452Y1133169D03*
X1619193D03*
X1622933D03*
X1626673D03*
X1615452Y1140649D03*
X1619193D03*
X1622933D03*
X1626673D03*
X1615452Y1125688D03*
X1619193D03*
X1622933D03*
X1626673D03*
X1615452Y1148129D03*
X1619193D03*
X1622933D03*
X1626673D03*
X1619193Y1155610D03*
X1626673D03*
X1615452Y1170570D03*
X1622933D03*
X1626673Y1166830D03*
X1615452Y1159350D03*
X1619193Y1166830D03*
X1622933Y1159350D03*
X1615452Y1181791D03*
X1619193D03*
X1622933D03*
X1626673D03*
X1615452Y1189271D03*
X1619193D03*
X1622933D03*
X1626673D03*
Y1174310D03*
X1619193D03*
Y1204232D03*
X1615452D03*
X1626673D03*
X1622933D03*
X1615452Y1196751D03*
X1619193D03*
X1622933D03*
X1626673D03*
X1617322Y1221062D03*
X1619193Y1207972D03*
X1622933D03*
X1626673Y1211712D03*
Y1207972D03*
X1615452Y1211712D03*
Y1207972D03*
X1621063Y1221062D03*
X1613582D03*
X1624803D03*
X1613582Y1228543D03*
Y1224803D03*
X1621063Y1228543D03*
Y1224803D03*
X1624803Y1232283D03*
Y1236023D03*
X1617322Y1232283D03*
Y1236023D03*
Y1239763D03*
X1621063Y1258465D03*
X1613582D03*
X1617038Y1348187D03*
X1621398D03*
X1617038Y1360099D03*
X1621398D03*
X1617038Y1384297D03*
Y1372385D03*
X1621398D03*
Y1384297D03*
Y1396583D03*
Y1408495D03*
X1639763Y1075196D03*
X1632283D03*
X1643503Y1071455D03*
X1636022D03*
X1628542D03*
X1636023Y1090157D03*
X1643504Y1082677D03*
X1636023Y1086417D03*
X1643504Y1090157D03*
Y1086417D03*
X1639763Y1090157D03*
Y1078936D03*
X1632283D03*
X1628543Y1086417D03*
Y1090157D03*
X1632283D03*
X1628542Y1093897D03*
X1632283D03*
Y1097637D03*
X1639763Y1093897D03*
Y1097637D03*
X1628543Y1105117D03*
X1636023D03*
X1643504D03*
X1628542Y1097637D03*
X1641633Y1118208D03*
X1637893Y1121948D03*
X1634153D03*
X1630413D03*
X1641633D03*
X1643504Y1108858D03*
X1639763D03*
X1636023D03*
X1632283D03*
X1628543D03*
X1641633Y1136909D03*
X1630413Y1133169D03*
X1634153D03*
X1637893D03*
X1641633D03*
X1634153Y1140649D03*
X1637893D03*
X1641633Y1125688D03*
Y1129429D03*
X1630413Y1125688D03*
X1634153D03*
X1637893D03*
X1641633Y1140649D03*
X1630413D03*
Y1148129D03*
X1634153D03*
X1637893D03*
X1641633Y1144389D03*
Y1148129D03*
Y1151869D03*
X1634153Y1155610D03*
X1641633D03*
X1634153Y1166830D03*
X1630413Y1159350D03*
Y1170570D03*
X1634153Y1189271D03*
X1637893D03*
X1641633Y1178051D03*
X1634153Y1174310D03*
X1641633Y1185531D03*
X1630413Y1181791D03*
X1634153D03*
X1637893D03*
X1641633Y1189271D03*
X1630413D03*
X1641633Y1174310D03*
X1641653Y1196732D03*
X1641633Y1204232D03*
X1630413D03*
X1634153D03*
X1637893D03*
X1641633Y1200491D03*
X1630413Y1196751D03*
X1634153D03*
X1637893D03*
X1641633Y1193011D03*
Y1211712D03*
X1634153Y1207972D03*
X1630413D03*
X1634153Y1211712D03*
X1637893Y1207972D03*
Y1211712D03*
X1630413D03*
X1641633Y1207972D03*
X1628543Y1221062D03*
X1632283D03*
X1636023D03*
X1639763D03*
X1643504D03*
X1628543Y1228543D03*
Y1224803D03*
X1632283Y1232283D03*
Y1236023D03*
X1636023Y1228543D03*
Y1224803D03*
X1639763Y1232283D03*
Y1236023D03*
X1643504Y1228543D03*
Y1224803D03*
X1628543Y1239763D03*
X1639763D03*
X1632283Y1243503D03*
X1639763D03*
X1632283Y1247243D03*
X1639763D03*
X1643504Y1258465D03*
X1636023D03*
X1628543D03*
X1629278Y1348187D03*
X1641518D03*
X1633638D03*
X1629278Y1360099D03*
X1641518D03*
X1633638D03*
X1629278Y1384297D03*
Y1372385D03*
X1641518Y1384297D03*
Y1372385D03*
X1633638Y1384297D03*
Y1372385D03*
X1629278Y1396583D03*
X1641518D03*
X1633638D03*
Y1408495D03*
X1629278D03*
X1641518D03*
X1647244Y1075196D03*
X1654724D03*
X1658463Y1071455D03*
X1650983D03*
X1654724Y1078936D03*
Y1090157D03*
X1658464D03*
X1650984D03*
X1647244D03*
Y1093897D03*
X1658464Y1101377D03*
Y1105117D03*
X1650984D03*
X1645374Y1118208D03*
X1649114D03*
X1658464Y1108858D03*
X1654724D03*
X1650984D03*
X1647244D03*
X1649114Y1140649D03*
X1652854Y1136909D03*
X1645374Y1125688D03*
X1649114Y1136909D03*
X1652854Y1140649D03*
X1645374Y1155610D03*
Y1151869D03*
Y1148129D03*
X1652854D03*
X1649114Y1144389D03*
X1652854Y1155610D03*
X1649114Y1148129D03*
X1652854Y1151869D03*
X1656594D03*
X1660334D03*
Y1155610D03*
X1649114Y1151870D03*
X1645374Y1166830D03*
X1652854Y1159350D03*
X1660334Y1166830D03*
Y1170570D03*
X1645374Y1159350D03*
X1660334D03*
X1645374Y1170570D03*
X1652854D03*
Y1166830D03*
Y1185531D03*
X1656594Y1181791D03*
X1652854Y1178051D03*
Y1174310D03*
X1649114Y1181791D03*
X1656594Y1185531D03*
X1660334Y1174310D03*
Y1178051D03*
Y1185531D03*
X1645374Y1181791D03*
Y1174310D03*
X1649114Y1178051D03*
Y1189271D03*
X1652854D03*
X1649114Y1185531D03*
X1656594Y1193011D03*
X1652854Y1204232D03*
Y1196751D03*
Y1193011D03*
X1649114D03*
X1645374Y1196751D03*
X1649114Y1211712D03*
X1645374Y1207972D03*
X1660334Y1215452D03*
Y1211712D03*
X1654724Y1221062D03*
X1658464D03*
X1650984D03*
X1647244D03*
Y1232283D03*
Y1236023D03*
X1654724Y1232283D03*
X1658464Y1228543D03*
X1654724Y1236023D03*
X1658464Y1224803D03*
X1650984Y1228543D03*
Y1224803D03*
X1654724Y1239763D03*
Y1243503D03*
X1647244Y1247243D03*
X1654724D03*
X1647244Y1243503D03*
X1658464Y1258465D03*
X1650984D03*
X1645878Y1348187D03*
X1653758D03*
X1658118D03*
X1645878Y1360099D03*
X1653758D03*
X1658118D03*
X1645878Y1384297D03*
Y1372385D03*
X1653758D03*
Y1384297D03*
X1658118D03*
Y1372385D03*
X1645878Y1396583D03*
X1653758D03*
X1658118D03*
X1645878Y1408495D03*
X1653758D03*
X1658118D03*
X1662204Y1075196D03*
X1669685D03*
X1673425Y1071455D03*
X1665944D03*
X1662203Y1090157D03*
X1669686Y1078936D03*
X1669684Y1090157D03*
X1662204Y1093897D03*
X1669685D03*
X1673425Y1105117D03*
X1665945D03*
X1669685Y1108858D03*
X1673425Y1116338D03*
Y1123818D03*
X1665944Y1112598D03*
Y1120078D03*
X1665945Y1108858D03*
X1662204Y1123818D03*
Y1120078D03*
Y1116338D03*
Y1108858D03*
X1671555Y1140649D03*
X1673425Y1131299D03*
X1662204Y1135039D03*
Y1131299D03*
Y1127558D03*
Y1138779D03*
X1664074Y1151869D03*
X1671555Y1148129D03*
X1664074Y1144389D03*
Y1159350D03*
X1671555D03*
X1664074Y1166830D03*
X1671555D03*
X1664074Y1189271D03*
Y1174310D03*
X1671555Y1181791D03*
Y1174310D03*
X1664074Y1181791D03*
X1671555Y1189271D03*
X1665945Y1194881D03*
X1664074Y1204232D03*
X1669685Y1202362D03*
X1673425Y1221062D03*
X1669685Y1209842D03*
X1665945Y1221062D03*
Y1217322D03*
X1662204Y1221062D03*
Y1232283D03*
Y1236023D03*
X1673425Y1224803D03*
Y1228543D03*
X1669685Y1232283D03*
Y1236023D03*
X1665945Y1224803D03*
Y1228543D03*
X1662204Y1239763D03*
X1669685D03*
X1673425Y1258465D03*
X1665945D03*
X1665998Y1348187D03*
X1670358D03*
X1665998Y1360099D03*
X1670358D03*
X1665998Y1384297D03*
Y1372385D03*
X1670358D03*
Y1384297D03*
X1665998Y1396583D03*
X1670358D03*
X1665998Y1408495D03*
X1670358D03*
X1677166Y1075196D03*
X1684646D03*
X1692126D03*
X1688385Y1071455D03*
X1680905D03*
X1677166Y1078936D03*
X1692126D03*
X1684646D03*
X1684644Y1090157D03*
X1677165Y1093897D03*
X1684645D03*
X1680905Y1105117D03*
X1677164Y1108857D03*
X1684645Y1108858D03*
X1690256Y1140649D03*
Y1155610D03*
Y1148129D03*
X1682775Y1166830D03*
X1679035Y1170570D03*
X1690256D03*
Y1178051D03*
X1682775Y1174310D03*
X1679035Y1178051D03*
X1682775Y1181791D03*
X1679035Y1185531D03*
X1682775Y1189271D03*
X1690256Y1185531D03*
X1680905Y1194881D03*
X1690256Y1193011D03*
X1679035D03*
X1692126Y1202362D03*
X1680905D03*
Y1198621D03*
X1677165D03*
X1684645Y1221062D03*
X1692126Y1209842D03*
X1680905Y1221062D03*
Y1217322D03*
X1677165Y1221062D03*
Y1213582D03*
X1680905D03*
Y1209842D03*
Y1206102D03*
X1688385Y1224803D03*
Y1228543D03*
X1684645Y1236023D03*
Y1232283D03*
X1692126D03*
X1680905Y1224803D03*
Y1228543D03*
X1677165Y1232283D03*
Y1236023D03*
X1680905Y1239763D03*
X1692126D03*
X1688385Y1258465D03*
X1680905D03*
X1678238Y1348187D03*
X1690478D03*
X1682598D03*
X1678238Y1360099D03*
X1690478D03*
X1682598D03*
X1678238Y1372385D03*
Y1384297D03*
X1690478D03*
Y1372385D03*
X1682598Y1384297D03*
Y1372385D03*
X1678238Y1396583D03*
X1690478D03*
X1682598D03*
X1678238Y1408495D03*
X1690478D03*
X1682598D03*
X1695866Y1078936D03*
X1699607Y1090158D03*
Y1082677D03*
Y1101378D03*
Y1123819D03*
Y1116339D03*
Y1108859D03*
Y1131300D03*
X1693996Y1170570D03*
Y1178051D03*
Y1185531D03*
Y1193011D03*
X1697676D03*
X1695866Y1202362D03*
X1699607Y1198621D03*
Y1221062D03*
Y1213582D03*
Y1206102D03*
Y1228543D03*
X1695866Y1250984D03*
X1699607Y1247243D03*
Y1239762D03*
X1695866Y1239763D03*
X1694838Y1348187D03*
X1702718D03*
X1707078D03*
X1702718Y1360099D03*
X1707078D03*
X1694838D03*
Y1384297D03*
Y1372385D03*
X1702718D03*
Y1384297D03*
X1707078D03*
Y1372385D03*
X1694838Y1396583D03*
X1702718D03*
X1707078D03*
X1694838Y1408495D03*
X1702718D03*
X1707078D03*
X1714958Y1348187D03*
X1719318D03*
X1714958Y1360099D03*
X1719318D03*
X1714958Y1384297D03*
Y1372385D03*
X1719318D03*
Y1384297D03*
X1714958Y1396583D03*
X1719318D03*
X1714958Y1408495D03*
X1719318D03*
X1727198Y1348187D03*
X1739438D03*
X1731558D03*
X1727198Y1360099D03*
X1739438D03*
X1731558D03*
X1739438Y1372385D03*
X1731558Y1384297D03*
Y1372385D03*
X1727198D03*
Y1384297D03*
X1739438D03*
X1727198Y1396583D03*
X1739438D03*
X1731558D03*
X1727198Y1408495D03*
X1739438D03*
X1731558D03*
G54D52*
X956448Y-30304D03*
Y-33204D03*
X953192Y-25085D03*
X956445Y-25099D03*
X950167Y-26405D03*
X953207Y-27600D03*
X956460Y-27614D03*
X978036Y-64265D03*
X975011Y-65585D03*
X978051Y-66780D03*
X981289Y-64279D03*
X981292Y-69484D03*
Y-72384D03*
X981304Y-66794D03*
X1231351Y-77080D03*
X1234592Y-79984D03*
X1234604Y-77094D03*
X1234592Y-82584D03*
Y-71970D03*
X1231336Y-74565D03*
X1234589Y-74579D03*
X1231336Y-64265D03*
X1234589D03*
X1234592Y-69470D03*
X1231351Y-66780D03*
X1234604D03*
X1228311Y-65585D03*
Y-75885D03*
X1236692Y-35515D03*
X1236707Y-38030D03*
X1233667Y-36835D03*
X1236692Y-25215D03*
X1236707Y-27730D03*
X1233667Y-26535D03*
X1239948Y-32920D03*
X1239945Y-35529D03*
X1239948Y-30420D03*
Y-40934D03*
X1239960Y-38044D03*
X1239948Y-43534D03*
X1239945Y-25215D03*
X1239960Y-27730D03*
X1487851Y-77080D03*
X1491092Y-79984D03*
X1491104Y-77094D03*
X1491092Y-82584D03*
Y-71970D03*
X1487836Y-74565D03*
X1491089Y-74579D03*
X1487836Y-64265D03*
X1491089D03*
X1491092Y-69470D03*
X1487851Y-66780D03*
X1491104D03*
X1484811Y-65585D03*
Y-75885D03*
X1526448Y-33050D03*
X1523192Y-35645D03*
X1526445Y-35659D03*
X1526448Y-30550D03*
X1523207Y-38160D03*
X1526448Y-41064D03*
X1526460Y-38174D03*
X1526448Y-43664D03*
X1520167Y-36965D03*
X1523192Y-25345D03*
X1526445D03*
X1523207Y-27860D03*
X1526460D03*
X1520167Y-26665D03*
X1742336Y-74565D03*
Y-64265D03*
X1739311Y-65585D03*
Y-75885D03*
X1742351Y-77080D03*
X1745592Y-79984D03*
X1745604Y-77094D03*
X1745592Y-82584D03*
Y-71970D03*
X1745589Y-74579D03*
Y-64265D03*
X1745592Y-69470D03*
X1742351Y-66780D03*
X1745604D03*
X1804667Y-37095D03*
Y-26795D03*
X1810948Y-33180D03*
X1807692Y-35775D03*
X1810945Y-35789D03*
X1810948Y-30680D03*
X1807707Y-38290D03*
X1810948Y-41194D03*
X1810960Y-38304D03*
X1810948Y-43794D03*
X1807692Y-25475D03*
X1810945D03*
X1807707Y-27990D03*
X1810960D03*
G54D23*
X46348Y1727941D03*
Y1737941D03*
Y1773941D03*
Y1783941D03*
X333112Y1751624D03*
Y1761624D03*
X333212Y1797624D03*
Y1807624D03*
X619861Y1751765D03*
Y1761765D03*
X619475Y1798845D03*
Y1808845D03*
X907163Y1752566D03*
Y1762566D03*
X907166Y1800435D03*
Y1810435D03*
G54D41*
X266841Y421555D03*
Y550020D03*
X295856Y421555D03*
Y550020D03*
X723927Y421555D03*
Y550020D03*
X752942Y421555D03*
Y550020D03*
X1181014Y421555D03*
Y550020D03*
X1210029Y421555D03*
Y550020D03*
X1638101Y421555D03*
Y550020D03*
X1667116Y421555D03*
Y550020D03*
G54D56*
X1236871Y1715189D03*
X1236864Y1773377D03*
X1235371Y1802909D03*
G54D57*
X1236871Y1744208D03*
%LPC*%
G75*
G54D64*
G01X-20602Y-468335D02*
Y-543335D01*
X479398D01*
Y-468335D01*
X-20602D01*
G01X-8602Y-533335D02*
Y-538335D01*
G01X-10059Y-533335D02*
X-7145D01*
G01X-2235Y-538335D02*
X-4769D01*
Y-533335D01*
X-2235D01*
G01X-3249Y-535752D02*
X-4769D01*
G01X331Y-533335D02*
Y-538335D01*
X2865D01*
G01X6698Y-538502D02*
X6571Y-538418D01*
Y-538252D01*
X6698Y-538168D01*
X6825Y-538252D01*
Y-538418D01*
X6698Y-538502D01*
G01Y-536252D02*
X6571Y-536168D01*
Y-536002D01*
X6698Y-535918D01*
X6825Y-536002D01*
Y-536168D01*
X6698Y-536252D01*
G01X11481Y-540002D02*
X10848Y-539168D01*
X10531Y-538335D01*
Y-535002D01*
X10848Y-534168D01*
X11481Y-533335D01*
G01X16898D02*
X16391Y-533502D01*
X16011Y-533918D01*
X15758Y-534418D01*
X15568Y-535085D01*
X15505Y-535835D01*
X15568Y-536585D01*
X15758Y-537252D01*
X16011Y-537752D01*
X16391Y-538168D01*
X16898Y-538335D01*
X17405Y-538168D01*
X17785Y-537752D01*
X18038Y-537252D01*
X18228Y-536585D01*
X18291Y-535835D01*
X18228Y-535085D01*
X18038Y-534418D01*
X17785Y-533918D01*
X17405Y-533502D01*
X16898Y-533335D01*
G01X20605Y-537335D02*
X20985Y-537918D01*
X21491Y-538252D01*
X22061Y-538335D01*
X22568Y-538252D01*
X23075Y-537835D01*
X23391Y-537335D01*
X23455Y-536835D01*
X23328Y-536252D01*
X22885Y-535835D01*
X22441Y-535668D01*
X21871D01*
G01X22441D02*
X22821Y-535418D01*
X23138Y-535002D01*
X23265Y-534502D01*
X23138Y-534002D01*
X22821Y-533585D01*
X22251Y-533335D01*
X21681Y-533418D01*
X21111Y-533752D01*
G01X27415Y-540002D02*
X28048Y-539168D01*
X28365Y-538335D01*
Y-535002D01*
X28048Y-534168D01*
X27415Y-533335D01*
G01X30805Y-537335D02*
X31185Y-537918D01*
X31691Y-538252D01*
X32261Y-538335D01*
X32768Y-538252D01*
X33275Y-537835D01*
X33591Y-537335D01*
X33655Y-536835D01*
X33528Y-536252D01*
X33085Y-535835D01*
X32641Y-535668D01*
X32071D01*
G01X32641D02*
X33021Y-535418D01*
X33338Y-535002D01*
X33465Y-534502D01*
X33338Y-534002D01*
X33021Y-533585D01*
X32451Y-533335D01*
X31881Y-533418D01*
X31311Y-533752D01*
G01X36095Y-534168D02*
X36475Y-533668D01*
X36918Y-533418D01*
X37425Y-533335D01*
X38058Y-533502D01*
X38501Y-533918D01*
X38628Y-534418D01*
X38565Y-534918D01*
X38311Y-535335D01*
X37045Y-536168D01*
X36475Y-536752D01*
X36095Y-537585D01*
X35968Y-538335D01*
X38628D01*
G01X42271D02*
X42398Y-537252D01*
X42588Y-536335D01*
X42841Y-535502D01*
X43158Y-534585D01*
X43665Y-533335D01*
X41131D01*
G01X46675Y-536668D02*
X48321D01*
G01X51395Y-534168D02*
X51775Y-533668D01*
X52218Y-533418D01*
X52725Y-533335D01*
X53358Y-533502D01*
X53801Y-533918D01*
X53928Y-534418D01*
X53865Y-534918D01*
X53611Y-535335D01*
X52345Y-536168D01*
X51775Y-536752D01*
X51395Y-537585D01*
X51268Y-538335D01*
X53928D01*
G01X56305Y-537335D02*
X56685Y-537918D01*
X57191Y-538252D01*
X57761Y-538335D01*
X58268Y-538252D01*
X58775Y-537835D01*
X59091Y-537335D01*
X59155Y-536835D01*
X59028Y-536252D01*
X58585Y-535835D01*
X58141Y-535668D01*
X57571D01*
G01X58141D02*
X58521Y-535418D01*
X58838Y-535002D01*
X58965Y-534502D01*
X58838Y-534002D01*
X58521Y-533585D01*
X57951Y-533335D01*
X57381Y-533418D01*
X56811Y-533752D01*
G01X63558Y-538335D02*
Y-533335D01*
X61215Y-536918D01*
X64381D01*
G01X66505Y-537585D02*
X66885Y-538002D01*
X67328Y-538252D01*
X67898Y-538335D01*
X68468Y-538168D01*
X68911Y-537835D01*
X69228Y-537252D01*
X69291Y-536585D01*
X69165Y-535918D01*
X68848Y-535502D01*
X68405Y-535168D01*
X67961Y-535085D01*
X67518Y-535168D01*
X66948Y-535502D01*
X67138Y-533335D01*
X68848D01*
G01X76895Y-538335D02*
Y-533335D01*
X79301D01*
G01X78415Y-535752D02*
X76895D01*
G01X81615Y-538335D02*
X83198Y-533335D01*
X84781Y-538335D01*
G01X84211Y-536585D02*
X82185D01*
G01X86968Y-538335D02*
X89628Y-533335D01*
G01X86968D02*
X89628Y-538335D01*
G01X93398Y-538502D02*
X93271Y-538418D01*
Y-538252D01*
X93398Y-538168D01*
X93525Y-538252D01*
Y-538418D01*
X93398Y-538502D01*
G01Y-536252D02*
X93271Y-536168D01*
Y-536002D01*
X93398Y-535918D01*
X93525Y-536002D01*
Y-536168D01*
X93398Y-536252D01*
G01X98181Y-540002D02*
X97548Y-539168D01*
X97231Y-538335D01*
Y-535002D01*
X97548Y-534168D01*
X98181Y-533335D01*
G01X103598D02*
X103091Y-533502D01*
X102711Y-533918D01*
X102458Y-534418D01*
X102268Y-535085D01*
X102205Y-535835D01*
X102268Y-536585D01*
X102458Y-537252D01*
X102711Y-537752D01*
X103091Y-538168D01*
X103598Y-538335D01*
X104105Y-538168D01*
X104485Y-537752D01*
X104738Y-537252D01*
X104928Y-536585D01*
X104991Y-535835D01*
X104928Y-535085D01*
X104738Y-534418D01*
X104485Y-533918D01*
X104105Y-533502D01*
X103598Y-533335D01*
G01X107305Y-537335D02*
X107685Y-537918D01*
X108191Y-538252D01*
X108761Y-538335D01*
X109268Y-538252D01*
X109775Y-537835D01*
X110091Y-537335D01*
X110155Y-536835D01*
X110028Y-536252D01*
X109585Y-535835D01*
X109141Y-535668D01*
X108571D01*
G01X109141D02*
X109521Y-535418D01*
X109838Y-535002D01*
X109965Y-534502D01*
X109838Y-534002D01*
X109521Y-533585D01*
X108951Y-533335D01*
X108381Y-533418D01*
X107811Y-533752D01*
G01X114115Y-540002D02*
X114748Y-539168D01*
X115065Y-538335D01*
Y-535002D01*
X114748Y-534168D01*
X114115Y-533335D01*
G01X117505Y-537335D02*
X117885Y-537918D01*
X118391Y-538252D01*
X118961Y-538335D01*
X119468Y-538252D01*
X119975Y-537835D01*
X120291Y-537335D01*
X120355Y-536835D01*
X120228Y-536252D01*
X119785Y-535835D01*
X119341Y-535668D01*
X118771D01*
G01X119341D02*
X119721Y-535418D01*
X120038Y-535002D01*
X120165Y-534502D01*
X120038Y-534002D01*
X119721Y-533585D01*
X119151Y-533335D01*
X118581Y-533418D01*
X118011Y-533752D01*
G01X122921Y-537752D02*
X123365Y-538168D01*
X123871Y-538335D01*
X124378Y-538168D01*
X124821Y-537668D01*
X125138Y-536918D01*
X125265Y-536168D01*
Y-535252D01*
X125138Y-534502D01*
X124821Y-533835D01*
X124441Y-533502D01*
X123998Y-533335D01*
X123491Y-533502D01*
X123111Y-533835D01*
X122858Y-534335D01*
X122731Y-535002D01*
X122858Y-535585D01*
X123175Y-536168D01*
X123555Y-536502D01*
X123998Y-536585D01*
X124505Y-536418D01*
X124885Y-536002D01*
X125265Y-535252D01*
G01X128971Y-538335D02*
X129098Y-537252D01*
X129288Y-536335D01*
X129541Y-535502D01*
X129858Y-534585D01*
X130365Y-533335D01*
X127831D01*
G01X133375Y-536668D02*
X135021D01*
G01X137905Y-537335D02*
X138285Y-537918D01*
X138791Y-538252D01*
X139361Y-538335D01*
X139868Y-538252D01*
X140375Y-537835D01*
X140691Y-537335D01*
X140755Y-536835D01*
X140628Y-536252D01*
X140185Y-535835D01*
X139741Y-535668D01*
X139171D01*
G01X139741D02*
X140121Y-535418D01*
X140438Y-535002D01*
X140565Y-534502D01*
X140438Y-534002D01*
X140121Y-533585D01*
X139551Y-533335D01*
X138981Y-533418D01*
X138411Y-533752D01*
G01X143195Y-536252D02*
X143638Y-535668D01*
X144018Y-535335D01*
X144525Y-535168D01*
X144968Y-535335D01*
X145285Y-535668D01*
X145538Y-536168D01*
X145601Y-536752D01*
X145538Y-537252D01*
X145285Y-537752D01*
X144905Y-538168D01*
X144461Y-538335D01*
X143955Y-538168D01*
X143511Y-537668D01*
X143258Y-536918D01*
X143195Y-536085D01*
X143321Y-535002D01*
X143511Y-534418D01*
X143828Y-533835D01*
X144271Y-533418D01*
X144715Y-533335D01*
X145158Y-533502D01*
X145475Y-533918D01*
G01X149498Y-538335D02*
Y-533335D01*
X148738Y-534335D01*
G01Y-538335D02*
X150258D01*
G01X155358D02*
Y-533335D01*
X153015Y-536918D01*
X156181D01*
G01X174398Y-468335D02*
Y-543335D01*
G01Y-518335D02*
X277398D01*
Y-493335D01*
G01X174398D02*
X277398D01*
G01Y-468335D02*
Y-543335D01*
G01X279398Y-468335D02*
Y-543335D01*
G01X284905Y-528335D02*
Y-523335D01*
X286171D01*
X286678Y-523585D01*
X287058Y-523918D01*
X287375Y-524418D01*
X287628Y-525002D01*
X287691Y-525835D01*
X287628Y-526668D01*
X287375Y-527252D01*
X287058Y-527752D01*
X286678Y-528085D01*
X286171Y-528335D01*
X284905D01*
G01X289815D02*
X291398Y-523335D01*
X292981Y-528335D01*
G01X292411Y-526585D02*
X290385D01*
G01X296498Y-523335D02*
Y-528335D01*
G01X295041Y-523335D02*
X297955D01*
G01X302865Y-528335D02*
X300331D01*
Y-523335D01*
X302865D01*
G01X301851Y-525752D02*
X300331D01*
G01X306698Y-528502D02*
X306571Y-528418D01*
Y-528252D01*
X306698Y-528168D01*
X306825Y-528252D01*
Y-528418D01*
X306698Y-528502D01*
G01Y-526252D02*
X306571Y-526168D01*
Y-526002D01*
X306698Y-525918D01*
X306825Y-526002D01*
Y-526168D01*
X306698Y-526252D01*
G01X279398Y-518335D02*
X479398D01*
G01X285031Y-503335D02*
Y-498335D01*
X286551D01*
X287058Y-498585D01*
X287438Y-499168D01*
X287565Y-499835D01*
X287438Y-500502D01*
X287121Y-501002D01*
X286551Y-501252D01*
X285031D01*
G01X290258Y-503502D02*
X292538Y-498335D01*
G01X295041Y-503335D02*
Y-498335D01*
X297955Y-503335D01*
Y-498335D01*
G01X301598Y-503502D02*
X301471Y-503418D01*
Y-503252D01*
X301598Y-503168D01*
X301725Y-503252D01*
Y-503418D01*
X301598Y-503502D01*
G01Y-501252D02*
X301471Y-501168D01*
Y-501002D01*
X301598Y-500918D01*
X301725Y-501002D01*
Y-501168D01*
X301598Y-501252D01*
G01X279398Y-493335D02*
X479398D01*
G01X285031Y-478335D02*
Y-473335D01*
X286551D01*
X287058Y-473585D01*
X287438Y-474168D01*
X287565Y-474835D01*
X287438Y-475502D01*
X287121Y-476002D01*
X286551Y-476252D01*
X285031D01*
G01X290131Y-478335D02*
Y-473335D01*
X291715D01*
X292221Y-473585D01*
X292538Y-473918D01*
X292665Y-474585D01*
X292538Y-475252D01*
X292158Y-475668D01*
X291715Y-475918D01*
X290131D01*
G01X291715D02*
X292665Y-478335D01*
G01X296498D02*
X295991Y-478252D01*
X295548Y-477918D01*
X295168Y-477418D01*
X294915Y-476835D01*
X294788Y-476168D01*
Y-475502D01*
X294915Y-474835D01*
X295168Y-474252D01*
X295548Y-473752D01*
X295991Y-473418D01*
X296498Y-473335D01*
X297005Y-473418D01*
X297448Y-473752D01*
X297828Y-474252D01*
X298081Y-474835D01*
X298208Y-475502D01*
Y-476168D01*
X298081Y-476835D01*
X297828Y-477418D01*
X297448Y-477918D01*
X297005Y-478252D01*
X296498Y-478335D01*
G01X300331Y-477335D02*
X300648Y-477835D01*
X301028Y-478168D01*
X301471Y-478335D01*
X301978Y-478168D01*
X302358Y-477835D01*
X302738Y-477335D01*
X302865Y-476668D01*
Y-473335D01*
G01X307965Y-478335D02*
X305431D01*
Y-473335D01*
X307965D01*
G01X306951Y-475752D02*
X305431D01*
G01X313191Y-473752D02*
X312811Y-473502D01*
X312368Y-473335D01*
X311861D01*
X311291Y-473585D01*
X310848Y-474002D01*
X310531Y-474502D01*
X310278Y-475335D01*
X310215Y-476085D01*
X310341Y-476835D01*
X310531Y-477335D01*
X310911Y-477835D01*
X311355Y-478168D01*
X311798Y-478335D01*
X312241D01*
X312685Y-478168D01*
X313065Y-477918D01*
X313381Y-477585D01*
G01X316898Y-473335D02*
Y-478335D01*
G01X315441Y-473335D02*
X318355D01*
G01X321998Y-478502D02*
X321871Y-478418D01*
Y-478252D01*
X321998Y-478168D01*
X322125Y-478252D01*
Y-478418D01*
X321998Y-478502D01*
G01Y-476252D02*
X321871Y-476168D01*
Y-476002D01*
X321998Y-475918D01*
X322125Y-476002D01*
Y-476168D01*
X321998Y-476252D01*
G01X394258Y-543563D02*
Y-518563D01*
G01X397031Y-520835D02*
Y-525835D01*
X399565D01*
G01X402638Y-520835D02*
X404158D01*
G01X403398D02*
Y-525835D01*
G01X402638D02*
X404158D01*
G01X409005Y-523168D02*
X409258Y-522918D01*
X409448Y-522502D01*
X409575Y-521918D01*
X409448Y-521418D01*
X409195Y-521085D01*
X408751Y-520835D01*
X407041D01*
Y-525835D01*
X409131D01*
X409575Y-525502D01*
X409828Y-525002D01*
X409955Y-524418D01*
X409828Y-523835D01*
X409448Y-523335D01*
X409005Y-523168D01*
X407041D01*
G01X413598Y-526002D02*
X413471Y-525918D01*
Y-525752D01*
X413598Y-525668D01*
X413725Y-525752D01*
Y-525918D01*
X413598Y-526002D01*
G01Y-523752D02*
X413471Y-523668D01*
Y-523502D01*
X413598Y-523418D01*
X413725Y-523502D01*
Y-523668D01*
X413598Y-523752D01*
G01X437258Y-518563D02*
Y-543563D01*
G01X437398Y-518335D02*
Y-543335D01*
G01X441298Y-520835D02*
Y-525835D01*
G01X439841Y-520835D02*
X442755D01*
G01X446398Y-525835D02*
X446018Y-525752D01*
X445638Y-525418D01*
X445385Y-524835D01*
X445258Y-524168D01*
X445385Y-523502D01*
X445638Y-522918D01*
X446018Y-522585D01*
X446398Y-522502D01*
X446778Y-522585D01*
X447158Y-522918D01*
X447411Y-523502D01*
X447475Y-524168D01*
X447411Y-524835D01*
X447158Y-525418D01*
X446778Y-525752D01*
X446398Y-525835D01*
G01X451498D02*
X451118Y-525752D01*
X450738Y-525418D01*
X450485Y-524835D01*
X450358Y-524168D01*
X450485Y-523502D01*
X450738Y-522918D01*
X451118Y-522585D01*
X451498Y-522502D01*
X451878Y-522585D01*
X452258Y-522918D01*
X452511Y-523502D01*
X452575Y-524168D01*
X452511Y-524835D01*
X452258Y-525418D01*
X451878Y-525752D01*
X451498Y-525835D01*
G01X456598D02*
Y-520835D01*
G01X461698Y-526002D02*
X461571Y-525918D01*
Y-525752D01*
X461698Y-525668D01*
X461825Y-525752D01*
Y-525918D01*
X461698Y-526002D01*
G01Y-523752D02*
X461571Y-523668D01*
Y-523502D01*
X461698Y-523418D01*
X461825Y-523502D01*
Y-523668D01*
X461698Y-523752D01*
G01X437398Y-493335D02*
Y-518335D01*
G01X440031Y-500835D02*
Y-495835D01*
X441615D01*
X442121Y-496085D01*
X442438Y-496418D01*
X442565Y-497085D01*
X442438Y-497752D01*
X442058Y-498168D01*
X441615Y-498418D01*
X440031D01*
G01X441615D02*
X442565Y-500835D01*
G01X447665D02*
X445131D01*
Y-495835D01*
X447665D01*
G01X446651Y-498252D02*
X445131D01*
G01X449915Y-495835D02*
X451498Y-500835D01*
X453081Y-495835D01*
G01X456598Y-501002D02*
X456471Y-500918D01*
Y-500752D01*
X456598Y-500668D01*
X456725Y-500752D01*
Y-500918D01*
X456598Y-501002D01*
G01Y-498752D02*
X456471Y-498668D01*
Y-498502D01*
X456598Y-498418D01*
X456725Y-498502D01*
Y-498668D01*
X456598Y-498752D01*
G01X445411Y-546502D02*
X445518Y-546377D01*
X445598Y-546168D01*
X445651Y-545877D01*
X445598Y-545627D01*
X445491Y-545460D01*
X445305Y-545335D01*
X444585D01*
Y-547835D01*
X445465D01*
X445651Y-547668D01*
X445758Y-547418D01*
X445811Y-547127D01*
X445758Y-546835D01*
X445598Y-546585D01*
X445411Y-546502D01*
X444585D01*
G01X447878Y-547835D02*
Y-546168D01*
G01Y-546460D02*
X447771Y-546293D01*
X447611Y-546210D01*
X447425Y-546168D01*
X447238Y-546252D01*
X447078Y-546418D01*
X446971Y-546668D01*
X446918Y-547002D01*
X446971Y-547335D01*
X447078Y-547585D01*
X447238Y-547752D01*
X447425Y-547835D01*
X447611Y-547793D01*
X447771Y-547668D01*
X447878Y-547502D01*
G01X449198Y-547543D02*
X449331Y-547710D01*
X449518Y-547835D01*
X449678D01*
X449838Y-547752D01*
X449945Y-547627D01*
X449998Y-547460D01*
X449971Y-547210D01*
X449865Y-547085D01*
X449385Y-546835D01*
X449278Y-546543D01*
X449331Y-546335D01*
X449438Y-546210D01*
X449598Y-546168D01*
X449758Y-546210D01*
X449918Y-546335D01*
G01X451398Y-546710D02*
X452251D01*
X452171Y-546418D01*
X452038Y-546252D01*
X451851Y-546168D01*
X451665Y-546210D01*
X451505Y-546335D01*
X451398Y-546627D01*
X451345Y-546877D01*
Y-547127D01*
X451398Y-547377D01*
X451531Y-547627D01*
X451691Y-547793D01*
X451878Y-547835D01*
X452065Y-547752D01*
X452251Y-547502D01*
G01X453518Y-547835D02*
Y-545335D01*
G01Y-546585D02*
X453651Y-546335D01*
X453811Y-546210D01*
X453971Y-546168D01*
X454211Y-546252D01*
X454371Y-546418D01*
X454478Y-546710D01*
Y-547043D01*
X454425Y-547377D01*
X454318Y-547627D01*
X454131Y-547793D01*
X453971Y-547835D01*
X453811Y-547793D01*
X453651Y-547668D01*
X453518Y-547460D01*
G01X456198Y-547835D02*
X456038Y-547793D01*
X455878Y-547627D01*
X455771Y-547335D01*
X455718Y-547002D01*
X455771Y-546668D01*
X455878Y-546377D01*
X456038Y-546210D01*
X456198Y-546168D01*
X456358Y-546210D01*
X456518Y-546377D01*
X456625Y-546668D01*
X456651Y-547002D01*
X456625Y-547335D01*
X456518Y-547627D01*
X456358Y-547793D01*
X456198Y-547835D01*
G01X458878D02*
Y-546168D01*
G01Y-546460D02*
X458771Y-546293D01*
X458611Y-546210D01*
X458425Y-546168D01*
X458238Y-546252D01*
X458078Y-546418D01*
X457971Y-546668D01*
X457918Y-547002D01*
X457971Y-547335D01*
X458078Y-547585D01*
X458238Y-547752D01*
X458425Y-547835D01*
X458611Y-547793D01*
X458771Y-547668D01*
X458878Y-547502D01*
G01X460225Y-547835D02*
Y-546168D01*
G01Y-546502D02*
X460358Y-546335D01*
X460491Y-546210D01*
X460678Y-546168D01*
X460811Y-546210D01*
X460971Y-546335D01*
G01X463278Y-545335D02*
Y-547835D01*
G01Y-547460D02*
X463171Y-547668D01*
X463011Y-547793D01*
X462825Y-547835D01*
X462611Y-547752D01*
X462451Y-547543D01*
X462345Y-547293D01*
X462318Y-547002D01*
X462345Y-546710D01*
X462451Y-546460D01*
X462611Y-546252D01*
X462825Y-546168D01*
X463011Y-546210D01*
X463145Y-546293D01*
X463278Y-546460D01*
G01X466665Y-547835D02*
Y-545335D01*
X467331D01*
X467545Y-545460D01*
X467678Y-545627D01*
X467731Y-545960D01*
X467678Y-546293D01*
X467518Y-546502D01*
X467331Y-546627D01*
X466665D01*
G01X467331D02*
X467731Y-547835D01*
G01X468998Y-546710D02*
X469851D01*
X469771Y-546418D01*
X469638Y-546252D01*
X469451Y-546168D01*
X469265Y-546210D01*
X469105Y-546335D01*
X468998Y-546627D01*
X468945Y-546877D01*
Y-547127D01*
X468998Y-547377D01*
X469131Y-547627D01*
X469291Y-547793D01*
X469478Y-547835D01*
X469665Y-547752D01*
X469851Y-547502D01*
G01X471118Y-546168D02*
X471598Y-547835D01*
X472078Y-546168D01*
G01X473798Y-547918D02*
X473745Y-547877D01*
Y-547793D01*
X473798Y-547752D01*
X473851Y-547793D01*
Y-547877D01*
X473798Y-547918D01*
G01X475545Y-547543D02*
X475731Y-547752D01*
X475945Y-547835D01*
X476158Y-547752D01*
X476345Y-547502D01*
X476478Y-547127D01*
X476531Y-546752D01*
Y-546293D01*
X476478Y-545918D01*
X476345Y-545585D01*
X476185Y-545418D01*
X475998Y-545335D01*
X475785Y-545418D01*
X475625Y-545585D01*
X475518Y-545835D01*
X475465Y-546168D01*
X475518Y-546460D01*
X475651Y-546752D01*
X475811Y-546918D01*
X475998Y-546960D01*
X476211Y-546877D01*
X476371Y-546668D01*
X476531Y-546293D01*
G01X478411Y-546502D02*
X478518Y-546377D01*
X478598Y-546168D01*
X478651Y-545877D01*
X478598Y-545627D01*
X478491Y-545460D01*
X478305Y-545335D01*
X477585D01*
Y-547835D01*
X478465D01*
X478651Y-547668D01*
X478758Y-547418D01*
X478811Y-547127D01*
X478758Y-546835D01*
X478598Y-546585D01*
X478411Y-546502D01*
X477585D01*
G01X-1490433Y-1677216D02*
Y3837819D01*
X4496476D01*
Y-1677216D01*
X-1490433D01*
G01X-7782Y-515685D02*
X-6215D01*
Y-517575D01*
X-6685Y-518205D01*
X-7234Y-518625D01*
X-8017Y-518835D01*
X-8800Y-518625D01*
X-9349Y-518205D01*
X-9819Y-517575D01*
X-10132Y-516840D01*
X-10289Y-516000D01*
Y-515265D01*
X-10132Y-514635D01*
X-9819Y-513900D01*
X-9349Y-513270D01*
X-8879Y-512850D01*
X-8252Y-512535D01*
X-7704D01*
X-7077Y-512745D01*
X-6607Y-513165D01*
G01X-3675Y-512535D02*
Y-517050D01*
X-3362Y-517995D01*
X-2735Y-518625D01*
X-1952Y-518835D01*
X-1169Y-518625D01*
X-542Y-517995D01*
X-229Y-517050D01*
Y-512535D01*
G01X3408D02*
X5288D01*
G01X4348D02*
Y-518835D01*
G01X3408D02*
X5288D01*
G01X9003Y-517995D02*
X9630Y-518520D01*
X10335Y-518835D01*
X10961D01*
X11588Y-518520D01*
X12058Y-517995D01*
X12293Y-517260D01*
X12136Y-516525D01*
X11745Y-515895D01*
X11040Y-515475D01*
X10100Y-515265D01*
X9551Y-514845D01*
X9316Y-514110D01*
X9473Y-513375D01*
X9865Y-512850D01*
X10413Y-512535D01*
X10961D01*
X11510Y-512745D01*
X11980Y-513270D01*
G01X15303Y-518835D02*
Y-512535D01*
G01X18593D02*
Y-518835D01*
G01Y-515685D02*
X15303D01*
G01X21290Y-518835D02*
X23248Y-512535D01*
X25206Y-518835D01*
G01X24501Y-516630D02*
X21995D01*
G01X27746Y-518835D02*
Y-512535D01*
X31350Y-518835D01*
Y-512535D01*
G01X40425Y-518835D02*
Y-512535D01*
X41991D01*
X42618Y-512850D01*
X43088Y-513270D01*
X43480Y-513900D01*
X43793Y-514635D01*
X43871Y-515685D01*
X43793Y-516735D01*
X43480Y-517470D01*
X43088Y-518100D01*
X42618Y-518520D01*
X41991Y-518835D01*
X40425D01*
G01X47508Y-512535D02*
X49388D01*
G01X48448D02*
Y-518835D01*
G01X47508D02*
X49388D01*
G01X53103Y-517995D02*
X53730Y-518520D01*
X54435Y-518835D01*
X55061D01*
X55688Y-518520D01*
X56158Y-517995D01*
X56393Y-517260D01*
X56236Y-516525D01*
X55845Y-515895D01*
X55140Y-515475D01*
X54200Y-515265D01*
X53651Y-514845D01*
X53416Y-514110D01*
X53573Y-513375D01*
X53965Y-512850D01*
X54513Y-512535D01*
X55061D01*
X55610Y-512745D01*
X56080Y-513270D01*
G01X61048Y-512535D02*
Y-518835D01*
G01X59246Y-512535D02*
X62850D01*
G01X67348Y-519045D02*
X67191Y-518940D01*
Y-518730D01*
X67348Y-518625D01*
X67505Y-518730D01*
Y-518940D01*
X67348Y-519045D01*
G01X73491Y-519990D02*
X73805Y-518625D01*
G01X79948Y-512535D02*
Y-518835D01*
G01X78146Y-512535D02*
X81750D01*
G01X84290Y-518835D02*
X86248Y-512535D01*
X88206Y-518835D01*
G01X87501Y-516630D02*
X84995D01*
G01X92548Y-518835D02*
X91921Y-518730D01*
X91373Y-518310D01*
X90903Y-517680D01*
X90590Y-516945D01*
X90433Y-516105D01*
Y-515265D01*
X90590Y-514425D01*
X90903Y-513690D01*
X91373Y-513060D01*
X91921Y-512640D01*
X92548Y-512535D01*
X93175Y-512640D01*
X93723Y-513060D01*
X94193Y-513690D01*
X94506Y-514425D01*
X94663Y-515265D01*
Y-516105D01*
X94506Y-516945D01*
X94193Y-517680D01*
X93723Y-518310D01*
X93175Y-518730D01*
X92548Y-518835D01*
G01X98848D02*
Y-516000D01*
X97281Y-512535D01*
G01X100415D02*
X98848Y-516000D01*
G01X103425Y-512535D02*
Y-517050D01*
X103738Y-517995D01*
X104365Y-518625D01*
X105148Y-518835D01*
X105931Y-518625D01*
X106558Y-517995D01*
X106871Y-517050D01*
Y-512535D01*
G01X109490Y-518835D02*
X111448Y-512535D01*
X113406Y-518835D01*
G01X112701Y-516630D02*
X110195D01*
G01X115946Y-518835D02*
Y-512535D01*
X119550Y-518835D01*
Y-512535D01*
G01X-6529Y-523060D02*
X-6999Y-522745D01*
X-7547Y-522535D01*
X-8174D01*
X-8879Y-522850D01*
X-9427Y-523375D01*
X-9819Y-524005D01*
X-10132Y-525055D01*
X-10210Y-526000D01*
X-10054Y-526945D01*
X-9819Y-527575D01*
X-9349Y-528205D01*
X-8800Y-528625D01*
X-8252Y-528835D01*
X-7704D01*
X-7155Y-528625D01*
X-6685Y-528310D01*
X-6294Y-527890D01*
G01X-2892Y-522535D02*
X-1012D01*
G01X-1952D02*
Y-528835D01*
G01X-2892D02*
X-1012D01*
G01X4348Y-522535D02*
Y-528835D01*
G01X2546Y-522535D02*
X6150D01*
G01X10648Y-528835D02*
Y-526000D01*
X9081Y-522535D01*
G01X12215D02*
X10648Y-526000D01*
G01X21525Y-527575D02*
X21995Y-528310D01*
X22621Y-528730D01*
X23326Y-528835D01*
X23953Y-528730D01*
X24580Y-528205D01*
X24971Y-527575D01*
X25050Y-526945D01*
X24893Y-526210D01*
X24345Y-525685D01*
X23796Y-525475D01*
X23091D01*
G01X23796D02*
X24266Y-525160D01*
X24658Y-524635D01*
X24815Y-524005D01*
X24658Y-523375D01*
X24266Y-522850D01*
X23561Y-522535D01*
X22856Y-522640D01*
X22151Y-523060D01*
G01X27825Y-527575D02*
X28295Y-528310D01*
X28921Y-528730D01*
X29626Y-528835D01*
X30253Y-528730D01*
X30880Y-528205D01*
X31271Y-527575D01*
X31350Y-526945D01*
X31193Y-526210D01*
X30645Y-525685D01*
X30096Y-525475D01*
X29391D01*
G01X30096D02*
X30566Y-525160D01*
X30958Y-524635D01*
X31115Y-524005D01*
X30958Y-523375D01*
X30566Y-522850D01*
X29861Y-522535D01*
X29156Y-522640D01*
X28451Y-523060D01*
G01X34125Y-527575D02*
X34595Y-528310D01*
X35221Y-528730D01*
X35926Y-528835D01*
X36553Y-528730D01*
X37180Y-528205D01*
X37571Y-527575D01*
X37650Y-526945D01*
X37493Y-526210D01*
X36945Y-525685D01*
X36396Y-525475D01*
X35691D01*
G01X36396D02*
X36866Y-525160D01*
X37258Y-524635D01*
X37415Y-524005D01*
X37258Y-523375D01*
X36866Y-522850D01*
X36161Y-522535D01*
X35456Y-522640D01*
X34751Y-523060D01*
G01X41991Y-528835D02*
X42148Y-527470D01*
X42383Y-526315D01*
X42696Y-525265D01*
X43088Y-524110D01*
X43715Y-522535D01*
X40581D01*
G01X48291Y-528835D02*
X48448Y-527470D01*
X48683Y-526315D01*
X48996Y-525265D01*
X49388Y-524110D01*
X50015Y-522535D01*
X46881D01*
G01X54591Y-529990D02*
X54905Y-528625D01*
G01X61048Y-522535D02*
Y-528835D01*
G01X59246Y-522535D02*
X62850D01*
G01X65390Y-528835D02*
X67348Y-522535D01*
X69306Y-528835D01*
G01X68601Y-526630D02*
X66095D01*
G01X72708Y-522535D02*
X74588D01*
G01X73648D02*
Y-528835D01*
G01X72708D02*
X74588D01*
G01X77598Y-522535D02*
X78695Y-528835D01*
X79948Y-522535D01*
X81201Y-528835D01*
X82298Y-522535D01*
G01X84290Y-528835D02*
X86248Y-522535D01*
X88206Y-528835D01*
G01X87501Y-526630D02*
X84995D01*
G01X90746Y-528835D02*
Y-522535D01*
X94350Y-528835D01*
Y-522535D01*
G01X104756Y-530935D02*
X103973Y-529885D01*
X103581Y-528835D01*
Y-524635D01*
X103973Y-523585D01*
X104756Y-522535D01*
G01X116181Y-528835D02*
Y-522535D01*
X118140D01*
X118766Y-522850D01*
X119158Y-523270D01*
X119315Y-524110D01*
X119158Y-524950D01*
X118688Y-525475D01*
X118140Y-525790D01*
X116181D01*
G01X118140D02*
X119315Y-528835D01*
G01X124048Y-529045D02*
X123891Y-528940D01*
Y-528730D01*
X124048Y-528625D01*
X124205Y-528730D01*
Y-528940D01*
X124048Y-529045D01*
G01X130348Y-528835D02*
X129721Y-528730D01*
X129173Y-528310D01*
X128703Y-527680D01*
X128390Y-526945D01*
X128233Y-526105D01*
Y-525265D01*
X128390Y-524425D01*
X128703Y-523690D01*
X129173Y-523060D01*
X129721Y-522640D01*
X130348Y-522535D01*
X130975Y-522640D01*
X131523Y-523060D01*
X131993Y-523690D01*
X132306Y-524425D01*
X132463Y-525265D01*
Y-526105D01*
X132306Y-526945D01*
X131993Y-527680D01*
X131523Y-528310D01*
X130975Y-528730D01*
X130348Y-528835D01*
G01X136648Y-529045D02*
X136491Y-528940D01*
Y-528730D01*
X136648Y-528625D01*
X136805Y-528730D01*
Y-528940D01*
X136648Y-529045D01*
G01X144671Y-523060D02*
X144201Y-522745D01*
X143653Y-522535D01*
X143026D01*
X142321Y-522850D01*
X141773Y-523375D01*
X141381Y-524005D01*
X141068Y-525055D01*
X140990Y-526000D01*
X141146Y-526945D01*
X141381Y-527575D01*
X141851Y-528205D01*
X142400Y-528625D01*
X142948Y-528835D01*
X143496D01*
X144045Y-528625D01*
X144515Y-528310D01*
X144906Y-527890D01*
G01X149248Y-529045D02*
X149091Y-528940D01*
Y-528730D01*
X149248Y-528625D01*
X149405Y-528730D01*
Y-528940D01*
X149248Y-529045D01*
G01X155940Y-530935D02*
X156723Y-529885D01*
X157115Y-528835D01*
Y-524635D01*
X156723Y-523585D01*
X155940Y-522535D01*
G01X-10054Y-508835D02*
Y-502535D01*
X-6450Y-508835D01*
Y-502535D01*
G01X-1952Y-508835D02*
X-2579Y-508730D01*
X-3127Y-508310D01*
X-3597Y-507680D01*
X-3910Y-506945D01*
X-4067Y-506105D01*
Y-505265D01*
X-3910Y-504425D01*
X-3597Y-503690D01*
X-3127Y-503060D01*
X-2579Y-502640D01*
X-1952Y-502535D01*
X-1325Y-502640D01*
X-777Y-503060D01*
X-307Y-503690D01*
X6Y-504425D01*
X163Y-505265D01*
Y-506105D01*
X6Y-506945D01*
X-307Y-507680D01*
X-777Y-508310D01*
X-1325Y-508730D01*
X-1952Y-508835D01*
G01X4348Y-509045D02*
X4191Y-508940D01*
Y-508730D01*
X4348Y-508625D01*
X4505Y-508730D01*
Y-508940D01*
X4348Y-509045D01*
G01X9160Y-503585D02*
X9630Y-502955D01*
X10178Y-502640D01*
X10805Y-502535D01*
X11588Y-502745D01*
X12136Y-503270D01*
X12293Y-503900D01*
X12215Y-504530D01*
X11901Y-505055D01*
X10335Y-506105D01*
X9630Y-506840D01*
X9160Y-507890D01*
X9003Y-508835D01*
X12293D01*
G01X16948D02*
Y-502535D01*
X16008Y-503795D01*
G01Y-508835D02*
X17888D01*
G01X23248D02*
Y-502535D01*
X22308Y-503795D01*
G01Y-508835D02*
X24188D01*
G01X29391Y-509990D02*
X29705Y-508625D01*
G01X33498Y-502535D02*
X34595Y-508835D01*
X35848Y-502535D01*
X37101Y-508835D01*
X38198Y-502535D01*
G01X43715Y-508835D02*
X40581D01*
Y-502535D01*
X43715D01*
G01X42461Y-505580D02*
X40581D01*
G01X46646Y-508835D02*
Y-502535D01*
X50250Y-508835D01*
Y-502535D01*
G01X53103Y-508835D02*
Y-502535D01*
G01X56393D02*
Y-508835D01*
G01Y-505685D02*
X53103D01*
G01X59325Y-502535D02*
Y-507050D01*
X59638Y-507995D01*
X60265Y-508625D01*
X61048Y-508835D01*
X61831Y-508625D01*
X62458Y-507995D01*
X62771Y-507050D01*
Y-502535D01*
G01X65390Y-508835D02*
X67348Y-502535D01*
X69306Y-508835D01*
G01X68601Y-506630D02*
X66095D01*
G01X78460Y-503585D02*
X78930Y-502955D01*
X79478Y-502640D01*
X80105Y-502535D01*
X80888Y-502745D01*
X81436Y-503270D01*
X81593Y-503900D01*
X81515Y-504530D01*
X81201Y-505055D01*
X79635Y-506105D01*
X78930Y-506840D01*
X78460Y-507890D01*
X78303Y-508835D01*
X81593D01*
G01X84446D02*
Y-502535D01*
X88050Y-508835D01*
Y-502535D01*
G01X90825Y-508835D02*
Y-502535D01*
X92391D01*
X93018Y-502850D01*
X93488Y-503270D01*
X93880Y-503900D01*
X94193Y-504635D01*
X94271Y-505685D01*
X94193Y-506735D01*
X93880Y-507470D01*
X93488Y-508100D01*
X93018Y-508520D01*
X92391Y-508835D01*
X90825D01*
G01X103581D02*
Y-502535D01*
X105540D01*
X106166Y-502850D01*
X106558Y-503270D01*
X106715Y-504110D01*
X106558Y-504950D01*
X106088Y-505475D01*
X105540Y-505790D01*
X103581D01*
G01X105540D02*
X106715Y-508835D01*
G01X109725D02*
Y-502535D01*
X111291D01*
X111918Y-502850D01*
X112388Y-503270D01*
X112780Y-503900D01*
X113093Y-504635D01*
X113171Y-505685D01*
X113093Y-506735D01*
X112780Y-507470D01*
X112388Y-508100D01*
X111918Y-508520D01*
X111291Y-508835D01*
X109725D01*
G01X117748Y-509045D02*
X117591Y-508940D01*
Y-508730D01*
X117748Y-508625D01*
X117905Y-508730D01*
Y-508940D01*
X117748Y-509045D01*
G01X14048Y-498135D02*
X11528Y-497718D01*
X9323Y-496052D01*
X7433Y-493552D01*
X6173Y-490635D01*
X5543Y-487302D01*
Y-483968D01*
X6173Y-480635D01*
X7433Y-477718D01*
X9323Y-475219D01*
X11528Y-473552D01*
X14048Y-473135D01*
X16568Y-473552D01*
X18773Y-475219D01*
X20663Y-477718D01*
X21923Y-480635D01*
X22553Y-483968D01*
Y-487302D01*
X21923Y-490635D01*
X20663Y-493552D01*
X18773Y-496052D01*
X16568Y-497718D01*
X14048Y-498135D01*
G01X16568Y-491468D02*
X20348Y-498135D01*
G01X33893Y-481469D02*
Y-493135D01*
X35153Y-496052D01*
X37043Y-497718D01*
X39248Y-498135D01*
X41453Y-497718D01*
X43343Y-496052D01*
X44603Y-493135D01*
G01Y-498135D02*
Y-481469D01*
G01X70118Y-498135D02*
Y-481469D01*
G01Y-484385D02*
X68858Y-482719D01*
X66968Y-481885D01*
X64763Y-481469D01*
X62558Y-482302D01*
X60668Y-483968D01*
X59408Y-486469D01*
X58778Y-489802D01*
X59408Y-493135D01*
X60668Y-495636D01*
X62558Y-497302D01*
X64763Y-498135D01*
X66968Y-497718D01*
X68858Y-496469D01*
X70118Y-494802D01*
G01X84293Y-498135D02*
Y-481469D01*
G01Y-485635D02*
X85553Y-483552D01*
X87443Y-481885D01*
X89963Y-481469D01*
X92168Y-481885D01*
X94058Y-483552D01*
X95003Y-486469D01*
Y-498135D01*
G01X114848Y-473135D02*
Y-498135D01*
G01X110438Y-481469D02*
X119258D01*
G01X145718Y-498135D02*
Y-481469D01*
G01Y-484385D02*
X144458Y-482719D01*
X142568Y-481885D01*
X140363Y-481469D01*
X138158Y-482302D01*
X136268Y-483968D01*
X135008Y-486469D01*
X134378Y-489802D01*
X135008Y-493135D01*
X136268Y-495636D01*
X138158Y-497302D01*
X140363Y-498135D01*
X142568Y-497718D01*
X144458Y-496469D01*
X145718Y-494802D01*
G01X185398Y-477835D02*
Y-485835D01*
X189398D01*
G01X197198D02*
Y-480502D01*
G01Y-481435D02*
X196798Y-480902D01*
X196198Y-480635D01*
X195498Y-480502D01*
X194798Y-480768D01*
X194198Y-481302D01*
X193798Y-482102D01*
X193598Y-483168D01*
X193798Y-484235D01*
X194198Y-485035D01*
X194798Y-485568D01*
X195498Y-485835D01*
X196198Y-485702D01*
X196798Y-485302D01*
X197198Y-484769D01*
G01X201298Y-488235D02*
X201898Y-488502D01*
X202698Y-488235D01*
X203198Y-487702D01*
X203598Y-487035D01*
X204198Y-484902D01*
X205498Y-480502D01*
G01X202298D02*
X204198Y-484902D01*
G01X209898Y-482235D02*
X213098D01*
X212798Y-481302D01*
X212298Y-480768D01*
X211598Y-480502D01*
X210898Y-480635D01*
X210298Y-481035D01*
X209898Y-481968D01*
X209698Y-482769D01*
Y-483568D01*
X209898Y-484368D01*
X210398Y-485168D01*
X210998Y-485702D01*
X211698Y-485835D01*
X212398Y-485568D01*
X213098Y-484769D01*
G01X217998Y-485835D02*
Y-480502D01*
G01Y-481568D02*
X218498Y-481035D01*
X218998Y-480635D01*
X219698Y-480502D01*
X220198Y-480635D01*
X220798Y-481035D01*
G01X211398Y-535835D02*
Y-532235D01*
X209398Y-527835D01*
G01X213398D02*
X211398Y-532235D01*
G01X217698Y-530502D02*
Y-534235D01*
X218098Y-535168D01*
X218698Y-535702D01*
X219398Y-535835D01*
X220098Y-535702D01*
X220698Y-535168D01*
X221098Y-534235D01*
G01Y-535835D02*
Y-530502D01*
G01X225698Y-535835D02*
Y-530502D01*
G01Y-531835D02*
X226098Y-531168D01*
X226698Y-530635D01*
X227498Y-530502D01*
X228198Y-530635D01*
X228798Y-531168D01*
X229098Y-532102D01*
Y-535835D01*
G01X237198D02*
Y-530502D01*
G01Y-531435D02*
X236798Y-530902D01*
X236198Y-530635D01*
X235498Y-530502D01*
X234798Y-530768D01*
X234198Y-531302D01*
X233798Y-532102D01*
X233598Y-533168D01*
X233798Y-534235D01*
X234198Y-535035D01*
X234798Y-535568D01*
X235498Y-535835D01*
X236198Y-535702D01*
X236798Y-535302D01*
X237198Y-534769D01*
G01X219498Y-506835D02*
X221498D01*
Y-509235D01*
X220898Y-510035D01*
X220198Y-510568D01*
X219198Y-510835D01*
X218198Y-510568D01*
X217498Y-510035D01*
X216898Y-509235D01*
X216498Y-508302D01*
X216298Y-507235D01*
Y-506302D01*
X216498Y-505502D01*
X216898Y-504568D01*
X217498Y-503768D01*
X218098Y-503235D01*
X218898Y-502835D01*
X219598D01*
X220398Y-503102D01*
X220998Y-503635D01*
G01X224598Y-510835D02*
Y-502835D01*
X229198Y-510835D01*
Y-502835D01*
G01X232698Y-510835D02*
Y-502835D01*
X234698D01*
X235498Y-503235D01*
X236098Y-503768D01*
X236598Y-504568D01*
X236998Y-505502D01*
X237098Y-506835D01*
X236998Y-508168D01*
X236598Y-509102D01*
X236098Y-509902D01*
X235498Y-510435D01*
X234698Y-510835D01*
X232698D01*
G01X240998Y-504168D02*
X241598Y-503368D01*
X242298Y-502968D01*
X243098Y-502835D01*
X244098Y-503102D01*
X244798Y-503768D01*
X244998Y-504568D01*
X244898Y-505369D01*
X244498Y-506035D01*
X242498Y-507368D01*
X241598Y-508302D01*
X240998Y-509635D01*
X240798Y-510835D01*
X244998D01*
G01X246198Y-485835D02*
X246398Y-484102D01*
X246698Y-482635D01*
X247098Y-481302D01*
X247598Y-479835D01*
X248398Y-477835D01*
X244398D01*
G01X311998Y-529168D02*
X312598Y-528368D01*
X313298Y-527968D01*
X314098Y-527835D01*
X315098Y-528102D01*
X315798Y-528768D01*
X315998Y-529568D01*
X315898Y-530369D01*
X315498Y-531035D01*
X313498Y-532368D01*
X312598Y-533302D01*
X311998Y-534635D01*
X311798Y-535835D01*
X315998D01*
G01X321898Y-527835D02*
X321098Y-528102D01*
X320498Y-528768D01*
X320098Y-529568D01*
X319798Y-530635D01*
X319698Y-531835D01*
X319798Y-533035D01*
X320098Y-534102D01*
X320498Y-534902D01*
X321098Y-535568D01*
X321898Y-535835D01*
X322698Y-535568D01*
X323298Y-534902D01*
X323698Y-534102D01*
X323998Y-533035D01*
X324098Y-531835D01*
X323998Y-530635D01*
X323698Y-529568D01*
X323298Y-528768D01*
X322698Y-528102D01*
X321898Y-527835D01*
G01X327998Y-529168D02*
X328598Y-528368D01*
X329298Y-527968D01*
X330098Y-527835D01*
X331098Y-528102D01*
X331798Y-528768D01*
X331998Y-529568D01*
X331898Y-530369D01*
X331498Y-531035D01*
X329498Y-532368D01*
X328598Y-533302D01*
X327998Y-534635D01*
X327798Y-535835D01*
X331998D01*
G01X335698Y-534235D02*
X336298Y-535168D01*
X337098Y-535702D01*
X337998Y-535835D01*
X338798Y-535702D01*
X339598Y-535035D01*
X340098Y-534235D01*
X340198Y-533435D01*
X339998Y-532502D01*
X339298Y-531835D01*
X338598Y-531568D01*
X337698D01*
G01X338598D02*
X339198Y-531168D01*
X339698Y-530502D01*
X339898Y-529702D01*
X339698Y-528902D01*
X339198Y-528235D01*
X338298Y-527835D01*
X337398Y-527968D01*
X336498Y-528502D01*
G01X344098Y-536102D02*
X347698Y-527835D01*
G01X353898D02*
X353098Y-528102D01*
X352498Y-528768D01*
X352098Y-529568D01*
X351798Y-530635D01*
X351698Y-531835D01*
X351798Y-533035D01*
X352098Y-534102D01*
X352498Y-534902D01*
X353098Y-535568D01*
X353898Y-535835D01*
X354698Y-535568D01*
X355298Y-534902D01*
X355698Y-534102D01*
X355998Y-533035D01*
X356098Y-531835D01*
X355998Y-530635D01*
X355698Y-529568D01*
X355298Y-528768D01*
X354698Y-528102D01*
X353898Y-527835D01*
G01X361898Y-535835D02*
Y-527835D01*
X360698Y-529435D01*
G01Y-535835D02*
X363098D01*
G01X368098Y-536102D02*
X371698Y-527835D01*
G01X377898D02*
X377098Y-528102D01*
X376498Y-528768D01*
X376098Y-529568D01*
X375798Y-530635D01*
X375698Y-531835D01*
X375798Y-533035D01*
X376098Y-534102D01*
X376498Y-534902D01*
X377098Y-535568D01*
X377898Y-535835D01*
X378698Y-535568D01*
X379298Y-534902D01*
X379698Y-534102D01*
X379998Y-533035D01*
X380098Y-531835D01*
X379998Y-530635D01*
X379698Y-529568D01*
X379298Y-528768D01*
X378698Y-528102D01*
X377898Y-527835D01*
G01X384198Y-534902D02*
X384898Y-535568D01*
X385698Y-535835D01*
X386498Y-535568D01*
X387198Y-534769D01*
X387698Y-533568D01*
X387898Y-532368D01*
Y-530902D01*
X387698Y-529702D01*
X387198Y-528635D01*
X386598Y-528102D01*
X385898Y-527835D01*
X385098Y-528102D01*
X384498Y-528635D01*
X384098Y-529435D01*
X383898Y-530502D01*
X384098Y-531435D01*
X384598Y-532368D01*
X385198Y-532902D01*
X385898Y-533035D01*
X386698Y-532769D01*
X387298Y-532102D01*
X387898Y-530902D01*
G01X311698Y-510835D02*
Y-502835D01*
X313698D01*
X314498Y-503235D01*
X315098Y-503768D01*
X315598Y-504568D01*
X315998Y-505502D01*
X316098Y-506835D01*
X315998Y-508168D01*
X315598Y-509102D01*
X315098Y-509902D01*
X314498Y-510435D01*
X313698Y-510835D01*
X311698D01*
G01X319398D02*
X321898Y-502835D01*
X324398Y-510835D01*
G01X323498Y-508035D02*
X320298D01*
G01X329898Y-502835D02*
X329098Y-503102D01*
X328498Y-503768D01*
X328098Y-504568D01*
X327798Y-505635D01*
X327698Y-506835D01*
X327798Y-508035D01*
X328098Y-509102D01*
X328498Y-509902D01*
X329098Y-510568D01*
X329898Y-510835D01*
X330698Y-510568D01*
X331298Y-509902D01*
X331698Y-509102D01*
X331998Y-508035D01*
X332098Y-506835D01*
X331998Y-505635D01*
X331698Y-504568D01*
X331298Y-503768D01*
X330698Y-503102D01*
X329898Y-502835D01*
G01X335998Y-510835D02*
Y-502835D01*
X339798D01*
G01X338398Y-506702D02*
X335998D01*
G01X345898Y-502835D02*
X345098Y-503102D01*
X344498Y-503768D01*
X344098Y-504568D01*
X343798Y-505635D01*
X343698Y-506835D01*
X343798Y-508035D01*
X344098Y-509102D01*
X344498Y-509902D01*
X345098Y-510568D01*
X345898Y-510835D01*
X346698Y-510568D01*
X347298Y-509902D01*
X347698Y-509102D01*
X347998Y-508035D01*
X348098Y-506835D01*
X347998Y-505635D01*
X347698Y-504568D01*
X347298Y-503768D01*
X346698Y-503102D01*
X345898Y-502835D01*
G01X353898D02*
Y-510835D01*
G01X351598Y-502835D02*
X356198D01*
G01X363898Y-510835D02*
X359898D01*
Y-502835D01*
X363898D01*
G01X362298Y-506702D02*
X359898D01*
G01X370698Y-506568D02*
X371098Y-506168D01*
X371398Y-505502D01*
X371598Y-504568D01*
X371398Y-503768D01*
X370998Y-503235D01*
X370298Y-502835D01*
X367598D01*
Y-510835D01*
X370898D01*
X371598Y-510302D01*
X371998Y-509502D01*
X372198Y-508568D01*
X371998Y-507635D01*
X371398Y-506835D01*
X370698Y-506568D01*
X367598D01*
G01X376698Y-502835D02*
X379098D01*
G01X377898D02*
Y-510835D01*
G01X376698D02*
X379098D01*
G01X383998D02*
Y-502835D01*
X387798D01*
G01X386398Y-506702D02*
X383998D01*
G01X393898Y-502835D02*
X393098Y-503102D01*
X392498Y-503768D01*
X392098Y-504568D01*
X391798Y-505635D01*
X391698Y-506835D01*
X391798Y-508035D01*
X392098Y-509102D01*
X392498Y-509902D01*
X393098Y-510568D01*
X393898Y-510835D01*
X394698Y-510568D01*
X395298Y-509902D01*
X395698Y-509102D01*
X395998Y-508035D01*
X396098Y-506835D01*
X395998Y-505635D01*
X395698Y-504568D01*
X395298Y-503768D01*
X394698Y-503102D01*
X393898Y-502835D01*
G01X329498Y-485835D02*
Y-477835D01*
X333298D01*
G01X331898Y-481702D02*
X329498D01*
G01X339398Y-477835D02*
X338598Y-478102D01*
X337998Y-478768D01*
X337598Y-479568D01*
X337298Y-480635D01*
X337198Y-481835D01*
X337298Y-483035D01*
X337598Y-484102D01*
X337998Y-484902D01*
X338598Y-485568D01*
X339398Y-485835D01*
X340198Y-485568D01*
X340798Y-484902D01*
X341198Y-484102D01*
X341498Y-483035D01*
X341598Y-481835D01*
X341498Y-480635D01*
X341198Y-479568D01*
X340798Y-478768D01*
X340198Y-478102D01*
X339398Y-477835D01*
G01X347398D02*
Y-485835D01*
G01X345098Y-477835D02*
X349698D01*
G01X352398Y-488502D02*
X358398D01*
G01X361898Y-482235D02*
X365098D01*
X364798Y-481302D01*
X364298Y-480768D01*
X363598Y-480502D01*
X362898Y-480635D01*
X362298Y-481035D01*
X361898Y-481968D01*
X361698Y-482769D01*
Y-483568D01*
X361898Y-484368D01*
X362398Y-485168D01*
X362998Y-485702D01*
X363698Y-485835D01*
X364398Y-485568D01*
X365098Y-484769D01*
G01X369898Y-480502D02*
X372898Y-485835D01*
G01Y-480502D02*
X369898Y-485835D01*
G01X377598Y-488502D02*
Y-480502D01*
G01Y-481702D02*
X378098Y-481035D01*
X378598Y-480635D01*
X379398Y-480502D01*
X380098Y-480635D01*
X380798Y-481302D01*
X381098Y-482235D01*
X381198Y-483168D01*
X381098Y-484102D01*
X380798Y-485035D01*
X380198Y-485568D01*
X379398Y-485835D01*
X378698Y-485702D01*
X377998Y-485302D01*
X377598Y-484769D01*
G01X389198Y-485835D02*
Y-480502D01*
G01Y-481435D02*
X388798Y-480902D01*
X388198Y-480635D01*
X387498Y-480502D01*
X386798Y-480768D01*
X386198Y-481302D01*
X385798Y-482102D01*
X385598Y-483168D01*
X385798Y-484235D01*
X386198Y-485035D01*
X386798Y-485568D01*
X387498Y-485835D01*
X388198Y-485702D01*
X388798Y-485302D01*
X389198Y-484769D01*
G01X393698Y-485835D02*
Y-480502D01*
G01Y-481835D02*
X394098Y-481168D01*
X394698Y-480635D01*
X395498Y-480502D01*
X396198Y-480635D01*
X396798Y-481168D01*
X397098Y-482102D01*
Y-485835D01*
G01X405198Y-477835D02*
Y-485835D01*
G01Y-484635D02*
X404798Y-485302D01*
X404198Y-485702D01*
X403498Y-485835D01*
X402698Y-485568D01*
X402098Y-484902D01*
X401698Y-484102D01*
X401598Y-483168D01*
X401698Y-482235D01*
X402098Y-481435D01*
X402698Y-480768D01*
X403498Y-480502D01*
X404198Y-480635D01*
X404698Y-480902D01*
X405198Y-481435D01*
G01X409898Y-482235D02*
X413098D01*
X412798Y-481302D01*
X412298Y-480768D01*
X411598Y-480502D01*
X410898Y-480635D01*
X410298Y-481035D01*
X409898Y-481968D01*
X409698Y-482769D01*
Y-483568D01*
X409898Y-484368D01*
X410398Y-485168D01*
X410998Y-485702D01*
X411698Y-485835D01*
X412398Y-485568D01*
X413098Y-484769D01*
G01X417998Y-485835D02*
Y-480502D01*
G01Y-481568D02*
X418498Y-481035D01*
X418998Y-480635D01*
X419698Y-480502D01*
X420198Y-480635D01*
X420798Y-481035D01*
G01X424398Y-488502D02*
X430398D01*
G01X433598Y-485835D02*
Y-477835D01*
G01Y-481835D02*
X434098Y-481035D01*
X434698Y-480635D01*
X435298Y-480502D01*
X436198Y-480768D01*
X436798Y-481302D01*
X437198Y-482235D01*
Y-483302D01*
X436998Y-484368D01*
X436598Y-485168D01*
X435898Y-485702D01*
X435298Y-485835D01*
X434698Y-485702D01*
X434098Y-485302D01*
X433598Y-484635D01*
G01X445198Y-477835D02*
Y-485835D01*
G01Y-484635D02*
X444798Y-485302D01*
X444198Y-485702D01*
X443498Y-485835D01*
X442698Y-485568D01*
X442098Y-484902D01*
X441698Y-484102D01*
X441598Y-483168D01*
X441698Y-482235D01*
X442098Y-481435D01*
X442698Y-480768D01*
X443498Y-480502D01*
X444198Y-480635D01*
X444698Y-480902D01*
X445198Y-481435D01*
G01X400398Y-538835D02*
Y-530835D01*
X399198Y-532435D01*
G01Y-538835D02*
X401598D01*
G01X406498Y-535502D02*
X407198Y-534568D01*
X407798Y-534035D01*
X408598Y-533768D01*
X409298Y-534035D01*
X409798Y-534568D01*
X410198Y-535368D01*
X410298Y-536302D01*
X410198Y-537102D01*
X409798Y-537902D01*
X409198Y-538568D01*
X408498Y-538835D01*
X407698Y-538568D01*
X406998Y-537769D01*
X406598Y-536568D01*
X406498Y-535235D01*
X406698Y-533502D01*
X406998Y-532568D01*
X407498Y-531635D01*
X408198Y-530968D01*
X408898Y-530835D01*
X409598Y-531102D01*
X410098Y-531768D01*
G01X416398Y-539102D02*
X416198Y-538968D01*
Y-538702D01*
X416398Y-538568D01*
X416598Y-538702D01*
Y-538968D01*
X416398Y-539102D01*
G01X422498Y-535502D02*
X423198Y-534568D01*
X423798Y-534035D01*
X424598Y-533768D01*
X425298Y-534035D01*
X425798Y-534568D01*
X426198Y-535368D01*
X426298Y-536302D01*
X426198Y-537102D01*
X425798Y-537902D01*
X425198Y-538568D01*
X424498Y-538835D01*
X423698Y-538568D01*
X422998Y-537769D01*
X422598Y-536568D01*
X422498Y-535235D01*
X422698Y-533502D01*
X422998Y-532568D01*
X423498Y-531635D01*
X424198Y-530968D01*
X424898Y-530835D01*
X425598Y-531102D01*
X426098Y-531768D01*
G01X445398Y-538835D02*
Y-530835D01*
X444198Y-532435D01*
G01Y-538835D02*
X446598D01*
G01X453198D02*
X453398Y-537102D01*
X453698Y-535635D01*
X454098Y-534302D01*
X454598Y-532835D01*
X455398Y-530835D01*
X451398D01*
G01X461398Y-539102D02*
X461198Y-538968D01*
Y-538702D01*
X461398Y-538568D01*
X461598Y-538702D01*
Y-538968D01*
X461398Y-539102D01*
G01X467498Y-532168D02*
X468098Y-531368D01*
X468798Y-530968D01*
X469598Y-530835D01*
X470598Y-531102D01*
X471298Y-531768D01*
X471498Y-532568D01*
X471398Y-533369D01*
X470998Y-534035D01*
X468998Y-535368D01*
X468098Y-536302D01*
X467498Y-537635D01*
X467298Y-538835D01*
X471498D01*
G01X465498Y-513835D02*
Y-505835D01*
X469298D01*
G01X467898Y-509702D02*
X465498D01*
M02*
